(kicad_pcb
	(version 20260206)
	(generator "pcbnew")
	(generator_version "10.0")
	(general
		(thickness 1.6)
		(legacy_teardrops no)
	)
	(paper "A4")
	(layers
		(0 "F.Cu" signal "TOP")
		(4 "In1.Cu" signal "GND")
		(6 "In2.Cu" signal "IN1")
		(8 "In3.Cu" signal "GND1")
		(10 "In4.Cu" signal "VCC")
		(12 "In5.Cu" signal "VCC1")
		(14 "In6.Cu" signal "GND2")
		(16 "In7.Cu" signal "IN2")
		(18 "In8.Cu" signal "GND3")
		(2 "B.Cu" signal "BOTTOM")
		(9 "F.Adhes" user "F.Adhesive")
		(11 "B.Adhes" user "B.Adhesive")
		(13 "F.Paste" user "Package Geometry/Pastemask Top")
		(15 "B.Paste" user "Package Geometry/Pastemask Bottom")
		(5 "F.SilkS" user "Ref Des/Silkscreen Top")
		(7 "B.SilkS" user "Ref Des/Silkscreen Bottom")
		(1 "F.Mask" user "Board Geometry/Soldermask Top")
		(3 "B.Mask" user "Board Geometry/Soldermask Bottom")
		(17 "Dwgs.User" user "User.Drawings")
		(19 "Cmts.User" user "User.Comments")
		(21 "Eco1.User" user "User.Eco1")
		(23 "Eco2.User" user "User.Eco2")
		(25 "Edge.Cuts" user "Board Geometry/Outline")
		(27 "Margin" user)
		(31 "F.CrtYd" user "Package Geometry/Place Bound Top")
		(29 "B.CrtYd" user "Package Geometry/Place Bound Bottom")
		(35 "F.Fab" user "Ref Des/Assembly Top")
		(33 "B.Fab" user "Ref Des/Assembly Bottom")
	)
	(setup
		(pad_to_mask_clearance 0)
		(allow_soldermask_bridges_in_footprints no)
		(tenting
			(front yes)
			(back yes)
		)
		(covering
			(front no)
			(back no)
		)
		(plugging
			(front no)
			(back no)
		)
		(capping no)
		(filling no)
		(pcbplotparams
			(layerselection 0x00000000_00000000_55555555_5755f5ff)
			(plot_on_all_layers_selection 0x00000000_00000000_00000000_00000000)
			(disableapertmacros no)
			(usegerberextensions no)
			(usegerberattributes yes)
			(usegerberadvancedattributes yes)
			(creategerberjobfile yes)
			(dashed_line_dash_ratio 12)
			(dashed_line_gap_ratio 3)
			(svgprecision 4)
			(plotframeref no)
			(mode 1)
			(useauxorigin no)
			(pdf_front_fp_property_popups yes)
			(pdf_back_fp_property_popups yes)
			(pdf_metadata yes)
			(pdf_single_document no)
			(dxfpolygonmode yes)
			(dxfimperialunits yes)
			(dxfusepcbnewfont yes)
			(psnegative no)
			(psa4output no)
			(plot_black_and_white yes)
			(sketchpadsonfab no)
			(plotpadnumbers no)
			(hidednponfab no)
			(sketchdnponfab yes)
			(crossoutdnponfab yes)
			(subtractmaskfromsilk no)
			(outputformat 1)
			(mirror no)
			(drillshape 1)
			(scaleselection 1)
			(outputdirectory "")
		)
	)
	(footprint ""
		(layer "F.Cu")
		(at 122.047 -136.906 90)
		(property "Reference" "PC17"
			(at 6.19633 1.016 0)
			(unlocked yes)
			(layer "F.SilkS")
			(effects
				(font
					(size 0.7874 0.5842)
					(thickness 0.1524)
				)
				(justify left)
			)
		)
		(property "Value" ""
			(at 0 0 90)
			(layer "F.Fab")
			(effects
				(font
					(size 1.27 1.27)
				)
			)
		)
		(duplicate_pad_numbers_are_jumpers no)
		(fp_line
			(start 5.2578 2.499868)
			(end -5.2578 2.499868)
			(stroke
				(width 0.1524)
				(type default)
			)
			(layer "F.SilkS")
		)
		(fp_circle
			(center 0 2.500122)
			(end 0 7.758176)
			(stroke
				(width 0.1524)
				(type default)
			)
			(fill no)
			(layer "F.SilkS")
		)
		(fp_poly
			(pts
				(arc
					(start 5.2578 2.499868)
					(mid 0 7.757922)
					(end -5.2578 2.499868)
				)
			)
			(stroke
				(width 0)
				(type default)
			)
			(fill yes)
			(layer "F.SilkS")
		)
		(fp_circle
			(center 0 2.500122)
			(end 0 7.758176)
			(stroke
				(width 0.1)
				(type default)
			)
			(fill no)
			(layer "F.Fab")
		)
		(pad "1" thru_hole rect
			(at 0 0)
			(size 1.5748 1.5748)
			(drill 1.0668)
			(layers "*.Cu" "*.Mask")
			(remove_unused_layers no)
			(net "P52V_HS_FILTER")
			(clearance 0)
			(padstack
				(mode front_inner_back)
				(layer "Inner"
					(shape circle)
					(size 1.5748 1.5748)
					(clearance 0)
				)
				(layer "B.Cu"
					(shape rect)
					(size 1.5748 1.5748)
					(clearance 0)
				)
			)
		)
		(pad "2" thru_hole circle
			(at 0 4.99999)
			(size 1.5748 1.5748)
			(drill 1.0668)
			(layers "*.Cu" "*.Mask")
			(remove_unused_layers no)
			(net "GND")
			(clearance 0)
		)
	)
	(footprint ""
		(layer "F.Cu")
		(at 219.434918 -113.24717 90)
		(property "Reference" "L1"
			(at -7.703566 5.312918 0)
			(unlocked yes)
			(layer "F.SilkS")
			(effects
				(font
					(size 0.7874 0.5842)
					(thickness 0.1524)
				)
				(justify left)
			)
		)
		(property "Value" ""
			(at 0 0 90)
			(layer "F.Fab")
			(effects
				(font
					(size 1.27 1.27)
				)
			)
		)
		(duplicate_pad_numbers_are_jumpers no)
		(fp_line
			(start 6.849872 -6.450076)
			(end -6.849872 -6.450076)
			(stroke
				(width 0.1524)
				(type default)
			)
			(layer "F.SilkS")
		)
		(fp_line
			(start -6.849872 -6.450076)
			(end -6.849872 -2.6416)
			(stroke
				(width 0.1524)
				(type default)
			)
			(layer "F.SilkS")
		)
		(fp_line
			(start 6.849872 -2.6416)
			(end 6.849872 -6.450076)
			(stroke
				(width 0.1524)
				(type default)
			)
			(layer "F.SilkS")
		)
		(fp_line
			(start -6.849872 2.6416)
			(end -6.849872 6.450076)
			(stroke
				(width 0.1524)
				(type default)
			)
			(layer "F.SilkS")
		)
		(fp_line
			(start 6.849872 6.450076)
			(end 6.849872 2.6416)
			(stroke
				(width 0.1524)
				(type default)
			)
			(layer "F.SilkS")
		)
		(fp_line
			(start -6.849872 6.450076)
			(end 6.849872 6.450076)
			(stroke
				(width 0.1524)
				(type default)
			)
			(layer "F.SilkS")
		)
		(fp_line
			(start 6.849872 -6.450076)
			(end -6.849872 -6.450076)
			(stroke
				(width 0.1)
				(type default)
			)
			(layer "F.Fab")
		)
		(fp_line
			(start -6.849872 -6.450076)
			(end -6.849872 6.450076)
			(stroke
				(width 0.1)
				(type default)
			)
			(layer "F.Fab")
		)
		(fp_line
			(start 6.849872 6.450076)
			(end 6.849872 -6.450076)
			(stroke
				(width 0.1)
				(type default)
			)
			(layer "F.Fab")
		)
		(fp_line
			(start -6.849872 6.450076)
			(end 6.849872 6.450076)
			(stroke
				(width 0.1)
				(type default)
			)
			(layer "F.Fab")
		)
		(pad "1" smd rect
			(at -5.407406 0 90)
			(size 2.9464 5.0038)
			(layers "F.Cu" "F.Mask" "F.Paste")
			(net "P52V_HS")
		)
		(pad "2" smd rect
			(at 5.407406 0 90)
			(size 2.9464 5.0038)
			(layers "F.Cu" "F.Mask" "F.Paste")
			(net "P52V_HS_FILTER")
		)
	)
	(footprint ""
		(layer "F.Cu")
		(at 287.4518 -35.168078)
		(property "Reference" "PR6932"
			(at 0 0 0)
			(layer "F.SilkS")
			(hide yes)
			(effects
				(font
					(size 1.27 1.27)
				)
			)
		)
		(property "Value" ""
			(at 0 0 0)
			(layer "F.Fab")
			(effects
				(font
					(size 1.27 1.27)
				)
			)
		)
		(duplicate_pad_numbers_are_jumpers no)
		(fp_line
			(start -0.7874 -0.4064)
			(end 0.7874 -0.4064)
			(stroke
				(width 0.1524)
				(type default)
			)
			(layer "F.SilkS")
		)
		(fp_line
			(start -0.7874 0.4064)
			(end -0.7874 -0.4064)
			(stroke
				(width 0.1524)
				(type default)
			)
			(layer "F.SilkS")
		)
		(fp_line
			(start 0.7874 -0.4064)
			(end 0.7874 0.4064)
			(stroke
				(width 0.1524)
				(type default)
			)
			(layer "F.SilkS")
		)
		(fp_line
			(start 0.7874 0.4064)
			(end -0.7874 0.4064)
			(stroke
				(width 0.1524)
				(type default)
			)
			(layer "F.SilkS")
		)
		(fp_line
			(start -0.67945 -0.305054)
			(end -0.12065 -0.305054)
			(stroke
				(width 0.1)
				(type default)
			)
			(layer "F.Fab")
		)
		(fp_line
			(start -0.67945 0.3048)
			(end -0.67945 -0.305054)
			(stroke
				(width 0.1)
				(type default)
			)
			(layer "F.Fab")
		)
		(fp_line
			(start -0.12065 -0.305054)
			(end -0.12065 -0.2794)
			(stroke
				(width 0.1)
				(type default)
			)
			(layer "F.Fab")
		)
		(fp_line
			(start -0.12065 -0.2794)
			(end 0.12065 -0.2794)
			(stroke
				(width 0.1)
				(type default)
			)
			(layer "F.Fab")
		)
		(fp_line
			(start -0.12065 0.2794)
			(end -0.12065 0.3048)
			(stroke
				(width 0.1)
				(type default)
			)
			(layer "F.Fab")
		)
		(fp_line
			(start -0.12065 0.3048)
			(end -0.67945 0.3048)
			(stroke
				(width 0.1)
				(type default)
			)
			(layer "F.Fab")
		)
		(fp_line
			(start 0.120396 0.2794)
			(end -0.12065 0.2794)
			(stroke
				(width 0.1)
				(type default)
			)
			(layer "F.Fab")
		)
		(fp_line
			(start 0.120396 0.3048)
			(end 0.120396 0.2794)
			(stroke
				(width 0.1)
				(type default)
			)
			(layer "F.Fab")
		)
		(fp_line
			(start 0.12065 -0.3048)
			(end 0.67945 -0.3048)
			(stroke
				(width 0.1)
				(type default)
			)
			(layer "F.Fab")
		)
		(fp_line
			(start 0.12065 -0.2794)
			(end 0.12065 -0.3048)
			(stroke
				(width 0.1)
				(type default)
			)
			(layer "F.Fab")
		)
		(fp_line
			(start 0.67945 -0.3048)
			(end 0.67945 0.3048)
			(stroke
				(width 0.1)
				(type default)
			)
			(layer "F.Fab")
		)
		(fp_line
			(start 0.67945 0.3048)
			(end 0.120396 0.3048)
			(stroke
				(width 0.1)
				(type default)
			)
			(layer "F.Fab")
		)
		(pad "1" smd circle
			(at -0.40005 0)
			(size 0 0)
			(layers "F.Cu" "F.Mask" "F.Paste")
			(net "P52V_HS1_PWRGIN")
		)
		(pad "2" smd circle
			(at 0.40005 0)
			(size 0 0)
			(layers "F.Cu" "F.Mask" "F.Paste")
			(net "GND_FIELD_SIGNAL")
		)
	)
	(footprint ""
		(layer "F.Cu")
		(at 30.000194 -11.999976 -90)
		(property "Reference" "H16"
			(at 6.692646 12.982194 0)
			(unlocked yes)
			(layer "F.SilkS")
			(effects
				(font
					(size 0.7874 0.5842)
					(thickness 0.1524)
				)
				(justify left)
			)
		)
		(property "Value" ""
			(at 0 0 270)
			(layer "F.Fab")
			(effects
				(font
					(size 1.27 1.27)
				)
			)
		)
		(duplicate_pad_numbers_are_jumpers no)
		(pad "1" thru_hole oval
			(at 0 0 270)
			(size 10.0076 32.004)
			(drill 3.0226
				(offset 0 10.999978)
			)
			(layers "*.Cu" "*.Mask")
			(remove_unused_layers no)
			(net "GND")
			(clearance -1.995678)
			(padstack
				(mode front_inner_back)
				(layer "Inner"
					(shape circle)
					(size 0 0)
					(clearance 0)
				)
				(layer "B.Cu"
					(shape oval)
					(size 10.0076 32.004)
					(offset 0 10.999978)
					(clearance -1.995678)
				)
			)
		)
	)
	(footprint ""
		(layer "F.Cu")
		(at 40.781478 -62.27064)
		(property "Reference" "R5894"
			(at 0 0 0)
			(layer "F.SilkS")
			(hide yes)
			(effects
				(font
					(size 1.27 1.27)
				)
			)
		)
		(property "Value" ""
			(at 0 0 0)
			(layer "F.Fab")
			(effects
				(font
					(size 1.27 1.27)
				)
			)
		)
		(duplicate_pad_numbers_are_jumpers no)
		(fp_line
			(start -0.7874 -0.4064)
			(end 0.7874 -0.4064)
			(stroke
				(width 0.1524)
				(type default)
			)
			(layer "F.SilkS")
		)
		(fp_line
			(start -0.7874 0.4064)
			(end -0.7874 -0.4064)
			(stroke
				(width 0.1524)
				(type default)
			)
			(layer "F.SilkS")
		)
		(fp_line
			(start 0.7874 -0.4064)
			(end 0.7874 0.4064)
			(stroke
				(width 0.1524)
				(type default)
			)
			(layer "F.SilkS")
		)
		(fp_line
			(start 0.7874 0.4064)
			(end -0.7874 0.4064)
			(stroke
				(width 0.1524)
				(type default)
			)
			(layer "F.SilkS")
		)
		(fp_line
			(start -0.67945 -0.305054)
			(end -0.12065 -0.305054)
			(stroke
				(width 0.1)
				(type default)
			)
			(layer "F.Fab")
		)
		(fp_line
			(start -0.67945 0.3048)
			(end -0.67945 -0.305054)
			(stroke
				(width 0.1)
				(type default)
			)
			(layer "F.Fab")
		)
		(fp_line
			(start -0.12065 -0.305054)
			(end -0.12065 -0.2794)
			(stroke
				(width 0.1)
				(type default)
			)
			(layer "F.Fab")
		)
		(fp_line
			(start -0.12065 -0.2794)
			(end 0.12065 -0.2794)
			(stroke
				(width 0.1)
				(type default)
			)
			(layer "F.Fab")
		)
		(fp_line
			(start -0.12065 0.2794)
			(end -0.12065 0.3048)
			(stroke
				(width 0.1)
				(type default)
			)
			(layer "F.Fab")
		)
		(fp_line
			(start -0.12065 0.3048)
			(end -0.67945 0.3048)
			(stroke
				(width 0.1)
				(type default)
			)
			(layer "F.Fab")
		)
		(fp_line
			(start 0.120396 0.2794)
			(end -0.12065 0.2794)
			(stroke
				(width 0.1)
				(type default)
			)
			(layer "F.Fab")
		)
		(fp_line
			(start 0.120396 0.3048)
			(end 0.120396 0.2794)
			(stroke
				(width 0.1)
				(type default)
			)
			(layer "F.Fab")
		)
		(fp_line
			(start 0.12065 -0.3048)
			(end 0.67945 -0.3048)
			(stroke
				(width 0.1)
				(type default)
			)
			(layer "F.Fab")
		)
		(fp_line
			(start 0.12065 -0.2794)
			(end 0.12065 -0.3048)
			(stroke
				(width 0.1)
				(type default)
			)
			(layer "F.Fab")
		)
		(fp_line
			(start 0.67945 -0.3048)
			(end 0.67945 0.3048)
			(stroke
				(width 0.1)
				(type default)
			)
			(layer "F.Fab")
		)
		(fp_line
			(start 0.67945 0.3048)
			(end 0.120396 0.3048)
			(stroke
				(width 0.1)
				(type default)
			)
			(layer "F.Fab")
		)
		(pad "1" smd rect
			(at -0.40005 0 180)
			(size 0.4572 0.508)
			(layers "F.Cu" "F.Mask" "F.Paste")
			(net "P12V_BRICK")
		)
		(pad "2" smd rect
			(at 0.40005 0 180)
			(size 0.4572 0.508)
			(layers "F.Cu" "F.Mask" "F.Paste")
			(net "P12V_HPDB_0_FB")
		)
	)
	(footprint ""
		(layer "F.Cu")
		(at 281.559 -35.687 90)
		(property "Reference" "R150"
			(at 0 0 90)
			(layer "F.SilkS")
			(hide yes)
			(effects
				(font
					(size 1.27 1.27)
				)
			)
		)
		(property "Value" ""
			(at 0 0 90)
			(layer "F.Fab")
			(effects
				(font
					(size 1.27 1.27)
				)
			)
		)
		(duplicate_pad_numbers_are_jumpers no)
		(fp_line
			(start 0.7874 -0.4064)
			(end 0.7874 0.4064)
			(stroke
				(width 0.1524)
				(type default)
			)
			(layer "F.SilkS")
		)
		(fp_line
			(start -0.7874 -0.4064)
			(end 0.7874 -0.4064)
			(stroke
				(width 0.1524)
				(type default)
			)
			(layer "F.SilkS")
		)
		(fp_line
			(start 0.7874 0.4064)
			(end -0.7874 0.4064)
			(stroke
				(width 0.1524)
				(type default)
			)
			(layer "F.SilkS")
		)
		(fp_line
			(start -0.7874 0.4064)
			(end -0.7874 -0.4064)
			(stroke
				(width 0.1524)
				(type default)
			)
			(layer "F.SilkS")
		)
		(fp_line
			(start -0.12065 -0.305054)
			(end -0.12065 -0.2794)
			(stroke
				(width 0.1)
				(type default)
			)
			(layer "F.Fab")
		)
		(fp_line
			(start -0.67945 -0.305054)
			(end -0.12065 -0.305054)
			(stroke
				(width 0.1)
				(type default)
			)
			(layer "F.Fab")
		)
		(fp_line
			(start 0.67945 -0.3048)
			(end 0.67945 0.3048)
			(stroke
				(width 0.1)
				(type default)
			)
			(layer "F.Fab")
		)
		(fp_line
			(start 0.12065 -0.3048)
			(end 0.67945 -0.3048)
			(stroke
				(width 0.1)
				(type default)
			)
			(layer "F.Fab")
		)
		(fp_line
			(start 0.12065 -0.2794)
			(end 0.12065 -0.3048)
			(stroke
				(width 0.1)
				(type default)
			)
			(layer "F.Fab")
		)
		(fp_line
			(start -0.12065 -0.2794)
			(end 0.12065 -0.2794)
			(stroke
				(width 0.1)
				(type default)
			)
			(layer "F.Fab")
		)
		(fp_line
			(start 0.120396 0.2794)
			(end -0.12065 0.2794)
			(stroke
				(width 0.1)
				(type default)
			)
			(layer "F.Fab")
		)
		(fp_line
			(start -0.12065 0.2794)
			(end -0.12065 0.3048)
			(stroke
				(width 0.1)
				(type default)
			)
			(layer "F.Fab")
		)
		(fp_line
			(start 0.67945 0.3048)
			(end 0.120396 0.3048)
			(stroke
				(width 0.1)
				(type default)
			)
			(layer "F.Fab")
		)
		(fp_line
			(start 0.120396 0.3048)
			(end 0.120396 0.2794)
			(stroke
				(width 0.1)
				(type default)
			)
			(layer "F.Fab")
		)
		(fp_line
			(start -0.12065 0.3048)
			(end -0.67945 0.3048)
			(stroke
				(width 0.1)
				(type default)
			)
			(layer "F.Fab")
		)
		(fp_line
			(start -0.67945 0.3048)
			(end -0.67945 -0.305054)
			(stroke
				(width 0.1)
				(type default)
			)
			(layer "F.Fab")
		)
		(pad "1" smd circle
			(at -0.40005 0 90)
			(size 0 0)
			(layers "F.Cu" "F.Mask" "F.Paste")
			(net "P3V3_AUX")
		)
		(pad "2" smd circle
			(at 0.40005 0 90)
			(size 0 0)
			(layers "F.Cu" "F.Mask" "F.Paste")
			(net "P52V_HS1_GPO2")
		)
	)
	(footprint ""
		(layer "F.Cu")
		(at 90.043 -49.911)
		(property "Reference" "PC89"
			(at 0 0 0)
			(layer "F.SilkS")
			(hide yes)
			(effects
				(font
					(size 1.27 1.27)
				)
			)
		)
		(property "Value" ""
			(at 0 0 0)
			(layer "F.Fab")
			(effects
				(font
					(size 1.27 1.27)
				)
			)
		)
		(duplicate_pad_numbers_are_jumpers no)
		(fp_line
			(start -1.524 -0.762)
			(end 1.524 -0.762)
			(stroke
				(width 0.1524)
				(type default)
			)
			(layer "F.SilkS")
		)
		(fp_line
			(start -1.524 0.762)
			(end -1.524 -0.762)
			(stroke
				(width 0.1524)
				(type default)
			)
			(layer "F.SilkS")
		)
		(fp_line
			(start 1.524 -0.762)
			(end 1.524 0.762)
			(stroke
				(width 0.1524)
				(type default)
			)
			(layer "F.SilkS")
		)
		(fp_line
			(start 1.524 0.762)
			(end -1.524 0.762)
			(stroke
				(width 0.1524)
				(type default)
			)
			(layer "F.SilkS")
		)
		(fp_line
			(start -1.1049 -0.724916)
			(end -1.1049 0.724916)
			(stroke
				(width 0.1)
				(type default)
			)
			(layer "F.Fab")
		)
		(fp_line
			(start -1.1049 0.724916)
			(end 1.1049 0.724916)
			(stroke
				(width 0.1)
				(type default)
			)
			(layer "F.Fab")
		)
		(fp_line
			(start 1.1049 -0.724916)
			(end -1.1049 -0.724916)
			(stroke
				(width 0.1)
				(type default)
			)
			(layer "F.Fab")
		)
		(fp_line
			(start 1.1049 0.724916)
			(end 1.1049 -0.724916)
			(stroke
				(width 0.1)
				(type default)
			)
			(layer "F.Fab")
		)
		(pad "1" smd rect
			(at -0.889 0 180)
			(size 1.016 1.27)
			(layers "F.Cu" "F.Mask" "F.Paste")
			(net "P12V_BRICK")
		)
		(pad "2" smd rect
			(at 0.889 0 180)
			(size 1.016 1.27)
			(layers "F.Cu" "F.Mask" "F.Paste")
			(net "GND")
		)
	)
	(footprint ""
		(layer "F.Cu")
		(at 96.8502 -22.225)
		(property "Reference" "ME1"
			(at 0 0 0)
			(layer "F.SilkS")
			(hide yes)
			(effects
				(font
					(size 1.27 1.27)
				)
			)
		)
		(property "Value" ""
			(at 0 0 0)
			(layer "F.Fab")
			(effects
				(font
					(size 1.27 1.27)
				)
			)
		)
		(duplicate_pad_numbers_are_jumpers no)
		(fp_line
			(start -3.1369 2.5527)
			(end -3.1115 2.5019)
			(stroke
				(width 0.1524)
				(type default)
			)
			(layer "F.SilkS")
		)
		(fp_line
			(start -3.1369 3.0861)
			(end -2.8321 3.0861)
			(stroke
				(width 0.1524)
				(type default)
			)
			(layer "F.SilkS")
		)
		(fp_line
			(start -3.1242 2.9972)
			(end -3.1369 3.0861)
			(stroke
				(width 0.1524)
				(type default)
			)
			(layer "F.SilkS")
		)
		(fp_line
			(start -3.1115 2.5019)
			(end -3.0861 2.4765)
			(stroke
				(width 0.1524)
				(type default)
			)
			(layer "F.SilkS")
		)
		(fp_line
			(start -3.0988 2.921)
			(end -3.1242 2.9972)
			(stroke
				(width 0.1524)
				(type default)
			)
			(layer "F.SilkS")
		)
		(fp_line
			(start -3.0861 2.4765)
			(end -3.048 2.4511)
			(stroke
				(width 0.1524)
				(type default)
			)
			(layer "F.SilkS")
		)
		(fp_line
			(start -3.0734 2.8829)
			(end -3.0988 2.921)
			(stroke
				(width 0.1524)
				(type default)
			)
			(layer "F.SilkS")
		)
		(fp_line
			(start -3.048 2.4511)
			(end -2.9972 2.4384)
			(stroke
				(width 0.1524)
				(type default)
			)
			(layer "F.SilkS")
		)
		(fp_line
			(start -3.048 2.8575)
			(end -3.0734 2.8829)
			(stroke
				(width 0.1524)
				(type default)
			)
			(layer "F.SilkS")
		)
		(fp_line
			(start -3.0099 2.8067)
			(end -3.048 2.8575)
			(stroke
				(width 0.1524)
				(type default)
			)
			(layer "F.SilkS")
		)
		(fp_line
			(start -2.9972 2.4384)
			(end -2.9337 2.4511)
			(stroke
				(width 0.1524)
				(type default)
			)
			(layer "F.SilkS")
		)
		(fp_line
			(start -2.9591 2.7686)
			(end -3.0099 2.8067)
			(stroke
				(width 0.1524)
				(type default)
			)
			(layer "F.SilkS")
		)
		(fp_line
			(start -2.9337 2.4511)
			(end -2.8702 2.5146)
			(stroke
				(width 0.1524)
				(type default)
			)
			(layer "F.SilkS")
		)
		(fp_line
			(start -2.921 2.7432)
			(end -2.9591 2.7686)
			(stroke
				(width 0.1524)
				(type default)
			)
			(layer "F.SilkS")
		)
		(fp_line
			(start -2.8956 2.7178)
			(end -2.921 2.7432)
			(stroke
				(width 0.1524)
				(type default)
			)
			(layer "F.SilkS")
		)
		(fp_line
			(start -2.8702 2.5146)
			(end -2.8575 2.5527)
			(stroke
				(width 0.1524)
				(type default)
			)
			(layer "F.SilkS")
		)
		(fp_line
			(start -2.8702 2.6797)
			(end -2.8956 2.7178)
			(stroke
				(width 0.1524)
				(type default)
			)
			(layer "F.SilkS")
		)
		(fp_line
			(start -2.8575 2.5527)
			(end -2.8575 2.6416)
			(stroke
				(width 0.1524)
				(type default)
			)
			(layer "F.SilkS")
		)
		(fp_line
			(start -2.8575 2.6416)
			(end -2.8702 2.6797)
			(stroke
				(width 0.1524)
				(type default)
			)
			(layer "F.SilkS")
		)
		(fp_line
			(start -2.5908 2.6543)
			(end -2.5908 3.0861)
			(stroke
				(width 0.1524)
				(type default)
			)
			(layer "F.SilkS")
		)
		(fp_line
			(start -2.5908 2.7813)
			(end -2.5654 2.7305)
			(stroke
				(width 0.1524)
				(type default)
			)
			(layer "F.SilkS")
		)
		(fp_line
			(start -2.5654 2.7305)
			(end -2.54 2.6924)
			(stroke
				(width 0.1524)
				(type default)
			)
			(layer "F.SilkS")
		)
		(fp_line
			(start -2.54 2.6924)
			(end -2.5146 2.667)
			(stroke
				(width 0.1524)
				(type default)
			)
			(layer "F.SilkS")
		)
		(fp_line
			(start -2.5146 2.667)
			(end -2.4638 2.6543)
			(stroke
				(width 0.1524)
				(type default)
			)
			(layer "F.SilkS")
		)
		(fp_line
			(start -2.4638 2.6543)
			(end -2.4257 2.6543)
			(stroke
				(width 0.1524)
				(type default)
			)
			(layer "F.SilkS")
		)
		(fp_line
			(start -2.4257 2.6543)
			(end -2.3749 2.667)
			(stroke
				(width 0.1524)
				(type default)
			)
			(layer "F.SilkS")
		)
		(fp_line
			(start -2.3749 2.667)
			(end -2.3368 2.7178)
			(stroke
				(width 0.1524)
				(type default)
			)
			(layer "F.SilkS")
		)
		(fp_line
			(start -2.3368 2.7178)
			(end -2.3114 2.7686)
			(stroke
				(width 0.1524)
				(type default)
			)
			(layer "F.SilkS")
		)
		(fp_line
			(start -2.3114 2.7686)
			(end -2.3114 3.0861)
			(stroke
				(width 0.1524)
				(type default)
			)
			(layer "F.SilkS")
		)
		(fp_line
			(start -2.0701 2.8575)
			(end -2.0701 2.9083)
			(stroke
				(width 0.1524)
				(type default)
			)
			(layer "F.SilkS")
		)
		(fp_line
			(start -2.0701 2.9083)
			(end -2.0574 2.9718)
			(stroke
				(width 0.1524)
				(type default)
			)
			(layer "F.SilkS")
		)
		(fp_line
			(start -2.0574 2.8194)
			(end -2.0701 2.8575)
			(stroke
				(width 0.1524)
				(type default)
			)
			(layer "F.SilkS")
		)
		(fp_line
			(start -2.0574 2.9718)
			(end -2.032 3.0099)
			(stroke
				(width 0.1524)
				(type default)
			)
			(layer "F.SilkS")
		)
		(fp_line
			(start -2.0447 2.794)
			(end -2.0574 2.8194)
			(stroke
				(width 0.1524)
				(type default)
			)
			(layer "F.SilkS")
		)
		(fp_line
			(start -2.032 3.0099)
			(end -2.0066 3.0353)
			(stroke
				(width 0.1524)
				(type default)
			)
			(layer "F.SilkS")
		)
		(fp_line
			(start -2.0066 2.7559)
			(end -2.0447 2.794)
			(stroke
				(width 0.1524)
				(type default)
			)
			(layer "F.SilkS")
		)
		(fp_line
			(start -2.0066 3.0353)
			(end -1.9685 3.0607)
			(stroke
				(width 0.1524)
				(type default)
			)
			(layer "F.SilkS")
		)
		(fp_line
			(start -1.9685 2.7305)
			(end -2.0066 2.7559)
			(stroke
				(width 0.1524)
				(type default)
			)
			(layer "F.SilkS")
		)
		(fp_line
			(start -1.9685 3.0607)
			(end -1.9304 3.0734)
			(stroke
				(width 0.1524)
				(type default)
			)
			(layer "F.SilkS")
		)
		(fp_line
			(start -1.9304 3.0734)
			(end -1.8796 3.0734)
			(stroke
				(width 0.1524)
				(type default)
			)
			(layer "F.SilkS")
		)
		(fp_line
			(start -1.9177 2.7178)
			(end -1.9685 2.7305)
			(stroke
				(width 0.1524)
				(type default)
			)
			(layer "F.SilkS")
		)
		(fp_line
			(start -1.8796 3.0734)
			(end -1.8161 3.0607)
			(stroke
				(width 0.1524)
				(type default)
			)
			(layer "F.SilkS")
		)
		(fp_line
			(start -1.8542 2.7178)
			(end -1.9177 2.7178)
			(stroke
				(width 0.1524)
				(type default)
			)
			(layer "F.SilkS")
		)
		(fp_line
			(start -1.8161 2.7305)
			(end -1.8542 2.7178)
			(stroke
				(width 0.1524)
				(type default)
			)
			(layer "F.SilkS")
		)
		(fp_line
			(start -1.8161 3.0607)
			(end -1.778 3.0353)
			(stroke
				(width 0.1524)
				(type default)
			)
			(layer "F.SilkS")
		)
		(fp_line
			(start -1.778 2.7559)
			(end -1.8161 2.7305)
			(stroke
				(width 0.1524)
				(type default)
			)
			(layer "F.SilkS")
		)
		(fp_line
			(start -1.778 3.0353)
			(end -1.7526 3.0099)
			(stroke
				(width 0.1524)
				(type default)
			)
			(layer "F.SilkS")
		)
		(fp_line
			(start -1.7526 2.4384)
			(end -1.7526 3.0861)
			(stroke
				(width 0.1524)
				(type default)
			)
			(layer "F.SilkS")
		)
		(fp_line
			(start -1.7526 2.7813)
			(end -1.778 2.7559)
			(stroke
				(width 0.1524)
				(type default)
			)
			(layer "F.SilkS")
		)
		(fp_line
			(start -1.3208 -1.524)
			(end 1.4732 1.397)
			(stroke
				(width 0.1524)
				(type default)
			)
			(layer "F.SilkS")
		)
		(fp_line
			(start -1.1938 -1.27)
			(end -1.1938 1.2954)
			(stroke
				(width 0.254)
				(type default)
			)
			(layer "F.SilkS")
		)
		(fp_line
			(start -1.1938 -1.27)
			(end -0.5588 -1.27)
			(stroke
				(width 0.254)
				(type default)
			)
			(layer "F.SilkS")
		)
		(fp_line
			(start -1.1557 2.4257)
			(end -1.1557 3.0861)
			(stroke
				(width 0.1524)
				(type default)
			)
			(layer "F.SilkS")
		)
		(fp_line
			(start -1.016 4.7498)
			(end -1.016 4.826)
			(stroke
				(width 0.254)
				(type default)
			)
			(layer "F.SilkS")
		)
		(fp_line
			(start -1.016 4.7752)
			(end 0.3048 4.7752)
			(stroke
				(width 0.254)
				(type default)
			)
			(layer "F.SilkS")
		)
		(fp_line
			(start -1.016 4.826)
			(end -0.9906 4.953)
			(stroke
				(width 0.254)
				(type default)
			)
			(layer "F.SilkS")
		)
		(fp_line
			(start -0.9906 4.5974)
			(end -1.016 4.7498)
			(stroke
				(width 0.254)
				(type default)
			)
			(layer "F.SilkS")
		)
		(fp_line
			(start -0.9906 4.953)
			(end -0.9652 5.0292)
			(stroke
				(width 0.254)
				(type default)
			)
			(layer "F.SilkS")
		)
		(fp_line
			(start -0.9652 4.5212)
			(end -0.9906 4.5974)
			(stroke
				(width 0.254)
				(type default)
			)
			(layer "F.SilkS")
		)
		(fp_line
			(start -0.9652 5.0292)
			(end -0.9144 5.1308)
			(stroke
				(width 0.254)
				(type default)
			)
			(layer "F.SilkS")
		)
		(fp_line
			(start -0.9144 4.4196)
			(end -0.9652 4.5212)
			(stroke
				(width 0.254)
				(type default)
			)
			(layer "F.SilkS")
		)
		(fp_line
			(start -0.9144 5.1308)
			(end -0.8382 5.2324)
			(stroke
				(width 0.254)
				(type default)
			)
			(layer "F.SilkS")
		)
		(fp_line
			(start -0.8382 4.318)
			(end -0.9144 4.4196)
			(stroke
				(width 0.254)
				(type default)
			)
			(layer "F.SilkS")
		)
		(fp_line
			(start -0.8382 5.2324)
			(end -0.7112 5.334)
			(stroke
				(width 0.254)
				(type default)
			)
			(layer "F.SilkS")
		)
		(fp_line
			(start -0.8128 4.2926)
			(end -0.8382 4.318)
			(stroke
				(width 0.254)
				(type default)
			)
			(layer "F.SilkS")
		)
		(fp_line
			(start -0.7747 2.6543)
			(end -0.5969 3.0861)
			(stroke
				(width 0.1524)
				(type default)
			)
			(layer "F.SilkS")
		)
		(fp_line
			(start -0.7112 4.2164)
			(end -0.8128 4.2926)
			(stroke
				(width 0.254)
				(type default)
			)
			(layer "F.SilkS")
		)
		(fp_line
			(start -0.7112 5.334)
			(end -0.6096 5.3848)
			(stroke
				(width 0.254)
				(type default)
			)
			(layer "F.SilkS")
		)
		(fp_line
			(start -0.6096 4.1656)
			(end -0.7112 4.2164)
			(stroke
				(width 0.254)
				(type default)
			)
			(layer "F.SilkS")
		)
		(fp_line
			(start -0.6096 5.3848)
			(end -0.5334 5.4102)
			(stroke
				(width 0.254)
				(type default)
			)
			(layer "F.SilkS")
		)
		(fp_line
			(start -0.5969 3.0861)
			(end -0.4191 2.6543)
			(stroke
				(width 0.1524)
				(type default)
			)
			(layer "F.SilkS")
		)
		(fp_line
			(start -0.5588 0)
			(end -1.1938 0)
			(stroke
				(width 0.254)
				(type default)
			)
			(layer "F.SilkS")
		)
		(fp_line
			(start -0.5334 4.1402)
			(end -0.6096 4.1656)
			(stroke
				(width 0.254)
				(type default)
			)
			(layer "F.SilkS")
		)
		(fp_line
			(start -0.5334 5.4102)
			(end -0.381 5.4356)
			(stroke
				(width 0.254)
				(type default)
			)
			(layer "F.SilkS")
		)
		(fp_line
			(start -0.4064 4.1148)
			(end -0.5334 4.1402)
			(stroke
				(width 0.254)
				(type default)
			)
			(layer "F.SilkS")
		)
		(fp_line
			(start -0.381 5.4356)
			(end -0.3556 5.4356)
			(stroke
				(width 0.254)
				(type default)
			)
			(layer "F.SilkS")
		)
		(fp_line
			(start -0.3556 5.4356)
			(end -0.1778 5.4102)
			(stroke
				(width 0.254)
				(type default)
			)
			(layer "F.SilkS")
		)
		(fp_line
			(start -0.3048 4.1148)
			(end -0.4064 4.1148)
			(stroke
				(width 0.254)
				(type default)
			)
			(layer "F.SilkS")
		)
		(fp_line
			(start -0.1778 4.1402)
			(end -0.3048 4.1148)
			(stroke
				(width 0.254)
				(type default)
			)
			(layer "F.SilkS")
		)
		(fp_line
			(start -0.1778 5.4102)
			(end -0.1016 5.3848)
			(stroke
				(width 0.254)
				(type default)
			)
			(layer "F.SilkS")
		)
		(fp_line
			(start -0.1016 4.1656)
			(end -0.1778 4.1402)
			(stroke
				(width 0.254)
				(type default)
			)
			(layer "F.SilkS")
		)
		(fp_line
			(start -0.1016 5.3848)
			(end -0.0508 5.3594)
			(stroke
				(width 0.254)
				(type default)
			)
			(layer "F.SilkS")
		)
		(fp_line
			(start -0.0508 5.3594)
			(end 0.1016 5.2578)
			(stroke
				(width 0.254)
				(type default)
			)
			(layer "F.SilkS")
		)
		(fp_line
			(start -0.0381 2.4257)
			(end -0.0381 3.0861)
			(stroke
				(width 0.1524)
				(type default)
			)
			(layer "F.SilkS")
		)
		(fp_line
			(start 0 4.2164)
			(end -0.1016 4.1656)
			(stroke
				(width 0.254)
				(type default)
			)
			(layer "F.SilkS")
		)
		(fp_line
			(start 0.1016 5.2578)
			(end 0.2032 5.1308)
			(stroke
				(width 0.254)
				(type default)
			)
			(layer "F.SilkS")
		)
		(fp_line
			(start 0.127 4.318)
			(end 0 4.2164)
			(stroke
				(width 0.254)
				(type default)
			)
			(layer "F.SilkS")
		)
		(fp_line
			(start 0.2032 4.4196)
			(end 0.127 4.318)
			(stroke
				(width 0.254)
				(type default)
			)
			(layer "F.SilkS")
		)
		(fp_line
			(start 0.254 4.5212)
			(end 0.2032 4.4196)
			(stroke
				(width 0.254)
				(type default)
			)
			(layer "F.SilkS")
		)
		(fp_line
			(start 0.2794 4.5974)
			(end 0.254 4.5212)
			(stroke
				(width 0.254)
				(type default)
			)
			(layer "F.SilkS")
		)
		(fp_line
			(start 0.3048 4.7752)
			(end 0.2794 4.5974)
			(stroke
				(width 0.254)
				(type default)
			)
			(layer "F.SilkS")
		)
		(fp_line
			(start 0.3556 -1.27)
			(end 0.3556 1.2954)
			(stroke
				(width 0.254)
				(type default)
			)
			(layer "F.SilkS")
		)
		(fp_line
			(start 0.635 4.3434)
			(end 0.9144 4.191)
			(stroke
				(width 0.254)
				(type default)
			)
			(layer "F.SilkS")
		)
		(fp_line
			(start 0.6731 2.3495)
			(end 0.6731 2.3749)
			(stroke
				(width 0.1524)
				(type default)
			)
			(layer "F.SilkS")
		)
		(fp_line
			(start 0.6731 2.3749)
			(end 0.6985 2.4003)
			(stroke
				(width 0.1524)
				(type default)
			)
			(layer "F.SilkS")
		)
		(fp_line
			(start 0.6985 2.3241)
			(end 0.6731 2.3495)
			(stroke
				(width 0.1524)
				(type default)
			)
			(layer "F.SilkS")
		)
		(fp_line
			(start 0.6985 2.4003)
			(end 0.7239 2.3749)
			(stroke
				(width 0.1524)
				(type default)
			)
			(layer "F.SilkS")
		)
		(fp_line
			(start 0.6985 2.6416)
			(end 0.6985 3.0861)
			(stroke
				(width 0.1524)
				(type default)
			)
			(layer "F.SilkS")
		)
		(fp_line
			(start 0.7239 2.3495)
			(end 0.6985 2.3241)
			(stroke
				(width 0.1524)
				(type default)
			)
			(layer "F.SilkS")
		)
		(fp_line
			(start 0.7239 2.3749)
			(end 0.7239 2.3495)
			(stroke
				(width 0.1524)
				(type default)
			)
			(layer "F.SilkS")
		)
		(fp_line
			(start 0.9144 4.191)
			(end 0.9144 5.461)
			(stroke
				(width 0.254)
				(type default)
			)
			(layer "F.SilkS")
		)
		(fp_line
			(start 1.143 2.6543)
			(end 1.143 3.0861)
			(stroke
				(width 0.1524)
				(type default)
			)
			(layer "F.SilkS")
		)
		(fp_line
			(start 1.143 2.7813)
			(end 1.1684 2.7305)
			(stroke
				(width 0.1524)
				(type default)
			)
			(layer "F.SilkS")
		)
		(fp_line
			(start 1.1684 2.7305)
			(end 1.1938 2.6924)
			(stroke
				(width 0.1524)
				(type default)
			)
			(layer "F.SilkS")
		)
		(fp_line
			(start 1.1938 2.6924)
			(end 1.2192 2.667)
			(stroke
				(width 0.1524)
				(type default)
			)
			(layer "F.SilkS")
		)
		(fp_line
			(start 1.2192 2.667)
			(end 1.27 2.6543)
			(stroke
				(width 0.1524)
				(type default)
			)
			(layer "F.SilkS")
		)
		(fp_line
			(start 1.27 2.6543)
			(end 1.3081 2.6543)
			(stroke
				(width 0.1524)
				(type default)
			)
			(layer "F.SilkS")
		)
		(fp_line
			(start 1.3081 2.6543)
			(end 1.3589 2.667)
			(stroke
				(width 0.1524)
				(type default)
			)
			(layer "F.SilkS")
		)
		(fp_line
			(start 1.3589 2.667)
			(end 1.397 2.7178)
			(stroke
				(width 0.1524)
				(type default)
			)
			(layer "F.SilkS")
		)
		(fp_line
			(start 1.397 2.7178)
			(end 1.4224 2.7686)
			(stroke
				(width 0.1524)
				(type default)
			)
			(layer "F.SilkS")
		)
		(fp_line
			(start 1.4224 2.7686)
			(end 1.4224 3.0861)
			(stroke
				(width 0.1524)
				(type default)
			)
			(layer "F.SilkS")
		)
		(fp_line
			(start 1.7018 2.667)
			(end 1.9304 2.667)
			(stroke
				(width 0.1524)
				(type default)
			)
			(layer "F.SilkS")
		)
		(fp_line
			(start 1.8161 2.4511)
			(end 1.8161 3.0861)
			(stroke
				(width 0.1524)
				(type default)
			)
			(layer "F.SilkS")
		)
		(fp_line
			(start 1.8161 3.0861)
			(end 1.9939 3.0734)
			(stroke
				(width 0.1524)
				(type default)
			)
			(layer "F.SilkS")
		)
		(fp_line
			(start 2.1844 2.8575)
			(end 2.1844 2.8956)
			(stroke
				(width 0.1524)
				(type default)
			)
			(layer "F.SilkS")
		)
		(fp_line
			(start 2.1844 2.8956)
			(end 2.1971 2.9464)
			(stroke
				(width 0.1524)
				(type default)
			)
			(layer "F.SilkS")
		)
		(fp_line
			(start 2.1971 2.794)
			(end 2.1844 2.8575)
			(stroke
				(width 0.1524)
				(type default)
			)
			(layer "F.SilkS")
		)
		(fp_line
			(start 2.1971 2.9464)
			(end 2.2098 2.9718)
			(stroke
				(width 0.1524)
				(type default)
			)
			(layer "F.SilkS")
		)
		(fp_line
			(start 2.2098 2.7686)
			(end 2.1971 2.794)
			(stroke
				(width 0.1524)
				(type default)
			)
			(layer "F.SilkS")
		)
		(fp_line
			(start 2.2098 2.9718)
			(end 2.2352 3.0099)
			(stroke
				(width 0.1524)
				(type default)
			)
			(layer "F.SilkS")
		)
		(fp_line
			(start 2.2352 2.7305)
			(end 2.2098 2.7686)
			(stroke
				(width 0.1524)
				(type default)
			)
			(layer "F.SilkS")
		)
		(fp_line
			(start 2.2352 3.0099)
			(end 2.2606 3.0353)
			(stroke
				(width 0.1524)
				(type default)
			)
			(layer "F.SilkS")
		)
		(fp_line
			(start 2.2606 2.7051)
			(end 2.2352 2.7305)
			(stroke
				(width 0.1524)
				(type default)
			)
			(layer "F.SilkS")
		)
		(fp_line
			(start 2.2606 3.0353)
			(end 2.2987 3.0607)
			(stroke
				(width 0.1524)
				(type default)
			)
			(layer "F.SilkS")
		)
		(fp_line
			(start 2.2987 2.6797)
			(end 2.2606 2.7051)
			(stroke
				(width 0.1524)
				(type default)
			)
			(layer "F.SilkS")
		)
		(fp_line
			(start 2.2987 3.0607)
			(end 2.3241 3.0734)
			(stroke
				(width 0.1524)
				(type default)
			)
			(layer "F.SilkS")
		)
		(fp_line
			(start 2.3241 2.667)
			(end 2.2987 2.6797)
			(stroke
				(width 0.1524)
				(type default)
			)
			(layer "F.SilkS")
		)
		(fp_line
			(start 2.3241 3.0734)
			(end 2.3876 3.0861)
			(stroke
				(width 0.1524)
				(type default)
			)
			(layer "F.SilkS")
		)
		(fp_line
			(start 2.3749 2.6543)
			(end 2.3241 2.667)
			(stroke
				(width 0.1524)
				(type default)
			)
			(layer "F.SilkS")
		)
		(fp_line
			(start 2.3876 3.0861)
			(end 2.4384 3.0861)
			(stroke
				(width 0.1524)
				(type default)
			)
			(layer "F.SilkS")
		)
		(fp_line
			(start 2.413 2.6543)
			(end 2.3749 2.6543)
			(stroke
				(width 0.1524)
				(type default)
			)
			(layer "F.SilkS")
		)
		(fp_line
			(start 2.4384 3.0861)
			(end 2.5019 3.0607)
			(stroke
				(width 0.1524)
				(type default)
			)
			(layer "F.SilkS")
		)
		(fp_line
			(start 2.4638 2.667)
			(end 2.413 2.6543)
			(stroke
				(width 0.1524)
				(type default)
			)
			(layer "F.SilkS")
		)
		(fp_line
			(start 2.5019 2.6797)
			(end 2.4638 2.667)
			(stroke
				(width 0.1524)
				(type default)
			)
			(layer "F.SilkS")
		)
		(fp_line
			(start 2.8194 2.667)
			(end 3.048 2.667)
			(stroke
				(width 0.1524)
				(type default)
			)
			(layer "F.SilkS")
		)
		(fp_line
			(start 2.9337 2.4511)
			(end 2.9337 3.0861)
			(stroke
				(width 0.1524)
				(type default)
			)
			(layer "F.SilkS")
		)
		(fp_line
			(start 2.9337 3.0861)
			(end 3.1115 3.0734)
			(stroke
				(width 0.1524)
				(type default)
			)
			(layer "F.SilkS")
		)
		(fp_arc
			(start -1.5748 4.826)
			(mid -0.985652 3.828319)
			(end 0.127 3.5052)
			(stroke
				(width 0.1524)
				(type default)
			)
			(layer "F.SilkS")
		)
		(fp_arc
			(start -0.5588 -1.27)
			(mid 0.0762 -0.635)
			(end -0.5588 0)
			(stroke
				(width 0.254)
				(type default)
			)
			(layer "F.SilkS")
		)
		(fp_arc
			(start -0.127 3.5052)
			(mid 0.985653 3.828369)
			(end 1.5748 4.826)
			(stroke
				(width 0.1524)
				(type default)
			)
			(layer "F.SilkS")
		)
		(fp_arc
			(start 0.1524 6.096)
			(mid -0.964559 5.805562)
			(end -1.5748 4.826)
			(stroke
				(width 0.1524)
				(type default)
			)
			(layer "F.SilkS")
		)
		(fp_arc
			(start 1.5748 4.826)
			(mid 0.964538 5.805581)
			(end -0.1524 6.096)
			(stroke
				(width 0.1524)
				(type default)
			)
			(layer "F.SilkS")
		)
		(fp_circle
			(center -1.8923 2.8956)
			(end -1.71196 2.8956)
			(stroke
				(width 0.1524)
				(type default)
			)
			(fill no)
			(layer "F.SilkS")
		)
		(fp_circle
			(center 0 0)
			(end 2.03454 0)
			(stroke
				(width 0.1524)
				(type default)
			)
			(fill no)
			(layer "F.SilkS")
		)
		(fp_circle
			(center 0.9652 0.6858)
			(end 1.57734 0.6858)
			(stroke
				(width 0.254)
				(type default)
			)
			(fill no)
			(layer "F.SilkS")
		)
	)
	(footprint ""
		(layer "F.Cu")
		(at 124.714 -130.175)
		(property "Reference" "PC22"
			(at 0 0 0)
			(layer "F.SilkS")
			(hide yes)
			(effects
				(font
					(size 1.27 1.27)
				)
			)
		)
		(property "Value" ""
			(at 0 0 0)
			(layer "F.Fab")
			(effects
				(font
					(size 1.27 1.27)
				)
			)
		)
		(duplicate_pad_numbers_are_jumpers no)
		(fp_line
			(start -2.2098 -0.9398)
			(end 2.2098 -0.9398)
			(stroke
				(width 0.1524)
				(type default)
			)
			(layer "F.SilkS")
		)
		(fp_line
			(start -2.2098 0.9398)
			(end -2.2098 -0.9398)
			(stroke
				(width 0.1524)
				(type default)
			)
			(layer "F.SilkS")
		)
		(fp_line
			(start 2.2098 -0.9398)
			(end 2.2098 0.9398)
			(stroke
				(width 0.1524)
				(type default)
			)
			(layer "F.SilkS")
		)
		(fp_line
			(start 2.2098 0.9398)
			(end -2.2098 0.9398)
			(stroke
				(width 0.1524)
				(type default)
			)
			(layer "F.SilkS")
		)
		(fp_line
			(start -1.700022 -0.899922)
			(end 1.700022 -0.899922)
			(stroke
				(width 0.1)
				(type default)
			)
			(layer "F.Fab")
		)
		(fp_line
			(start -1.700022 0.899922)
			(end -1.700022 -0.899922)
			(stroke
				(width 0.1)
				(type default)
			)
			(layer "F.Fab")
		)
		(fp_line
			(start 1.700022 -0.899922)
			(end 1.700022 0.899922)
			(stroke
				(width 0.1)
				(type default)
			)
			(layer "F.Fab")
		)
		(fp_line
			(start 1.700022 0.899922)
			(end -1.700022 0.899922)
			(stroke
				(width 0.1)
				(type default)
			)
			(layer "F.Fab")
		)
		(pad "1" smd rect
			(at -1.4732 0 180)
			(size 1.1684 1.5748)
			(layers "F.Cu" "F.Mask" "F.Paste")
			(net "P52V_HS_FILTER")
		)
		(pad "2" smd rect
			(at 1.4732 0 180)
			(size 1.1684 1.5748)
			(layers "F.Cu" "F.Mask" "F.Paste")
			(net "GND")
		)
	)
	(footprint ""
		(layer "F.Cu")
		(at 301.625 -119.6975)
		(property "Reference" "PR6960"
			(at 0 0 0)
			(layer "F.SilkS")
			(hide yes)
			(effects
				(font
					(size 1.27 1.27)
				)
			)
		)
		(property "Value" ""
			(at 0 0 0)
			(layer "F.Fab")
			(effects
				(font
					(size 1.27 1.27)
				)
			)
		)
		(duplicate_pad_numbers_are_jumpers no)
		(fp_line
			(start -1.2954 -0.5842)
			(end 1.2954 -0.5842)
			(stroke
				(width 0.1524)
				(type default)
			)
			(layer "F.SilkS")
		)
		(fp_line
			(start -1.2954 0.5842)
			(end -1.2954 -0.5842)
			(stroke
				(width 0.1524)
				(type default)
			)
			(layer "F.SilkS")
		)
		(fp_line
			(start 1.2954 -0.5842)
			(end 1.2954 0.5842)
			(stroke
				(width 0.1524)
				(type default)
			)
			(layer "F.SilkS")
		)
		(fp_line
			(start 1.2954 0.5842)
			(end -1.2954 0.5842)
			(stroke
				(width 0.1524)
				(type default)
			)
			(layer "F.SilkS")
		)
		(fp_line
			(start -1.1938 -0.406654)
			(end -0.8636 -0.406654)
			(stroke
				(width 0.1)
				(type default)
			)
			(layer "F.Fab")
		)
		(fp_line
			(start -1.1938 0.4064)
			(end -1.1938 -0.406654)
			(stroke
				(width 0.1)
				(type default)
			)
			(layer "F.Fab")
		)
		(fp_line
			(start -0.8636 -0.4572)
			(end 0.8636 -0.4572)
			(stroke
				(width 0.1)
				(type default)
			)
			(layer "F.Fab")
		)
		(fp_line
			(start -0.8636 -0.406654)
			(end -0.8636 -0.4572)
			(stroke
				(width 0.1)
				(type default)
			)
			(layer "F.Fab")
		)
		(fp_line
			(start -0.8636 0.4064)
			(end -1.1938 0.4064)
			(stroke
				(width 0.1)
				(type default)
			)
			(layer "F.Fab")
		)
		(fp_line
			(start -0.8636 0.4318)
			(end -0.8636 0.4064)
			(stroke
				(width 0.1)
				(type default)
			)
			(layer "F.Fab")
		)
		(fp_line
			(start -0.8636 0.4572)
			(end -0.8636 0.4318)
			(stroke
				(width 0.1)
				(type default)
			)
			(layer "F.Fab")
		)
		(fp_line
			(start 0.8636 -0.4572)
			(end 0.8636 -0.406654)
			(stroke
				(width 0.1)
				(type default)
			)
			(layer "F.Fab")
		)
		(fp_line
			(start 0.8636 -0.406654)
			(end 1.1938 -0.406654)
			(stroke
				(width 0.1)
				(type default)
			)
			(layer "F.Fab")
		)
		(fp_line
			(start 0.8636 0.4064)
			(end 0.8636 0.4572)
			(stroke
				(width 0.1)
				(type default)
			)
			(layer "F.Fab")
		)
		(fp_line
			(start 0.8636 0.4572)
			(end -0.8636 0.4572)
			(stroke
				(width 0.1)
				(type default)
			)
			(layer "F.Fab")
		)
		(fp_line
			(start 1.1938 -0.406654)
			(end 1.1938 0.4064)
			(stroke
				(width 0.1)
				(type default)
			)
			(layer "F.Fab")
		)
		(fp_line
			(start 1.1938 0.4064)
			(end 0.8636 0.4064)
			(stroke
				(width 0.1)
				(type default)
			)
			(layer "F.Fab")
		)
		(pad "1" smd rect
			(at -0.7366 0 270)
			(size 0.7112 0.8128)
			(layers "F.Cu" "F.Mask" "F.Paste")
			(net "P52V_HS_1272_S_P")
		)
		(pad "2" smd rect
			(at 0.7366 0 270)
			(size 0.7112 0.8128)
			(layers "F.Cu" "F.Mask" "F.Paste")
			(net "P52V_HS1_SENSE_P_R1")
		)
	)
	(footprint ""
		(layer "F.Cu")
		(at 120.015 -60.96)
		(property "Reference" "PC70"
			(at -1.397 -3.52933 0)
			(unlocked yes)
			(layer "F.SilkS")
			(effects
				(font
					(size 0.7874 0.5842)
					(thickness 0.1524)
				)
				(justify left)
			)
		)
		(property "Value" ""
			(at 0 0 0)
			(layer "F.Fab")
			(effects
				(font
					(size 1.27 1.27)
				)
			)
		)
		(duplicate_pad_numbers_are_jumpers no)
		(fp_line
			(start 5.2578 2.499868)
			(end -5.2578 2.499868)
			(stroke
				(width 0.1524)
				(type default)
			)
			(layer "F.SilkS")
		)
		(fp_circle
			(center 0 2.499868)
			(end 5.2578 2.499868)
			(stroke
				(width 0.1524)
				(type default)
			)
			(fill no)
			(layer "F.SilkS")
		)
		(fp_poly
			(pts
				(arc
					(start 5.2578 2.499868)
					(mid 0 7.757922)
					(end -5.2578 2.499868)
				)
			)
			(stroke
				(width 0)
				(type default)
			)
			(fill yes)
			(layer "F.SilkS")
		)
		(fp_circle
			(center 0 2.499868)
			(end 5.2578 2.499868)
			(stroke
				(width 0.1)
				(type default)
			)
			(fill no)
			(layer "F.Fab")
		)
		(pad "1" thru_hole rect
			(at 0 0 270)
			(size 1.524 1.524)
			(drill 1.016)
			(layers "*.Cu" "*.Mask")
			(remove_unused_layers no)
			(net "P12V_BRICK")
			(clearance 0)
			(padstack
				(mode front_inner_back)
				(layer "Inner"
					(shape circle)
					(size 1.524 1.524)
					(clearance 0)
				)
				(layer "B.Cu"
					(shape rect)
					(size 1.524 1.524)
					(clearance 0)
				)
			)
		)
		(pad "2" thru_hole circle
			(at 0 4.99999 270)
			(size 1.524 1.524)
			(drill 1.016)
			(layers "*.Cu" "*.Mask")
			(remove_unused_layers no)
			(net "GND")
			(clearance 0)
		)
	)
	(footprint ""
		(layer "F.Cu")
		(at 294.9448 -42.164 -90)
		(property "Reference" "PC559"
			(at 0 0 270)
			(layer "F.SilkS")
			(hide yes)
			(effects
				(font
					(size 1.27 1.27)
				)
			)
		)
		(property "Value" ""
			(at 0 0 270)
			(layer "F.Fab")
			(effects
				(font
					(size 1.27 1.27)
				)
			)
		)
		(duplicate_pad_numbers_are_jumpers no)
		(fp_line
			(start -2.2098 0.9398)
			(end -2.2098 -0.9398)
			(stroke
				(width 0.1524)
				(type default)
			)
			(layer "F.SilkS")
		)
		(fp_line
			(start 2.2098 0.9398)
			(end -2.2098 0.9398)
			(stroke
				(width 0.1524)
				(type default)
			)
			(layer "F.SilkS")
		)
		(fp_line
			(start -2.2098 -0.9398)
			(end 2.2098 -0.9398)
			(stroke
				(width 0.1524)
				(type default)
			)
			(layer "F.SilkS")
		)
		(fp_line
			(start 2.2098 -0.9398)
			(end 2.2098 0.9398)
			(stroke
				(width 0.1524)
				(type default)
			)
			(layer "F.SilkS")
		)
		(fp_line
			(start -1.6764 0.9398)
			(end -1.6764 0.889)
			(stroke
				(width 0.1)
				(type default)
			)
			(layer "F.Fab")
		)
		(fp_line
			(start 1.6764 0.9398)
			(end -1.6764 0.9398)
			(stroke
				(width 0.1)
				(type default)
			)
			(layer "F.Fab")
		)
		(fp_line
			(start -1.6764 0.889)
			(end -1.6764 0.8382)
			(stroke
				(width 0.1)
				(type default)
			)
			(layer "F.Fab")
		)
		(fp_line
			(start 1.6764 0.889)
			(end 1.6764 0.9398)
			(stroke
				(width 0.1)
				(type default)
			)
			(layer "F.Fab")
		)
		(fp_line
			(start -2.1082 0.8382)
			(end -2.1082 -0.8382)
			(stroke
				(width 0.1)
				(type default)
			)
			(layer "F.Fab")
		)
		(fp_line
			(start -1.6764 0.8382)
			(end -2.1082 0.8382)
			(stroke
				(width 0.1)
				(type default)
			)
			(layer "F.Fab")
		)
		(fp_line
			(start 1.6764 0.8382)
			(end 1.6764 0.889)
			(stroke
				(width 0.1)
				(type default)
			)
			(layer "F.Fab")
		)
		(fp_line
			(start 2.1082 0.8382)
			(end 1.6764 0.8382)
			(stroke
				(width 0.1)
				(type default)
			)
			(layer "F.Fab")
		)
		(fp_line
			(start -2.1082 -0.8382)
			(end -1.6764 -0.8382)
			(stroke
				(width 0.1)
				(type default)
			)
			(layer "F.Fab")
		)
		(fp_line
			(start -1.6764 -0.8382)
			(end -1.6764 -0.889)
			(stroke
				(width 0.1)
				(type default)
			)
			(layer "F.Fab")
		)
		(fp_line
			(start 1.6764 -0.8382)
			(end 2.1082 -0.8382)
			(stroke
				(width 0.1)
				(type default)
			)
			(layer "F.Fab")
		)
		(fp_line
			(start 2.1082 -0.8382)
			(end 2.1082 0.8382)
			(stroke
				(width 0.1)
				(type default)
			)
			(layer "F.Fab")
		)
		(fp_line
			(start -1.6764 -0.889)
			(end -1.6764 -0.9398)
			(stroke
				(width 0.1)
				(type default)
			)
			(layer "F.Fab")
		)
		(fp_line
			(start 1.6764 -0.889)
			(end 1.6764 -0.8382)
			(stroke
				(width 0.1)
				(type default)
			)
			(layer "F.Fab")
		)
		(fp_line
			(start -1.6764 -0.9398)
			(end 1.6764 -0.9398)
			(stroke
				(width 0.1)
				(type default)
			)
			(layer "F.Fab")
		)
		(fp_line
			(start 1.6764 -0.9398)
			(end 1.6764 -0.889)
			(stroke
				(width 0.1)
				(type default)
			)
			(layer "F.Fab")
		)
		(pad "1" smd rect
			(at -1.4732 0 90)
			(size 1.1684 1.5748)
			(layers "F.Cu" "F.Mask" "F.Paste")
			(net "P52V_HS")
		)
		(pad "2" smd rect
			(at 1.4732 0 90)
			(size 1.1684 1.5748)
			(layers "F.Cu" "F.Mask" "F.Paste")
			(net "P52V_HS1_VCP")
		)
	)
	(footprint ""
		(layer "F.Cu")
		(at 106.426 -51.943)
		(property "Reference" "PC64"
			(at 0 0 0)
			(layer "F.SilkS")
			(hide yes)
			(effects
				(font
					(size 1.27 1.27)
				)
			)
		)
		(property "Value" ""
			(at 0 0 0)
			(layer "F.Fab")
			(effects
				(font
					(size 1.27 1.27)
				)
			)
		)
		(duplicate_pad_numbers_are_jumpers no)
		(fp_line
			(start -1.524 -0.762)
			(end 1.524 -0.762)
			(stroke
				(width 0.1524)
				(type default)
			)
			(layer "F.SilkS")
		)
		(fp_line
			(start -1.524 0.762)
			(end -1.524 -0.762)
			(stroke
				(width 0.1524)
				(type default)
			)
			(layer "F.SilkS")
		)
		(fp_line
			(start 1.524 -0.762)
			(end 1.524 0.762)
			(stroke
				(width 0.1524)
				(type default)
			)
			(layer "F.SilkS")
		)
		(fp_line
			(start 1.524 0.762)
			(end -1.524 0.762)
			(stroke
				(width 0.1524)
				(type default)
			)
			(layer "F.SilkS")
		)
		(fp_line
			(start -1.1049 -0.724916)
			(end -1.1049 0.724916)
			(stroke
				(width 0.1)
				(type default)
			)
			(layer "F.Fab")
		)
		(fp_line
			(start -1.1049 0.724916)
			(end 1.1049 0.724916)
			(stroke
				(width 0.1)
				(type default)
			)
			(layer "F.Fab")
		)
		(fp_line
			(start 1.1049 -0.724916)
			(end -1.1049 -0.724916)
			(stroke
				(width 0.1)
				(type default)
			)
			(layer "F.Fab")
		)
		(fp_line
			(start 1.1049 0.724916)
			(end 1.1049 -0.724916)
			(stroke
				(width 0.1)
				(type default)
			)
			(layer "F.Fab")
		)
		(pad "1" smd rect
			(at -0.889 0 180)
			(size 1.016 1.27)
			(layers "F.Cu" "F.Mask" "F.Paste")
			(net "P12V_BRICK")
		)
		(pad "2" smd rect
			(at 0.889 0 180)
			(size 1.016 1.27)
			(layers "F.Cu" "F.Mask" "F.Paste")
			(net "GND")
		)
	)
	(footprint ""
		(layer "F.Cu")
		(at 179.06746 -51.816)
		(property "Reference" "PC127"
			(at 0 0 0)
			(layer "F.SilkS")
			(hide yes)
			(effects
				(font
					(size 1.27 1.27)
				)
			)
		)
		(property "Value" ""
			(at 0 0 0)
			(layer "F.Fab")
			(effects
				(font
					(size 1.27 1.27)
				)
			)
		)
		(duplicate_pad_numbers_are_jumpers no)
		(fp_line
			(start -1.524 -0.762)
			(end 1.524 -0.762)
			(stroke
				(width 0.1524)
				(type default)
			)
			(layer "F.SilkS")
		)
		(fp_line
			(start -1.524 0.762)
			(end -1.524 -0.762)
			(stroke
				(width 0.1524)
				(type default)
			)
			(layer "F.SilkS")
		)
		(fp_line
			(start 1.524 -0.762)
			(end 1.524 0.762)
			(stroke
				(width 0.1524)
				(type default)
			)
			(layer "F.SilkS")
		)
		(fp_line
			(start 1.524 0.762)
			(end -1.524 0.762)
			(stroke
				(width 0.1524)
				(type default)
			)
			(layer "F.SilkS")
		)
		(fp_line
			(start -1.1049 -0.724916)
			(end -1.1049 0.724916)
			(stroke
				(width 0.1)
				(type default)
			)
			(layer "F.Fab")
		)
		(fp_line
			(start -1.1049 0.724916)
			(end 1.1049 0.724916)
			(stroke
				(width 0.1)
				(type default)
			)
			(layer "F.Fab")
		)
		(fp_line
			(start 1.1049 -0.724916)
			(end -1.1049 -0.724916)
			(stroke
				(width 0.1)
				(type default)
			)
			(layer "F.Fab")
		)
		(fp_line
			(start 1.1049 0.724916)
			(end 1.1049 -0.724916)
			(stroke
				(width 0.1)
				(type default)
			)
			(layer "F.Fab")
		)
		(pad "1" smd rect
			(at -0.889 0 180)
			(size 1.016 1.27)
			(layers "F.Cu" "F.Mask" "F.Paste")
			(net "P12V_BRICK")
		)
		(pad "2" smd rect
			(at 0.889 0 180)
			(size 1.016 1.27)
			(layers "F.Cu" "F.Mask" "F.Paste")
			(net "GND")
		)
	)
	(footprint ""
		(layer "F.Cu")
		(at 299.65396 -114.412268 180)
		(property "Reference" "PR1"
			(at 3.48996 -4.266438 0)
			(unlocked yes)
			(layer "F.SilkS")
			(effects
				(font
					(size 0.7874 0.5842)
					(thickness 0.1524)
				)
				(justify left)
			)
		)
		(property "Value" ""
			(at 0 0 180)
			(layer "F.Fab")
			(effects
				(font
					(size 1.27 1.27)
				)
			)
		)
		(duplicate_pad_numbers_are_jumpers no)
		(fp_line
			(start 3.9878 3.5814)
			(end -3.9878 3.5814)
			(stroke
				(width 0.1524)
				(type default)
			)
			(layer "F.SilkS")
		)
		(fp_line
			(start 3.9878 -3.5814)
			(end 3.9878 3.5814)
			(stroke
				(width 0.1524)
				(type default)
			)
			(layer "F.SilkS")
		)
		(fp_line
			(start -3.9878 3.5814)
			(end -3.9878 -3.5814)
			(stroke
				(width 0.1524)
				(type default)
			)
			(layer "F.SilkS")
		)
		(fp_line
			(start -3.9878 -3.5814)
			(end 3.9878 -3.5814)
			(stroke
				(width 0.1524)
				(type default)
			)
			(layer "F.SilkS")
		)
		(fp_line
			(start 3.5306 3.353054)
			(end -3.5306 3.353054)
			(stroke
				(width 0.1)
				(type default)
			)
			(layer "F.Fab")
		)
		(fp_line
			(start 3.5306 -3.353054)
			(end 3.5306 3.353054)
			(stroke
				(width 0.1)
				(type default)
			)
			(layer "F.Fab")
		)
		(fp_line
			(start -3.5306 3.353054)
			(end -3.5306 -3.353054)
			(stroke
				(width 0.1)
				(type default)
			)
			(layer "F.Fab")
		)
		(fp_line
			(start -3.5306 -3.353054)
			(end 3.5306 -3.353054)
			(stroke
				(width 0.1)
				(type default)
			)
			(layer "F.Fab")
		)
		(pad "1A" smd rect
			(at -2.249932 0)
			(size 3.2004 6.858)
			(layers "F.Cu" "F.Mask" "F.Paste")
			(net "P52V_1")
		)
		(pad "1B" smd rect
			(at -0.776732 0 180)
			(size 0.254 0.508)
			(layers "F.Cu" "F.Mask" "F.Paste")
			(net "P52V_HS1_SENSE_P_R1")
		)
		(pad "2A" smd rect
			(at 2.249932 0)
			(size 3.2004 6.858)
			(layers "F.Cu" "F.Mask" "F.Paste")
			(net "P52V_HS1_DRAIN_1")
		)
		(pad "2B" smd rect
			(at 0.776732 0 180)
			(size 0.254 0.508)
			(layers "F.Cu" "F.Mask" "F.Paste")
			(net "P52V_HS1_SENSE_N_R1")
		)
	)
	(footprint ""
		(layer "F.Cu")
		(at 281.98191 -56.957214 180)
		(property "Reference" "PR6969"
			(at 0 0 180)
			(layer "F.SilkS")
			(hide yes)
			(effects
				(font
					(size 1.27 1.27)
				)
			)
		)
		(property "Value" ""
			(at 0 0 180)
			(layer "F.Fab")
			(effects
				(font
					(size 1.27 1.27)
				)
			)
		)
		(duplicate_pad_numbers_are_jumpers no)
		(fp_line
			(start 0.7874 0.4064)
			(end -0.7874 0.4064)
			(stroke
				(width 0.1524)
				(type default)
			)
			(layer "F.SilkS")
		)
		(fp_line
			(start 0.7874 -0.4064)
			(end 0.7874 0.4064)
			(stroke
				(width 0.1524)
				(type default)
			)
			(layer "F.SilkS")
		)
		(fp_line
			(start -0.7874 0.4064)
			(end -0.7874 -0.4064)
			(stroke
				(width 0.1524)
				(type default)
			)
			(layer "F.SilkS")
		)
		(fp_line
			(start -0.7874 -0.4064)
			(end 0.7874 -0.4064)
			(stroke
				(width 0.1524)
				(type default)
			)
			(layer "F.SilkS")
		)
		(fp_line
			(start 0.67945 0.3048)
			(end 0.120396 0.3048)
			(stroke
				(width 0.1)
				(type default)
			)
			(layer "F.Fab")
		)
		(fp_line
			(start 0.67945 -0.3048)
			(end 0.67945 0.3048)
			(stroke
				(width 0.1)
				(type default)
			)
			(layer "F.Fab")
		)
		(fp_line
			(start 0.12065 -0.2794)
			(end 0.12065 -0.3048)
			(stroke
				(width 0.1)
				(type default)
			)
			(layer "F.Fab")
		)
		(fp_line
			(start 0.12065 -0.3048)
			(end 0.67945 -0.3048)
			(stroke
				(width 0.1)
				(type default)
			)
			(layer "F.Fab")
		)
		(fp_line
			(start 0.120396 0.3048)
			(end 0.120396 0.2794)
			(stroke
				(width 0.1)
				(type default)
			)
			(layer "F.Fab")
		)
		(fp_line
			(start 0.120396 0.2794)
			(end -0.12065 0.2794)
			(stroke
				(width 0.1)
				(type default)
			)
			(layer "F.Fab")
		)
		(fp_line
			(start -0.12065 0.3048)
			(end -0.67945 0.3048)
			(stroke
				(width 0.1)
				(type default)
			)
			(layer "F.Fab")
		)
		(fp_line
			(start -0.12065 0.2794)
			(end -0.12065 0.3048)
			(stroke
				(width 0.1)
				(type default)
			)
			(layer "F.Fab")
		)
		(fp_line
			(start -0.12065 -0.2794)
			(end 0.12065 -0.2794)
			(stroke
				(width 0.1)
				(type default)
			)
			(layer "F.Fab")
		)
		(fp_line
			(start -0.12065 -0.305054)
			(end -0.12065 -0.2794)
			(stroke
				(width 0.1)
				(type default)
			)
			(layer "F.Fab")
		)
		(fp_line
			(start -0.67945 0.3048)
			(end -0.67945 -0.305054)
			(stroke
				(width 0.1)
				(type default)
			)
			(layer "F.Fab")
		)
		(fp_line
			(start -0.67945 -0.305054)
			(end -0.12065 -0.305054)
			(stroke
				(width 0.1)
				(type default)
			)
			(layer "F.Fab")
		)
		(pad "1" smd rect
			(at -0.40005 0)
			(size 0.4572 0.508)
			(layers "F.Cu" "F.Mask" "F.Paste")
			(net "P52V_HS1_TEMPN_R")
		)
		(pad "2" smd rect
			(at 0.40005 0)
			(size 0.4572 0.508)
			(layers "F.Cu" "F.Mask" "F.Paste")
			(net "GND_FIELD_SIGNAL")
		)
	)
	(footprint ""
		(layer "F.Cu")
		(at 264.1854 -49.1998)
		(property "Reference" "PR24"
			(at 0 0 0)
			(layer "F.SilkS")
			(hide yes)
			(effects
				(font
					(size 1.27 1.27)
				)
			)
		)
		(property "Value" ""
			(at 0 0 0)
			(layer "F.Fab")
			(effects
				(font
					(size 1.27 1.27)
				)
			)
		)
		(duplicate_pad_numbers_are_jumpers no)
		(fp_line
			(start -0.7874 -0.4064)
			(end 0.7874 -0.4064)
			(stroke
				(width 0.1524)
				(type default)
			)
			(layer "F.SilkS")
		)
		(fp_line
			(start -0.7874 0.4064)
			(end -0.7874 -0.4064)
			(stroke
				(width 0.1524)
				(type default)
			)
			(layer "F.SilkS")
		)
		(fp_line
			(start 0.7874 -0.4064)
			(end 0.7874 0.4064)
			(stroke
				(width 0.1524)
				(type default)
			)
			(layer "F.SilkS")
		)
		(fp_line
			(start 0.7874 0.4064)
			(end -0.7874 0.4064)
			(stroke
				(width 0.1524)
				(type default)
			)
			(layer "F.SilkS")
		)
		(fp_line
			(start -0.67945 -0.305054)
			(end -0.12065 -0.305054)
			(stroke
				(width 0.1)
				(type default)
			)
			(layer "F.Fab")
		)
		(fp_line
			(start -0.67945 0.3048)
			(end -0.67945 -0.305054)
			(stroke
				(width 0.1)
				(type default)
			)
			(layer "F.Fab")
		)
		(fp_line
			(start -0.12065 -0.305054)
			(end -0.12065 -0.2794)
			(stroke
				(width 0.1)
				(type default)
			)
			(layer "F.Fab")
		)
		(fp_line
			(start -0.12065 -0.2794)
			(end 0.12065 -0.2794)
			(stroke
				(width 0.1)
				(type default)
			)
			(layer "F.Fab")
		)
		(fp_line
			(start -0.12065 0.2794)
			(end -0.12065 0.3048)
			(stroke
				(width 0.1)
				(type default)
			)
			(layer "F.Fab")
		)
		(fp_line
			(start -0.12065 0.3048)
			(end -0.67945 0.3048)
			(stroke
				(width 0.1)
				(type default)
			)
			(layer "F.Fab")
		)
		(fp_line
			(start 0.120396 0.2794)
			(end -0.12065 0.2794)
			(stroke
				(width 0.1)
				(type default)
			)
			(layer "F.Fab")
		)
		(fp_line
			(start 0.120396 0.3048)
			(end 0.120396 0.2794)
			(stroke
				(width 0.1)
				(type default)
			)
			(layer "F.Fab")
		)
		(fp_line
			(start 0.12065 -0.3048)
			(end 0.67945 -0.3048)
			(stroke
				(width 0.1)
				(type default)
			)
			(layer "F.Fab")
		)
		(fp_line
			(start 0.12065 -0.2794)
			(end 0.12065 -0.3048)
			(stroke
				(width 0.1)
				(type default)
			)
			(layer "F.Fab")
		)
		(fp_line
			(start 0.67945 -0.3048)
			(end 0.67945 0.3048)
			(stroke
				(width 0.1)
				(type default)
			)
			(layer "F.Fab")
		)
		(fp_line
			(start 0.67945 0.3048)
			(end 0.120396 0.3048)
			(stroke
				(width 0.1)
				(type default)
			)
			(layer "F.Fab")
		)
		(pad "1" smd circle
			(at -0.40005 0)
			(size 0 0)
			(layers "F.Cu" "F.Mask" "F.Paste")
			(net "P52V_HS1_FB")
		)
		(pad "2" smd circle
			(at 0.40005 0)
			(size 0 0)
			(layers "F.Cu" "F.Mask" "F.Paste")
			(net "GND_FIELD_SIGNAL")
		)
	)
	(footprint ""
		(layer "F.Cu")
		(at 106.426 -50.038)
		(property "Reference" "PC65"
			(at 0 0 0)
			(layer "F.SilkS")
			(hide yes)
			(effects
				(font
					(size 1.27 1.27)
				)
			)
		)
		(property "Value" ""
			(at 0 0 0)
			(layer "F.Fab")
			(effects
				(font
					(size 1.27 1.27)
				)
			)
		)
		(duplicate_pad_numbers_are_jumpers no)
		(fp_line
			(start -1.524 -0.762)
			(end 1.524 -0.762)
			(stroke
				(width 0.1524)
				(type default)
			)
			(layer "F.SilkS")
		)
		(fp_line
			(start -1.524 0.762)
			(end -1.524 -0.762)
			(stroke
				(width 0.1524)
				(type default)
			)
			(layer "F.SilkS")
		)
		(fp_line
			(start 1.524 -0.762)
			(end 1.524 0.762)
			(stroke
				(width 0.1524)
				(type default)
			)
			(layer "F.SilkS")
		)
		(fp_line
			(start 1.524 0.762)
			(end -1.524 0.762)
			(stroke
				(width 0.1524)
				(type default)
			)
			(layer "F.SilkS")
		)
		(fp_line
			(start -1.1049 -0.724916)
			(end -1.1049 0.724916)
			(stroke
				(width 0.1)
				(type default)
			)
			(layer "F.Fab")
		)
		(fp_line
			(start -1.1049 0.724916)
			(end 1.1049 0.724916)
			(stroke
				(width 0.1)
				(type default)
			)
			(layer "F.Fab")
		)
		(fp_line
			(start 1.1049 -0.724916)
			(end -1.1049 -0.724916)
			(stroke
				(width 0.1)
				(type default)
			)
			(layer "F.Fab")
		)
		(fp_line
			(start 1.1049 0.724916)
			(end 1.1049 -0.724916)
			(stroke
				(width 0.1)
				(type default)
			)
			(layer "F.Fab")
		)
		(pad "1" smd rect
			(at -0.889 0 180)
			(size 1.016 1.27)
			(layers "F.Cu" "F.Mask" "F.Paste")
			(net "P12V_BRICK")
		)
		(pad "2" smd rect
			(at 0.889 0 180)
			(size 1.016 1.27)
			(layers "F.Cu" "F.Mask" "F.Paste")
			(net "GND")
		)
	)
	(footprint ""
		(layer "F.Cu")
		(at 95.504 -50.038)
		(property "Reference" "PC87"
			(at 0 0 0)
			(layer "F.SilkS")
			(hide yes)
			(effects
				(font
					(size 1.27 1.27)
				)
			)
		)
		(property "Value" ""
			(at 0 0 0)
			(layer "F.Fab")
			(effects
				(font
					(size 1.27 1.27)
				)
			)
		)
		(duplicate_pad_numbers_are_jumpers no)
		(fp_line
			(start -1.524 -0.762)
			(end 1.524 -0.762)
			(stroke
				(width 0.1524)
				(type default)
			)
			(layer "F.SilkS")
		)
		(fp_line
			(start -1.524 0.762)
			(end -1.524 -0.762)
			(stroke
				(width 0.1524)
				(type default)
			)
			(layer "F.SilkS")
		)
		(fp_line
			(start 1.524 -0.762)
			(end 1.524 0.762)
			(stroke
				(width 0.1524)
				(type default)
			)
			(layer "F.SilkS")
		)
		(fp_line
			(start 1.524 0.762)
			(end -1.524 0.762)
			(stroke
				(width 0.1524)
				(type default)
			)
			(layer "F.SilkS")
		)
		(fp_line
			(start -1.1049 -0.724916)
			(end -1.1049 0.724916)
			(stroke
				(width 0.1)
				(type default)
			)
			(layer "F.Fab")
		)
		(fp_line
			(start -1.1049 0.724916)
			(end 1.1049 0.724916)
			(stroke
				(width 0.1)
				(type default)
			)
			(layer "F.Fab")
		)
		(fp_line
			(start 1.1049 -0.724916)
			(end -1.1049 -0.724916)
			(stroke
				(width 0.1)
				(type default)
			)
			(layer "F.Fab")
		)
		(fp_line
			(start 1.1049 0.724916)
			(end 1.1049 -0.724916)
			(stroke
				(width 0.1)
				(type default)
			)
			(layer "F.Fab")
		)
		(pad "1" smd rect
			(at -0.889 0 180)
			(size 1.016 1.27)
			(layers "F.Cu" "F.Mask" "F.Paste")
			(net "P12V_BRICK")
		)
		(pad "2" smd rect
			(at 0.889 0 180)
			(size 1.016 1.27)
			(layers "F.Cu" "F.Mask" "F.Paste")
			(net "GND")
		)
	)
	(footprint ""
		(layer "F.Cu")
		(at 201.257916 -66.956686 90)
		(property "Reference" "R61"
			(at 0 0 90)
			(layer "F.SilkS")
			(hide yes)
			(effects
				(font
					(size 1.27 1.27)
				)
			)
		)
		(property "Value" ""
			(at 0 0 90)
			(layer "F.Fab")
			(effects
				(font
					(size 1.27 1.27)
				)
			)
		)
		(duplicate_pad_numbers_are_jumpers no)
		(fp_line
			(start 0.7874 -0.4064)
			(end 0.7874 0.4064)
			(stroke
				(width 0.1524)
				(type default)
			)
			(layer "F.SilkS")
		)
		(fp_line
			(start -0.7874 -0.4064)
			(end 0.7874 -0.4064)
			(stroke
				(width 0.1524)
				(type default)
			)
			(layer "F.SilkS")
		)
		(fp_line
			(start 0.7874 0.4064)
			(end -0.7874 0.4064)
			(stroke
				(width 0.1524)
				(type default)
			)
			(layer "F.SilkS")
		)
		(fp_line
			(start -0.7874 0.4064)
			(end -0.7874 -0.4064)
			(stroke
				(width 0.1524)
				(type default)
			)
			(layer "F.SilkS")
		)
		(fp_line
			(start -0.12065 -0.305054)
			(end -0.12065 -0.2794)
			(stroke
				(width 0.1)
				(type default)
			)
			(layer "F.Fab")
		)
		(fp_line
			(start -0.67945 -0.305054)
			(end -0.12065 -0.305054)
			(stroke
				(width 0.1)
				(type default)
			)
			(layer "F.Fab")
		)
		(fp_line
			(start 0.67945 -0.3048)
			(end 0.67945 0.3048)
			(stroke
				(width 0.1)
				(type default)
			)
			(layer "F.Fab")
		)
		(fp_line
			(start 0.12065 -0.3048)
			(end 0.67945 -0.3048)
			(stroke
				(width 0.1)
				(type default)
			)
			(layer "F.Fab")
		)
		(fp_line
			(start 0.12065 -0.2794)
			(end 0.12065 -0.3048)
			(stroke
				(width 0.1)
				(type default)
			)
			(layer "F.Fab")
		)
		(fp_line
			(start -0.12065 -0.2794)
			(end 0.12065 -0.2794)
			(stroke
				(width 0.1)
				(type default)
			)
			(layer "F.Fab")
		)
		(fp_line
			(start 0.120396 0.2794)
			(end -0.12065 0.2794)
			(stroke
				(width 0.1)
				(type default)
			)
			(layer "F.Fab")
		)
		(fp_line
			(start -0.12065 0.2794)
			(end -0.12065 0.3048)
			(stroke
				(width 0.1)
				(type default)
			)
			(layer "F.Fab")
		)
		(fp_line
			(start 0.67945 0.3048)
			(end 0.120396 0.3048)
			(stroke
				(width 0.1)
				(type default)
			)
			(layer "F.Fab")
		)
		(fp_line
			(start 0.120396 0.3048)
			(end 0.120396 0.2794)
			(stroke
				(width 0.1)
				(type default)
			)
			(layer "F.Fab")
		)
		(fp_line
			(start -0.12065 0.3048)
			(end -0.67945 0.3048)
			(stroke
				(width 0.1)
				(type default)
			)
			(layer "F.Fab")
		)
		(fp_line
			(start -0.67945 0.3048)
			(end -0.67945 -0.305054)
			(stroke
				(width 0.1)
				(type default)
			)
			(layer "F.Fab")
		)
		(pad "1" smd circle
			(at -0.40005 0 90)
			(size 0 0)
			(layers "F.Cu" "F.Mask" "F.Paste")
			(net "LED_D2_R2")
		)
		(pad "2" smd circle
			(at 0.40005 0 90)
			(size 0 0)
			(layers "F.Cu" "F.Mask" "F.Paste")
			(net "LED_D2_R3")
		)
	)
	(footprint ""
		(layer "F.Cu")
		(at 274.2438 -24.2316)
		(property "Reference" "R5889"
			(at 0 0 0)
			(layer "F.SilkS")
			(hide yes)
			(effects
				(font
					(size 1.27 1.27)
				)
			)
		)
		(property "Value" ""
			(at 0 0 0)
			(layer "F.Fab")
			(effects
				(font
					(size 1.27 1.27)
				)
			)
		)
		(duplicate_pad_numbers_are_jumpers no)
		(fp_line
			(start -1.651 -0.8382)
			(end 1.651 -0.8382)
			(stroke
				(width 0.1524)
				(type default)
			)
			(layer "F.SilkS")
		)
		(fp_line
			(start -1.651 0.8382)
			(end -1.651 -0.8382)
			(stroke
				(width 0.1524)
				(type default)
			)
			(layer "F.SilkS")
		)
		(fp_line
			(start 1.651 -0.8382)
			(end 1.651 0.8382)
			(stroke
				(width 0.1524)
				(type default)
			)
			(layer "F.SilkS")
		)
		(fp_line
			(start 1.651 0.8382)
			(end -1.651 0.8382)
			(stroke
				(width 0.1524)
				(type default)
			)
			(layer "F.SilkS")
		)
		(fp_line
			(start -1.559814 -0.7366)
			(end -1.559814 0.7366)
			(stroke
				(width 0.1)
				(type default)
			)
			(layer "F.Fab")
		)
		(fp_line
			(start -1.559814 0.7366)
			(end -1.524 0.7366)
			(stroke
				(width 0.1)
				(type default)
			)
			(layer "F.Fab")
		)
		(fp_line
			(start -1.524 -0.7366)
			(end -1.559814 -0.7366)
			(stroke
				(width 0.1)
				(type default)
			)
			(layer "F.Fab")
		)
		(fp_line
			(start -1.524 0.7366)
			(end 1.524 0.7366)
			(stroke
				(width 0.1)
				(type default)
			)
			(layer "F.Fab")
		)
		(fp_line
			(start 1.524 -0.7366)
			(end -1.524 -0.7366)
			(stroke
				(width 0.1)
				(type default)
			)
			(layer "F.Fab")
		)
		(fp_line
			(start 1.524 0.7366)
			(end 1.560576 0.7366)
			(stroke
				(width 0.1)
				(type default)
			)
			(layer "F.Fab")
		)
		(fp_line
			(start 1.560576 -0.7366)
			(end 1.524 -0.7366)
			(stroke
				(width 0.1)
				(type default)
			)
			(layer "F.Fab")
		)
		(fp_line
			(start 1.560576 0.7366)
			(end 1.560576 -0.7366)
			(stroke
				(width 0.1)
				(type default)
			)
			(layer "F.Fab")
		)
		(pad "1" smd rect
			(at -0.94996 0 180)
			(size 1.1176 1.3716)
			(layers "F.Cu" "F.Mask" "F.Paste")
			(net "P52V_1_R")
		)
		(pad "2" smd rect
			(at 0.94996 0 180)
			(size 1.1176 1.3716)
			(layers "F.Cu" "F.Mask" "F.Paste")
			(net "P3V3_AND")
		)
	)
	(footprint ""
		(layer "F.Cu")
		(at 293.37 -50.673 -90)
		(property "Reference" "PR5"
			(at 0 0 270)
			(layer "F.SilkS")
			(hide yes)
			(effects
				(font
					(size 1.27 1.27)
				)
			)
		)
		(property "Value" ""
			(at 0 0 270)
			(layer "F.Fab")
			(effects
				(font
					(size 1.27 1.27)
				)
			)
		)
		(duplicate_pad_numbers_are_jumpers no)
		(fp_line
			(start -2.234946 0.9271)
			(end -2.234946 -0.9271)
			(stroke
				(width 0.1524)
				(type default)
			)
			(layer "F.SilkS")
		)
		(fp_line
			(start 2.234946 0.9271)
			(end -2.234946 0.9271)
			(stroke
				(width 0.1524)
				(type default)
			)
			(layer "F.SilkS")
		)
		(fp_line
			(start -2.234946 -0.9271)
			(end 2.234946 -0.9271)
			(stroke
				(width 0.1524)
				(type default)
			)
			(layer "F.SilkS")
		)
		(fp_line
			(start 2.234946 -0.9271)
			(end 2.234946 0.9271)
			(stroke
				(width 0.1524)
				(type default)
			)
			(layer "F.SilkS")
		)
		(fp_line
			(start -1.575054 0.824992)
			(end 1.575054 0.824992)
			(stroke
				(width 0.1)
				(type default)
			)
			(layer "F.Fab")
		)
		(fp_line
			(start 1.575054 0.824992)
			(end 1.575054 -0.824992)
			(stroke
				(width 0.1)
				(type default)
			)
			(layer "F.Fab")
		)
		(fp_line
			(start -1.575054 -0.824992)
			(end -1.575054 0.824992)
			(stroke
				(width 0.1)
				(type default)
			)
			(layer "F.Fab")
		)
		(fp_line
			(start 1.575054 -0.824992)
			(end -1.575054 -0.824992)
			(stroke
				(width 0.1)
				(type default)
			)
			(layer "F.Fab")
		)
		(pad "1" smd rect
			(at -1.599946 0 270)
			(size 1.016 1.6002)
			(layers "F.Cu" "F.Mask" "F.Paste")
			(net "P52V_1")
		)
		(pad "2" smd rect
			(at 1.599946 0 270)
			(size 1.016 1.6002)
			(layers "F.Cu" "F.Mask" "F.Paste")
			(net "P52V_HS1_VCC")
		)
	)
	(footprint ""
		(layer "F.Cu")
		(at 56.905906 -130.175)
		(property "Reference" "PC76"
			(at 0 0 0)
			(layer "F.SilkS")
			(hide yes)
			(effects
				(font
					(size 1.27 1.27)
				)
			)
		)
		(property "Value" ""
			(at 0 0 0)
			(layer "F.Fab")
			(effects
				(font
					(size 1.27 1.27)
				)
			)
		)
		(duplicate_pad_numbers_are_jumpers no)
		(fp_line
			(start -2.2098 -0.9398)
			(end 2.2098 -0.9398)
			(stroke
				(width 0.1524)
				(type default)
			)
			(layer "F.SilkS")
		)
		(fp_line
			(start -2.2098 0.9398)
			(end -2.2098 -0.9398)
			(stroke
				(width 0.1524)
				(type default)
			)
			(layer "F.SilkS")
		)
		(fp_line
			(start 2.2098 -0.9398)
			(end 2.2098 0.9398)
			(stroke
				(width 0.1524)
				(type default)
			)
			(layer "F.SilkS")
		)
		(fp_line
			(start 2.2098 0.9398)
			(end -2.2098 0.9398)
			(stroke
				(width 0.1524)
				(type default)
			)
			(layer "F.SilkS")
		)
		(fp_line
			(start -1.700022 -0.899922)
			(end 1.700022 -0.899922)
			(stroke
				(width 0.1)
				(type default)
			)
			(layer "F.Fab")
		)
		(fp_line
			(start -1.700022 0.899922)
			(end -1.700022 -0.899922)
			(stroke
				(width 0.1)
				(type default)
			)
			(layer "F.Fab")
		)
		(fp_line
			(start 1.700022 -0.899922)
			(end 1.700022 0.899922)
			(stroke
				(width 0.1)
				(type default)
			)
			(layer "F.Fab")
		)
		(fp_line
			(start 1.700022 0.899922)
			(end -1.700022 0.899922)
			(stroke
				(width 0.1)
				(type default)
			)
			(layer "F.Fab")
		)
		(pad "1" smd rect
			(at -1.4732 0 180)
			(size 1.1684 1.5748)
			(layers "F.Cu" "F.Mask" "F.Paste")
			(net "P52V_HS_FILTER")
		)
		(pad "2" smd rect
			(at 1.4732 0 180)
			(size 1.1684 1.5748)
			(layers "F.Cu" "F.Mask" "F.Paste")
			(net "GND")
		)
	)
	(footprint ""
		(layer "F.Cu")
		(at 270.383 -105.623868 -90)
		(property "Reference" "PR13"
			(at 0 0 270)
			(layer "F.SilkS")
			(hide yes)
			(effects
				(font
					(size 1.27 1.27)
				)
			)
		)
		(property "Value" ""
			(at 0 0 270)
			(layer "F.Fab")
			(effects
				(font
					(size 1.27 1.27)
				)
			)
		)
		(duplicate_pad_numbers_are_jumpers no)
		(fp_line
			(start -1.2954 0.5842)
			(end -1.2954 -0.5842)
			(stroke
				(width 0.1524)
				(type default)
			)
			(layer "F.SilkS")
		)
		(fp_line
			(start 1.2954 0.5842)
			(end -1.2954 0.5842)
			(stroke
				(width 0.1524)
				(type default)
			)
			(layer "F.SilkS")
		)
		(fp_line
			(start -1.2954 -0.5842)
			(end 1.2954 -0.5842)
			(stroke
				(width 0.1524)
				(type default)
			)
			(layer "F.SilkS")
		)
		(fp_line
			(start 1.2954 -0.5842)
			(end 1.2954 0.5842)
			(stroke
				(width 0.1524)
				(type default)
			)
			(layer "F.SilkS")
		)
		(fp_line
			(start -0.8636 0.4572)
			(end -0.8636 0.4318)
			(stroke
				(width 0.1)
				(type default)
			)
			(layer "F.Fab")
		)
		(fp_line
			(start 0.8636 0.4572)
			(end -0.8636 0.4572)
			(stroke
				(width 0.1)
				(type default)
			)
			(layer "F.Fab")
		)
		(fp_line
			(start -0.8636 0.4318)
			(end -0.8636 0.4064)
			(stroke
				(width 0.1)
				(type default)
			)
			(layer "F.Fab")
		)
		(fp_line
			(start -1.1938 0.4064)
			(end -1.1938 -0.406654)
			(stroke
				(width 0.1)
				(type default)
			)
			(layer "F.Fab")
		)
		(fp_line
			(start -0.8636 0.4064)
			(end -1.1938 0.4064)
			(stroke
				(width 0.1)
				(type default)
			)
			(layer "F.Fab")
		)
		(fp_line
			(start 0.8636 0.4064)
			(end 0.8636 0.4572)
			(stroke
				(width 0.1)
				(type default)
			)
			(layer "F.Fab")
		)
		(fp_line
			(start 1.1938 0.4064)
			(end 0.8636 0.4064)
			(stroke
				(width 0.1)
				(type default)
			)
			(layer "F.Fab")
		)
		(fp_line
			(start -1.1938 -0.406654)
			(end -0.8636 -0.406654)
			(stroke
				(width 0.1)
				(type default)
			)
			(layer "F.Fab")
		)
		(fp_line
			(start -0.8636 -0.406654)
			(end -0.8636 -0.4572)
			(stroke
				(width 0.1)
				(type default)
			)
			(layer "F.Fab")
		)
		(fp_line
			(start 0.8636 -0.406654)
			(end 1.1938 -0.406654)
			(stroke
				(width 0.1)
				(type default)
			)
			(layer "F.Fab")
		)
		(fp_line
			(start 1.1938 -0.406654)
			(end 1.1938 0.4064)
			(stroke
				(width 0.1)
				(type default)
			)
			(layer "F.Fab")
		)
		(fp_line
			(start -0.8636 -0.4572)
			(end 0.8636 -0.4572)
			(stroke
				(width 0.1)
				(type default)
			)
			(layer "F.Fab")
		)
		(fp_line
			(start 0.8636 -0.4572)
			(end 0.8636 -0.406654)
			(stroke
				(width 0.1)
				(type default)
			)
			(layer "F.Fab")
		)
		(pad "1" smd rect
			(at -0.7366 0 180)
			(size 0.7112 0.8128)
			(layers "F.Cu" "F.Mask" "F.Paste")
			(net "P52V_HS1_GATE1_R")
		)
		(pad "2" smd rect
			(at 0.7366 0 180)
			(size 0.7112 0.8128)
			(layers "F.Cu" "F.Mask" "F.Paste")
			(net "P52V_HS1_GATE3")
		)
	)
	(footprint ""
		(layer "F.Cu")
		(at 266.586716 -33.341818 180)
		(property "Reference" "PR33"
			(at 0 0 180)
			(layer "F.SilkS")
			(hide yes)
			(effects
				(font
					(size 1.27 1.27)
				)
			)
		)
		(property "Value" ""
			(at 0 0 180)
			(layer "F.Fab")
			(effects
				(font
					(size 1.27 1.27)
				)
			)
		)
		(duplicate_pad_numbers_are_jumpers no)
		(fp_line
			(start 0.7874 0.4064)
			(end -0.7874 0.4064)
			(stroke
				(width 0.1524)
				(type default)
			)
			(layer "F.SilkS")
		)
		(fp_line
			(start 0.7874 -0.4064)
			(end 0.7874 0.4064)
			(stroke
				(width 0.1524)
				(type default)
			)
			(layer "F.SilkS")
		)
		(fp_line
			(start -0.7874 0.4064)
			(end -0.7874 -0.4064)
			(stroke
				(width 0.1524)
				(type default)
			)
			(layer "F.SilkS")
		)
		(fp_line
			(start -0.7874 -0.4064)
			(end 0.7874 -0.4064)
			(stroke
				(width 0.1524)
				(type default)
			)
			(layer "F.SilkS")
		)
		(fp_line
			(start 0.67945 0.3048)
			(end 0.120396 0.3048)
			(stroke
				(width 0.1)
				(type default)
			)
			(layer "F.Fab")
		)
		(fp_line
			(start 0.67945 -0.3048)
			(end 0.67945 0.3048)
			(stroke
				(width 0.1)
				(type default)
			)
			(layer "F.Fab")
		)
		(fp_line
			(start 0.12065 -0.2794)
			(end 0.12065 -0.3048)
			(stroke
				(width 0.1)
				(type default)
			)
			(layer "F.Fab")
		)
		(fp_line
			(start 0.12065 -0.3048)
			(end 0.67945 -0.3048)
			(stroke
				(width 0.1)
				(type default)
			)
			(layer "F.Fab")
		)
		(fp_line
			(start 0.120396 0.3048)
			(end 0.120396 0.2794)
			(stroke
				(width 0.1)
				(type default)
			)
			(layer "F.Fab")
		)
		(fp_line
			(start 0.120396 0.2794)
			(end -0.12065 0.2794)
			(stroke
				(width 0.1)
				(type default)
			)
			(layer "F.Fab")
		)
		(fp_line
			(start -0.12065 0.3048)
			(end -0.67945 0.3048)
			(stroke
				(width 0.1)
				(type default)
			)
			(layer "F.Fab")
		)
		(fp_line
			(start -0.12065 0.2794)
			(end -0.12065 0.3048)
			(stroke
				(width 0.1)
				(type default)
			)
			(layer "F.Fab")
		)
		(fp_line
			(start -0.12065 -0.2794)
			(end 0.12065 -0.2794)
			(stroke
				(width 0.1)
				(type default)
			)
			(layer "F.Fab")
		)
		(fp_line
			(start -0.12065 -0.305054)
			(end -0.12065 -0.2794)
			(stroke
				(width 0.1)
				(type default)
			)
			(layer "F.Fab")
		)
		(fp_line
			(start -0.67945 0.3048)
			(end -0.67945 -0.305054)
			(stroke
				(width 0.1)
				(type default)
			)
			(layer "F.Fab")
		)
		(fp_line
			(start -0.67945 -0.305054)
			(end -0.12065 -0.305054)
			(stroke
				(width 0.1)
				(type default)
			)
			(layer "F.Fab")
		)
		(pad "1" smd circle
			(at -0.40005 0 180)
			(size 0 0)
			(layers "F.Cu" "F.Mask" "F.Paste")
			(net "HS1_TMR1")
		)
		(pad "2" smd circle
			(at 0.40005 0 180)
			(size 0 0)
			(layers "F.Cu" "F.Mask" "F.Paste")
			(net "HS1_TMR2")
		)
	)
	(footprint ""
		(layer "F.Cu")
		(at 144.47012 -121.209816)
		(property "Reference" "PU2"
			(at -26.563066 -5.12953 0)
			(unlocked yes)
			(layer "F.SilkS")
			(effects
				(font
					(size 0.7874 0.5842)
					(thickness 0.1524)
				)
				(justify left)
			)
		)
		(property "Value" ""
			(at 0 0 0)
			(layer "F.Fab")
			(effects
				(font
					(size 1.27 1.27)
				)
			)
		)
		(duplicate_pad_numbers_are_jumpers no)
		(fp_line
			(start -26.519886 -4.299966)
			(end -26.519886 55.099966)
			(stroke
				(width 0.1524)
				(type default)
			)
			(layer "F.SilkS")
		)
		(fp_line
			(start -26.519886 55.099966)
			(end 11.279886 55.099966)
			(stroke
				(width 0.1524)
				(type default)
			)
			(layer "F.SilkS")
		)
		(fp_line
			(start -26.020014 -3.800094)
			(end -26.020014 54.59984)
			(stroke
				(width 0.1524)
				(type default)
			)
			(layer "F.SilkS")
		)
		(fp_line
			(start -26.020014 54.59984)
			(end 10.780014 54.59984)
			(stroke
				(width 0.1524)
				(type default)
			)
			(layer "F.SilkS")
		)
		(fp_line
			(start 10.780014 -3.800094)
			(end -26.020014 -3.800094)
			(stroke
				(width 0.1524)
				(type default)
			)
			(layer "F.SilkS")
		)
		(fp_line
			(start 10.780014 54.59984)
			(end 10.780014 -3.800094)
			(stroke
				(width 0.1524)
				(type default)
			)
			(layer "F.SilkS")
		)
		(fp_line
			(start 11.279886 -4.299966)
			(end -26.519886 -4.299966)
			(stroke
				(width 0.1524)
				(type default)
			)
			(layer "F.SilkS")
		)
		(fp_line
			(start 11.279886 55.099966)
			(end 11.279886 -4.299966)
			(stroke
				(width 0.1524)
				(type default)
			)
			(layer "F.SilkS")
		)
		(fp_poly
			(pts
				(xy 1.27 -7.44728) (xy -1.27 -7.44728) (xy 0 -4.90728)
			)
			(stroke
				(width 0)
				(type default)
			)
			(fill yes)
			(layer "F.SilkS")
		)
		(fp_line
			(start -26.020014 -3.800094)
			(end -26.020014 54.59984)
			(stroke
				(width 0.1)
				(type default)
			)
			(layer "F.Fab")
		)
		(fp_line
			(start -26.020014 54.59984)
			(end 10.780014 54.59984)
			(stroke
				(width 0.1)
				(type default)
			)
			(layer "F.Fab")
		)
		(fp_line
			(start 10.780014 -3.800094)
			(end -26.020014 -3.800094)
			(stroke
				(width 0.1)
				(type default)
			)
			(layer "F.Fab")
		)
		(fp_line
			(start 10.780014 54.59984)
			(end 10.780014 -3.800094)
			(stroke
				(width 0.1)
				(type default)
			)
			(layer "F.Fab")
		)
		(fp_poly
			(pts
				(xy 1.27 -7.44728) (xy -1.27 -7.44728) (xy 0 -4.90728)
			)
			(stroke
				(width 0)
				(type default)
			)
			(fill yes)
			(layer "F.Fab")
		)
		(pad "1" thru_hole rect
			(at 0 0 270)
			(size 2.3622 2.3622)
			(drill 1.6002)
			(layers "*.Cu" "*.Mask")
			(remove_unused_layers no)
			(net "P52V_HS_FILTER")
			(clearance -0.127)
			(padstack
				(mode front_inner_back)
				(layer "Inner"
					(shape circle)
					(size 2.3622 2.3622)
					(clearance -0.127)
				)
				(layer "B.Cu"
					(shape rect)
					(size 2.3622 2.3622)
					(clearance -0.127)
				)
			)
		)
		(pad "2" thru_hole circle
			(at -7.62 0 270)
			(size 2.3622 2.3622)
			(drill 1.6002)
			(layers "*.Cu" "*.Mask")
			(remove_unused_layers no)
			(net "BRICK_P12V0_ON_OFF_R")
			(clearance -0.127)
		)
		(pad "3" thru_hole circle
			(at -15.24 0 270)
			(size 2.3622 2.3622)
			(drill 1.6002)
			(layers "*.Cu" "*.Mask")
			(remove_unused_layers no)
			(net "GND")
			(clearance -0.127)
		)
		(pad "4" thru_hole circle
			(at -19.05 50.8 270)
			(size 3.1242 3.1242)
			(drill 2.1082)
			(layers "*.Cu" "*.Mask")
			(remove_unused_layers no)
			(net "GND")
			(clearance -0.254)
		)
		(pad "5" thru_hole circle
			(at -15.24 50.8 270)
			(size 3.1242 3.1242)
			(drill 2.1082)
			(layers "*.Cu" "*.Mask")
			(remove_unused_layers no)
			(net "GND")
			(clearance -0.254)
		)
		(pad "6" thru_hole circle
			(at 0 50.8 270)
			(size 3.1242 3.1242)
			(drill 2.1082)
			(layers "*.Cu" "*.Mask")
			(remove_unused_layers no)
			(net "P12V_BRICK")
			(clearance -0.254)
		)
		(pad "7" thru_hole circle
			(at 3.81 50.8 270)
			(size 3.1242 3.1242)
			(drill 2.1082)
			(layers "*.Cu" "*.Mask")
			(remove_unused_layers no)
			(net "P12V_BRICK")
			(clearance -0.254)
		)
		(pad "8" thru_hole circle
			(at -13.619988 53.34 270)
			(size 1.3208 1.3208)
			(drill 0.9144)
			(layers "*.Cu" "*.Mask")
			(remove_unused_layers no)
			(net "P12V_BRICK0_PWRGD")
			(clearance 0.0508)
			(thermal_gap 0.0508)
		)
		(pad "9" thru_hole circle
			(at -11.619992 53.34 270)
			(size 1.3208 1.3208)
			(drill 0.9144)
			(layers "*.Cu" "*.Mask")
			(remove_unused_layers no)
			(net "P12V_MB0_SENSE-")
			(clearance 0.0508)
			(thermal_gap 0.0508)
		)
		(pad "10" thru_hole circle
			(at -9.619996 53.34 270)
			(size 1.3208 1.3208)
			(drill 0.9144)
			(layers "*.Cu" "*.Mask")
			(remove_unused_layers no)
			(net "SMB_BRICK0_SDA")
			(clearance 0.0508)
			(thermal_gap 0.0508)
		)
		(pad "11" thru_hole circle
			(at -7.62 53.34 270)
			(size 1.3208 1.3208)
			(drill 0.9144)
			(layers "*.Cu" "*.Mask")
			(remove_unused_layers no)
			(net "SMB_BRICK0_ALERT")
			(clearance 0.0508)
			(thermal_gap 0.0508)
		)
		(pad "12" thru_hole circle
			(at -5.620004 53.34 270)
			(size 1.3208 1.3208)
			(drill 0.9144)
			(layers "*.Cu" "*.Mask")
			(remove_unused_layers no)
			(net "SMB_BRICK0_SCL")
			(clearance 0.0508)
			(thermal_gap 0.0508)
		)
		(pad "13" thru_hole circle
			(at -3.620008 53.34 270)
			(size 1.3208 1.3208)
			(drill 0.9144)
			(layers "*.Cu" "*.Mask")
			(remove_unused_layers no)
			(net "BRICK0_PMBADD")
			(clearance 0.0508)
			(thermal_gap 0.0508)
		)
		(pad "14" thru_hole circle
			(at -1.620012 53.34 270)
			(size 1.3208 1.3208)
			(drill 0.9144)
			(layers "*.Cu" "*.Mask")
			(remove_unused_layers no)
			(net "P12V_MB0_SENSE+")
			(clearance 0.0508)
			(thermal_gap 0.0508)
		)
	)
	(footprint ""
		(layer "F.Cu")
		(at 69.097906 -130.175)
		(property "Reference" "PC79"
			(at 0 0 0)
			(layer "F.SilkS")
			(hide yes)
			(effects
				(font
					(size 1.27 1.27)
				)
			)
		)
		(property "Value" ""
			(at 0 0 0)
			(layer "F.Fab")
			(effects
				(font
					(size 1.27 1.27)
				)
			)
		)
		(duplicate_pad_numbers_are_jumpers no)
		(fp_line
			(start -2.2098 -0.9398)
			(end 2.2098 -0.9398)
			(stroke
				(width 0.1524)
				(type default)
			)
			(layer "F.SilkS")
		)
		(fp_line
			(start -2.2098 0.9398)
			(end -2.2098 -0.9398)
			(stroke
				(width 0.1524)
				(type default)
			)
			(layer "F.SilkS")
		)
		(fp_line
			(start 2.2098 -0.9398)
			(end 2.2098 0.9398)
			(stroke
				(width 0.1524)
				(type default)
			)
			(layer "F.SilkS")
		)
		(fp_line
			(start 2.2098 0.9398)
			(end -2.2098 0.9398)
			(stroke
				(width 0.1524)
				(type default)
			)
			(layer "F.SilkS")
		)
		(fp_line
			(start -1.700022 -0.899922)
			(end 1.700022 -0.899922)
			(stroke
				(width 0.1)
				(type default)
			)
			(layer "F.Fab")
		)
		(fp_line
			(start -1.700022 0.899922)
			(end -1.700022 -0.899922)
			(stroke
				(width 0.1)
				(type default)
			)
			(layer "F.Fab")
		)
		(fp_line
			(start 1.700022 -0.899922)
			(end 1.700022 0.899922)
			(stroke
				(width 0.1)
				(type default)
			)
			(layer "F.Fab")
		)
		(fp_line
			(start 1.700022 0.899922)
			(end -1.700022 0.899922)
			(stroke
				(width 0.1)
				(type default)
			)
			(layer "F.Fab")
		)
		(pad "1" smd rect
			(at -1.4732 0 180)
			(size 1.1684 1.5748)
			(layers "F.Cu" "F.Mask" "F.Paste")
			(net "P52V_HS_FILTER")
		)
		(pad "2" smd rect
			(at 1.4732 0 180)
			(size 1.1684 1.5748)
			(layers "F.Cu" "F.Mask" "F.Paste")
			(net "GND")
		)
	)
	(footprint ""
		(layer "F.Cu")
		(at 211.469986 -37.949632 -90)
		(property "Reference" "J1"
			(at -7.489698 -41.895014 0)
			(unlocked yes)
			(layer "F.SilkS")
			(effects
				(font
					(size 0.7874 0.5842)
					(thickness 0.1524)
				)
				(justify left)
			)
		)
		(property "Value" ""
			(at 0 0 270)
			(layer "F.Fab")
			(effects
				(font
					(size 1.27 1.27)
				)
			)
		)
		(duplicate_pad_numbers_are_jumpers no)
		(fp_line
			(start -6.469888 48.33493)
			(end -6.469888 -43.25493)
			(stroke
				(width 0.1524)
				(type default)
			)
			(layer "F.SilkS")
		)
		(fp_line
			(start 14.109954 48.33493)
			(end -6.469888 48.33493)
			(stroke
				(width 0.1524)
				(type default)
			)
			(layer "F.SilkS")
		)
		(fp_line
			(start -3.469894 45.334936)
			(end -1.905 45.334936)
			(stroke
				(width 0.1524)
				(type default)
			)
			(layer "F.SilkS")
		)
		(fp_line
			(start 1.905 45.334936)
			(end 11.10996 45.334936)
			(stroke
				(width 0.1524)
				(type default)
			)
			(layer "F.SilkS")
		)
		(fp_line
			(start 11.10996 45.334936)
			(end 11.10996 -40.254936)
			(stroke
				(width 0.1524)
				(type default)
			)
			(layer "F.SilkS")
		)
		(fp_line
			(start -3.469894 -40.254936)
			(end -3.469894 45.334936)
			(stroke
				(width 0.1524)
				(type default)
			)
			(layer "F.SilkS")
		)
		(fp_line
			(start -1.9304 -40.254936)
			(end -3.469894 -40.254936)
			(stroke
				(width 0.1524)
				(type default)
			)
			(layer "F.SilkS")
		)
		(fp_line
			(start 11.10996 -40.254936)
			(end 1.9304 -40.254936)
			(stroke
				(width 0.1524)
				(type default)
			)
			(layer "F.SilkS")
		)
		(fp_line
			(start -6.469888 -43.25493)
			(end 14.109954 -43.25493)
			(stroke
				(width 0.1524)
				(type default)
			)
			(layer "F.SilkS")
		)
		(fp_line
			(start 14.109954 -43.25493)
			(end 14.109954 48.33493)
			(stroke
				(width 0.1524)
				(type default)
			)
			(layer "F.SilkS")
		)
		(fp_poly
			(pts
				(xy -4.953 -0.508) (xy -4.953 0.508) (xy -3.937 0)
			)
			(stroke
				(width 0)
				(type default)
			)
			(fill yes)
			(layer "F.SilkS")
		)
		(fp_line
			(start -6.469888 48.33493)
			(end -6.469888 -43.25493)
			(stroke
				(width 0.1524)
				(type default)
			)
			(layer "B.SilkS")
		)
		(fp_line
			(start 14.109954 48.33493)
			(end -6.469888 48.33493)
			(stroke
				(width 0.1524)
				(type default)
			)
			(layer "B.SilkS")
		)
		(fp_line
			(start -6.469888 -43.25493)
			(end 14.109954 -43.25493)
			(stroke
				(width 0.1524)
				(type default)
			)
			(layer "B.SilkS")
		)
		(fp_line
			(start 14.109954 -43.25493)
			(end 14.109954 48.33493)
			(stroke
				(width 0.1524)
				(type default)
			)
			(layer "B.SilkS")
		)
		(fp_line
			(start -6.469888 48.33493)
			(end -6.469888 -43.25493)
			(stroke
				(width 0.1)
				(type default)
			)
			(layer "B.Fab")
		)
		(fp_line
			(start 14.109954 48.33493)
			(end -6.469888 48.33493)
			(stroke
				(width 0.1)
				(type default)
			)
			(layer "B.Fab")
		)
		(fp_line
			(start -6.469888 -43.25493)
			(end 14.109954 -43.25493)
			(stroke
				(width 0.1)
				(type default)
			)
			(layer "B.Fab")
		)
		(fp_line
			(start 14.109954 -43.25493)
			(end 14.109954 48.33493)
			(stroke
				(width 0.1)
				(type default)
			)
			(layer "B.Fab")
		)
		(fp_line
			(start -3.469894 45.334936)
			(end 11.10996 45.334936)
			(stroke
				(width 0.1)
				(type default)
			)
			(layer "F.Fab")
		)
		(fp_line
			(start 11.10996 45.334936)
			(end 11.10996 -40.254936)
			(stroke
				(width 0.1)
				(type default)
			)
			(layer "F.Fab")
		)
		(fp_line
			(start -3.469894 -40.254936)
			(end -3.469894 45.334936)
			(stroke
				(width 0.1)
				(type default)
			)
			(layer "F.Fab")
		)
		(fp_line
			(start 11.10996 -40.254936)
			(end -3.469894 -40.254936)
			(stroke
				(width 0.1)
				(type default)
			)
			(layer "F.Fab")
		)
		(fp_poly
			(pts
				(xy -4.953 -0.508) (xy -4.953 0.508) (xy -3.937 0)
			)
			(stroke
				(width 0)
				(type default)
			)
			(fill yes)
			(layer "F.Fab")
		)
		(fp_text user "PRESS-FIT"
			(at 12.581382 7.507986 0)
			(unlocked yes)
			(layer "F.SilkS")
			(effects
				(font
					(size 1.905 1.4224)
					(thickness 0.1524)
				)
				(justify left)
			)
		)
		(fp_text user "PRESS-FIT"
			(at 12.200382 -2.144014 0)
			(unlocked yes)
			(layer "B.SilkS")
			(effects
				(font
					(size 1.905 1.4224)
					(thickness 0.1524)
				)
				(justify left mirror)
			)
		)
		(fp_text user "PRESS-FIT"
			(at 12.61745 10.8966 180)
			(unlocked yes)
			(layer "B.Fab")
			(effects
				(font
					(size 1.905 1.4224)
					(thickness 0.1524)
				)
				(justify left mirror)
			)
		)
		(fp_text user "PRESS-FIT"
			(at 12.61745 -5.7404 180)
			(unlocked yes)
			(layer "F.Fab")
			(effects
				(font
					(size 1.905 1.4224)
					(thickness 0.1524)
				)
				(justify left)
			)
		)
		(pad "" np_thru_hole circle
			(at 0 -37.465 270)
			(size 0 0)
			(drill 3.2004)
			(layers "*.Cu" "*.Mask")
			(clearance 0)
		)
		(pad "" np_thru_hole circle
			(at 0 42.545 270)
			(size 0 0)
			(drill 3.2004)
			(layers "*.Cu" "*.Mask")
			(clearance 0)
		)
		(pad "A1" thru_hole rect
			(at 0 0 270)
			(size 1.52781 1.52781)
			(drill 1.01981)
			(layers "*.Cu" "*.Mask")
			(remove_unused_layers no)
			(net "TP_J1_A1")
			(clearance 0)
			(padstack
				(mode front_inner_back)
				(layer "Inner"
					(shape circle)
					(size 1.52781 1.52781)
					(clearance 0)
				)
				(layer "B.Cu"
					(shape rect)
					(size 1.52781 1.52781)
					(clearance 0)
				)
			)
		)
		(pad "A2" thru_hole circle
			(at 0 2.54 270)
			(size 1.52781 1.52781)
			(drill 1.01981)
			(layers "*.Cu" "*.Mask")
			(remove_unused_layers no)
			(net "FM_AC_PWR_CYCLE_R_N")
			(clearance 0)
		)
		(pad "A3" thru_hole circle
			(at 0 5.08 270)
			(size 1.52781 1.52781)
			(drill 1.01981)
			(layers "*.Cu" "*.Mask")
			(remove_unused_layers no)
			(net "P3V3_AUX_SCALED")
			(clearance 0)
		)
		(pad "B1" thru_hole circle
			(at 2.54 0 270)
			(size 1.52781 1.52781)
			(drill 1.01981)
			(layers "*.Cu" "*.Mask")
			(remove_unused_layers no)
			(net "RST_SMB_PDB_R_N")
			(clearance 0)
		)
		(pad "B2" thru_hole circle
			(at 2.54 2.54 270)
			(size 1.52781 1.52781)
			(drill 1.01981)
			(layers "*.Cu" "*.Mask")
			(remove_unused_layers no)
			(net "PWRGD_P3V3_AUX_MB_R")
			(clearance 0)
		)
		(pad "B3" thru_hole circle
			(at 2.54 5.08 270)
			(size 1.52781 1.52781)
			(drill 1.01981)
			(layers "*.Cu" "*.Mask")
			(remove_unused_layers no)
			(net "GND")
			(clearance 0)
		)
		(pad "C1" thru_hole circle
			(at 5.08 0 270)
			(size 1.52781 1.52781)
			(drill 1.01981)
			(layers "*.Cu" "*.Mask")
			(remove_unused_layers no)
			(net "SMB_MB_PDB_R_SCL")
			(clearance 0)
		)
		(pad "C2" thru_hole circle
			(at 5.08 2.54 270)
			(size 1.52781 1.52781)
			(drill 1.01981)
			(layers "*.Cu" "*.Mask")
			(remove_unused_layers no)
			(net "SMB_MB_PDB_R_SDA")
			(clearance 0)
		)
		(pad "C3" thru_hole circle
			(at 5.08 5.08 270)
			(size 1.52781 1.52781)
			(drill 1.01981)
			(layers "*.Cu" "*.Mask")
			(remove_unused_layers no)
			(net "PWRGD_GPU_HSC_BUF_R")
			(clearance 0)
		)
		(pad "D1" thru_hole circle
			(at 7.62 0 270)
			(size 1.52781 1.52781)
			(drill 1.01981)
			(layers "*.Cu" "*.Mask")
			(remove_unused_layers no)
			(net "FAN_PWR_R_EN")
			(clearance 0)
		)
		(pad "D2" thru_hole circle
			(at 7.62 2.54 270)
			(size 1.52781 1.52781)
			(drill 1.01981)
			(layers "*.Cu" "*.Mask")
			(remove_unused_layers no)
			(net "GPU_HSC_R_EN")
			(clearance 0)
		)
		(pad "D3" thru_hole circle
			(at 7.62 5.08 270)
			(size 1.52781 1.52781)
			(drill 1.01981)
			(layers "*.Cu" "*.Mask")
			(remove_unused_layers no)
			(net "P12V_BRICK_PWRGD_R_N")
			(clearance 0)
		)
		(pad "P1_1" thru_hole circle
			(at 7.62 -25.4 270)
			(size 1.52781 1.52781)
			(drill 1.01981)
			(layers "*.Cu" "*.Mask")
			(remove_unused_layers no)
			(net "GND")
			(clearance 0)
		)
		(pad "P1_2" thru_hole circle
			(at 5.08 -25.4 270)
			(size 1.52781 1.52781)
			(drill 1.01981)
			(layers "*.Cu" "*.Mask")
			(remove_unused_layers no)
			(net "GND")
			(clearance 0)
		)
		(pad "P1_3" thru_hole circle
			(at 2.54 -25.4 270)
			(size 1.52781 1.52781)
			(drill 1.01981)
			(layers "*.Cu" "*.Mask")
			(remove_unused_layers no)
			(net "GND")
			(clearance 0)
		)
		(pad "P1_4" thru_hole circle
			(at 0 -25.4 270)
			(size 1.52781 1.52781)
			(drill 1.01981)
			(layers "*.Cu" "*.Mask")
			(remove_unused_layers no)
			(net "GND")
			(clearance 0)
		)
		(pad "P1_5" thru_hole circle
			(at 7.62 -22.86 270)
			(size 1.52781 1.52781)
			(drill 1.01981)
			(layers "*.Cu" "*.Mask")
			(remove_unused_layers no)
			(net "GND")
			(clearance 0)
		)
		(pad "P1_6" thru_hole circle
			(at 5.08 -22.86 270)
			(size 1.52781 1.52781)
			(drill 1.01981)
			(layers "*.Cu" "*.Mask")
			(remove_unused_layers no)
			(net "GND")
			(clearance 0)
		)
		(pad "P1_7" thru_hole circle
			(at 2.54 -22.86 270)
			(size 1.52781 1.52781)
			(drill 1.01981)
			(layers "*.Cu" "*.Mask")
			(remove_unused_layers no)
			(net "GND")
			(clearance 0)
		)
		(pad "P1_8" thru_hole circle
			(at 0 -22.86 270)
			(size 1.52781 1.52781)
			(drill 1.01981)
			(layers "*.Cu" "*.Mask")
			(remove_unused_layers no)
			(net "GND")
			(clearance 0)
		)
		(pad "P2_1" thru_hole circle
			(at 7.62 -16.51 270)
			(size 1.52781 1.52781)
			(drill 1.01981)
			(layers "*.Cu" "*.Mask")
			(remove_unused_layers no)
			(net "GND")
			(clearance 0)
		)
		(pad "P2_2" thru_hole circle
			(at 5.08 -16.51 270)
			(size 1.52781 1.52781)
			(drill 1.01981)
			(layers "*.Cu" "*.Mask")
			(remove_unused_layers no)
			(net "GND")
			(clearance 0)
		)
		(pad "P2_3" thru_hole circle
			(at 2.54 -16.51 270)
			(size 1.52781 1.52781)
			(drill 1.01981)
			(layers "*.Cu" "*.Mask")
			(remove_unused_layers no)
			(net "GND")
			(clearance 0)
		)
		(pad "P2_4" thru_hole circle
			(at 0 -16.51 270)
			(size 1.52781 1.52781)
			(drill 1.01981)
			(layers "*.Cu" "*.Mask")
			(remove_unused_layers no)
			(net "GND")
			(clearance 0)
		)
		(pad "P2_5" thru_hole circle
			(at 7.62 -13.97 270)
			(size 1.52781 1.52781)
			(drill 1.01981)
			(layers "*.Cu" "*.Mask")
			(remove_unused_layers no)
			(net "GND")
			(clearance 0)
		)
		(pad "P2_6" thru_hole circle
			(at 5.08 -13.97 270)
			(size 1.52781 1.52781)
			(drill 1.01981)
			(layers "*.Cu" "*.Mask")
			(remove_unused_layers no)
			(net "GND")
			(clearance 0)
		)
		(pad "P2_7" thru_hole circle
			(at 2.54 -13.97 270)
			(size 1.52781 1.52781)
			(drill 1.01981)
			(layers "*.Cu" "*.Mask")
			(remove_unused_layers no)
			(net "GND")
			(clearance 0)
		)
		(pad "P2_8" thru_hole circle
			(at 0 -13.97 270)
			(size 1.52781 1.52781)
			(drill 1.01981)
			(layers "*.Cu" "*.Mask")
			(remove_unused_layers no)
			(net "GND")
			(clearance 0)
		)
		(pad "P3_1" thru_hole circle
			(at 7.62 -7.62 270)
			(size 1.52781 1.52781)
			(drill 1.01981)
			(layers "*.Cu" "*.Mask")
			(remove_unused_layers no)
			(net "GND")
			(clearance 0)
		)
		(pad "P3_2" thru_hole circle
			(at 5.08 -7.62 270)
			(size 1.52781 1.52781)
			(drill 1.01981)
			(layers "*.Cu" "*.Mask")
			(remove_unused_layers no)
			(net "GND")
			(clearance 0)
		)
		(pad "P3_3" thru_hole circle
			(at 2.54 -7.62 270)
			(size 1.52781 1.52781)
			(drill 1.01981)
			(layers "*.Cu" "*.Mask")
			(remove_unused_layers no)
			(net "GND")
			(clearance 0)
		)
		(pad "P3_4" thru_hole circle
			(at 0 -7.62 270)
			(size 1.52781 1.52781)
			(drill 1.01981)
			(layers "*.Cu" "*.Mask")
			(remove_unused_layers no)
			(net "GND")
			(clearance 0)
		)
		(pad "P3_5" thru_hole circle
			(at 7.62 -5.08 270)
			(size 1.52781 1.52781)
			(drill 1.01981)
			(layers "*.Cu" "*.Mask")
			(remove_unused_layers no)
			(net "GND")
			(clearance 0)
		)
		(pad "P3_6" thru_hole circle
			(at 5.08 -5.08 270)
			(size 1.52781 1.52781)
			(drill 1.01981)
			(layers "*.Cu" "*.Mask")
			(remove_unused_layers no)
			(net "GND")
			(clearance 0)
		)
		(pad "P3_7" thru_hole circle
			(at 2.54 -5.08 270)
			(size 1.52781 1.52781)
			(drill 1.01981)
			(layers "*.Cu" "*.Mask")
			(remove_unused_layers no)
			(net "GND")
			(clearance 0)
		)
		(pad "P3_8" thru_hole circle
			(at 0 -5.08 270)
			(size 1.52781 1.52781)
			(drill 1.01981)
			(layers "*.Cu" "*.Mask")
			(remove_unused_layers no)
			(net "GND")
			(clearance 0)
		)
		(pad "P4_1" thru_hole circle
			(at 7.62 10.16 270)
			(size 1.52781 1.52781)
			(drill 1.01981)
			(layers "*.Cu" "*.Mask")
			(remove_unused_layers no)
			(net "P12V_BRICK")
			(clearance 0)
		)
		(pad "P4_2" thru_hole circle
			(at 5.08 10.16 270)
			(size 1.52781 1.52781)
			(drill 1.01981)
			(layers "*.Cu" "*.Mask")
			(remove_unused_layers no)
			(net "P12V_BRICK")
			(clearance 0)
		)
		(pad "P4_3" thru_hole circle
			(at 2.54 10.16 270)
			(size 1.52781 1.52781)
			(drill 1.01981)
			(layers "*.Cu" "*.Mask")
			(remove_unused_layers no)
			(net "P12V_BRICK")
			(clearance 0)
		)
		(pad "P4_4" thru_hole circle
			(at 0 10.16 270)
			(size 1.52781 1.52781)
			(drill 1.01981)
			(layers "*.Cu" "*.Mask")
			(remove_unused_layers no)
			(net "P12V_BRICK")
			(clearance 0)
		)
		(pad "P4_5" thru_hole circle
			(at 7.62 12.7 270)
			(size 1.52781 1.52781)
			(drill 1.01981)
			(layers "*.Cu" "*.Mask")
			(remove_unused_layers no)
			(net "P12V_BRICK")
			(clearance 0)
		)
		(pad "P4_6" thru_hole circle
			(at 5.08 12.7 270)
			(size 1.52781 1.52781)
			(drill 1.01981)
			(layers "*.Cu" "*.Mask")
			(remove_unused_layers no)
			(net "P12V_BRICK")
			(clearance 0)
		)
		(pad "P4_7" thru_hole circle
			(at 2.54 12.7 270)
			(size 1.52781 1.52781)
			(drill 1.01981)
			(layers "*.Cu" "*.Mask")
			(remove_unused_layers no)
			(net "P12V_BRICK")
			(clearance 0)
		)
		(pad "P4_8" thru_hole circle
			(at 0 12.7 270)
			(size 1.52781 1.52781)
			(drill 1.01981)
			(layers "*.Cu" "*.Mask")
			(remove_unused_layers no)
			(net "P12V_BRICK")
			(clearance 0)
		)
		(pad "P5_1" thru_hole circle
			(at 7.62 19.05 270)
			(size 1.52781 1.52781)
			(drill 1.01981)
			(layers "*.Cu" "*.Mask")
			(remove_unused_layers no)
			(net "P12V_BRICK")
			(clearance 0)
		)
		(pad "P5_2" thru_hole circle
			(at 5.08 19.05 270)
			(size 1.52781 1.52781)
			(drill 1.01981)
			(layers "*.Cu" "*.Mask")
			(remove_unused_layers no)
			(net "P12V_BRICK")
			(clearance 0)
		)
		(pad "P5_3" thru_hole circle
			(at 2.54 19.05 270)
			(size 1.52781 1.52781)
			(drill 1.01981)
			(layers "*.Cu" "*.Mask")
			(remove_unused_layers no)
			(net "P12V_BRICK")
			(clearance 0)
		)
		(pad "P5_4" thru_hole circle
			(at 0 19.05 270)
			(size 1.52781 1.52781)
			(drill 1.01981)
			(layers "*.Cu" "*.Mask")
			(remove_unused_layers no)
			(net "P12V_BRICK")
			(clearance 0)
		)
		(pad "P5_5" thru_hole circle
			(at 7.62 21.59 270)
			(size 1.52781 1.52781)
			(drill 1.01981)
			(layers "*.Cu" "*.Mask")
			(remove_unused_layers no)
			(net "P12V_BRICK")
			(clearance 0)
		)
		(pad "P5_6" thru_hole circle
			(at 5.08 21.59 270)
			(size 1.52781 1.52781)
			(drill 1.01981)
			(layers "*.Cu" "*.Mask")
			(remove_unused_layers no)
			(net "P12V_BRICK")
			(clearance 0)
		)
		(pad "P5_7" thru_hole circle
			(at 2.54 21.59 270)
			(size 1.52781 1.52781)
			(drill 1.01981)
			(layers "*.Cu" "*.Mask")
			(remove_unused_layers no)
			(net "P12V_BRICK")
			(clearance 0)
		)
		(pad "P5_8" thru_hole circle
			(at 0 21.59 270)
			(size 1.52781 1.52781)
			(drill 1.01981)
			(layers "*.Cu" "*.Mask")
			(remove_unused_layers no)
			(net "P12V_BRICK")
			(clearance 0)
		)
		(pad "P6_1" thru_hole circle
			(at 7.62 27.94 270)
			(size 1.52781 1.52781)
			(drill 1.01981)
			(layers "*.Cu" "*.Mask")
			(remove_unused_layers no)
			(net "P12V_BRICK")
			(clearance 0)
		)
		(pad "P6_2" thru_hole circle
			(at 5.08 27.94 270)
			(size 1.52781 1.52781)
			(drill 1.01981)
			(layers "*.Cu" "*.Mask")
			(remove_unused_layers no)
			(net "P12V_BRICK")
			(clearance 0)
		)
		(pad "P6_3" thru_hole circle
			(at 2.54 27.94 270)
			(size 1.52781 1.52781)
			(drill 1.01981)
			(layers "*.Cu" "*.Mask")
			(remove_unused_layers no)
			(net "P12V_BRICK")
			(clearance 0)
		)
		(pad "P6_4" thru_hole circle
			(at 0 27.94 270)
			(size 1.52781 1.52781)
			(drill 1.01981)
			(layers "*.Cu" "*.Mask")
			(remove_unused_layers no)
			(net "P12V_BRICK")
			(clearance 0)
		)
		(pad "P6_5" thru_hole circle
			(at 7.62 30.48 270)
			(size 1.52781 1.52781)
			(drill 1.01981)
			(layers "*.Cu" "*.Mask")
			(remove_unused_layers no)
			(net "P12V_BRICK")
			(clearance 0)
		)
		(pad "P6_6" thru_hole circle
			(at 5.08 30.48 270)
			(size 1.52781 1.52781)
			(drill 1.01981)
			(layers "*.Cu" "*.Mask")
			(remove_unused_layers no)
			(net "P12V_BRICK")
			(clearance 0)
		)
		(pad "P6_7" thru_hole circle
			(at 2.54 30.48 270)
			(size 1.52781 1.52781)
			(drill 1.01981)
			(layers "*.Cu" "*.Mask")
			(remove_unused_layers no)
			(net "P12V_BRICK")
			(clearance 0)
		)
		(pad "P6_8" thru_hole circle
			(at 0 30.48 270)
			(size 1.52781 1.52781)
			(drill 1.01981)
			(layers "*.Cu" "*.Mask")
			(remove_unused_layers no)
			(net "P12V_BRICK")
			(clearance 0)
		)
		(zone
			(layers "F.Cu" "B.Cu" "In1.Cu" "In2.Cu" "In3.Cu" "In4.Cu" "In5.Cu" "In6.Cu"
				"In7.Cu" "In8.Cu"
			)
			(hatch none 0.5)
			(connect_pads
				(clearance 0)
			)
			(min_thickness 0.25)
			(keepout
				(tracks not_allowed)
				(vias allowed)
				(pads allowed)
				(copperpour not_allowed)
				(footprints allowed)
			)
			(placement
				(enabled no)
				(sheetname "")
			)
			(fill
				(thermal_gap 0.5)
				(thermal_bridge_width 0.5)
				(island_removal_mode 0)
			)
			(polygon
				(pts
					(arc
						(start 172.557186 -37.949632)
						(mid 165.292786 -37.949632)
						(end 172.557186 -37.949632)
					)
				)
			)
		)
		(zone
			(layers "F.Cu" "B.Cu" "In1.Cu" "In2.Cu" "In3.Cu" "In4.Cu" "In5.Cu" "In6.Cu"
				"In7.Cu" "In8.Cu"
			)
			(hatch none 0.5)
			(connect_pads
				(clearance 0)
			)
			(min_thickness 0.25)
			(keepout
				(tracks not_allowed)
				(vias allowed)
				(pads allowed)
				(copperpour not_allowed)
				(footprints allowed)
			)
			(placement
				(enabled no)
				(sheetname "")
			)
			(fill
				(thermal_gap 0.5)
				(thermal_bridge_width 0.5)
				(island_removal_mode 0)
			)
			(polygon
				(pts
					(arc
						(start 252.567186 -37.949632)
						(mid 245.302786 -37.949632)
						(end 252.567186 -37.949632)
					)
				)
			)
		)
		(zone
			(layer "B.Cu")
			(hatch none 0.5)
			(connect_pads
				(clearance 0)
			)
			(min_thickness 0.25)
			(keepout
				(tracks allowed)
				(vias not_allowed)
				(pads allowed)
				(copperpour not_allowed)
				(footprints allowed)
			)
			(placement
				(enabled no)
				(sheetname "")
			)
			(fill
				(thermal_gap 0.5)
				(thermal_bridge_width 0.5)
				(island_removal_mode 0)
			)
			(polygon
				(pts
					(xy 180.162708 -38.77691) (xy 180.162708 -29.502354) (xy 237.697264 -29.502354) (xy 237.697264 -38.77691)
				)
			)
		)
	)
	(footprint ""
		(layer "F.Cu")
		(at 279.019 -42.799 180)
		(property "Reference" "PC562"
			(at 0 0 180)
			(layer "F.SilkS")
			(hide yes)
			(effects
				(font
					(size 1.27 1.27)
				)
			)
		)
		(property "Value" ""
			(at 0 0 180)
			(layer "F.Fab")
			(effects
				(font
					(size 1.27 1.27)
				)
			)
		)
		(duplicate_pad_numbers_are_jumpers no)
		(fp_line
			(start 1.2954 0.5842)
			(end -1.2954 0.5842)
			(stroke
				(width 0.1524)
				(type default)
			)
			(layer "F.SilkS")
		)
		(fp_line
			(start 1.2954 -0.5842)
			(end 1.2954 0.5842)
			(stroke
				(width 0.1524)
				(type default)
			)
			(layer "F.SilkS")
		)
		(fp_line
			(start -1.2954 0.5842)
			(end -1.2954 -0.5842)
			(stroke
				(width 0.1524)
				(type default)
			)
			(layer "F.SilkS")
		)
		(fp_line
			(start -1.2954 -0.5842)
			(end 1.2954 -0.5842)
			(stroke
				(width 0.1524)
				(type default)
			)
			(layer "F.SilkS")
		)
		(fp_line
			(start 1.1938 0.4064)
			(end 0.8636 0.4064)
			(stroke
				(width 0.1)
				(type default)
			)
			(layer "F.Fab")
		)
		(fp_line
			(start 1.1938 -0.4064)
			(end 1.1938 0.4064)
			(stroke
				(width 0.1)
				(type default)
			)
			(layer "F.Fab")
		)
		(fp_line
			(start 0.8636 0.4572)
			(end -0.8636 0.4572)
			(stroke
				(width 0.1)
				(type default)
			)
			(layer "F.Fab")
		)
		(fp_line
			(start 0.8636 0.4064)
			(end 0.8636 0.4572)
			(stroke
				(width 0.1)
				(type default)
			)
			(layer "F.Fab")
		)
		(fp_line
			(start 0.8636 -0.4064)
			(end 1.1938 -0.4064)
			(stroke
				(width 0.1)
				(type default)
			)
			(layer "F.Fab")
		)
		(fp_line
			(start 0.8636 -0.4572)
			(end 0.8636 -0.4064)
			(stroke
				(width 0.1)
				(type default)
			)
			(layer "F.Fab")
		)
		(fp_line
			(start -0.8636 0.4572)
			(end -0.8636 0.4064)
			(stroke
				(width 0.1)
				(type default)
			)
			(layer "F.Fab")
		)
		(fp_line
			(start -0.8636 0.4064)
			(end -1.1938 0.4064)
			(stroke
				(width 0.1)
				(type default)
			)
			(layer "F.Fab")
		)
		(fp_line
			(start -0.8636 -0.4064)
			(end -0.8636 -0.4572)
			(stroke
				(width 0.1)
				(type default)
			)
			(layer "F.Fab")
		)
		(fp_line
			(start -0.8636 -0.4572)
			(end 0.8636 -0.4572)
			(stroke
				(width 0.1)
				(type default)
			)
			(layer "F.Fab")
		)
		(fp_line
			(start -1.1938 0.4064)
			(end -1.1938 -0.4064)
			(stroke
				(width 0.1)
				(type default)
			)
			(layer "F.Fab")
		)
		(fp_line
			(start -1.1938 -0.4064)
			(end -0.8636 -0.4064)
			(stroke
				(width 0.1)
				(type default)
			)
			(layer "F.Fab")
		)
		(pad "1" smd rect
			(at -0.7366 0 90)
			(size 0.7112 0.8128)
			(layers "F.Cu" "F.Mask" "F.Paste")
			(net "P52V_HS1_VCAP")
		)
		(pad "2" smd rect
			(at 0.7366 0 90)
			(size 0.7112 0.8128)
			(layers "F.Cu" "F.Mask" "F.Paste")
			(net "GND_FIELD_SIGNAL")
		)
	)
	(footprint ""
		(layer "F.Cu")
		(at 149.098 -127.889)
		(property "Reference" "PC19"
			(at 0 0 0)
			(layer "F.SilkS")
			(hide yes)
			(effects
				(font
					(size 1.27 1.27)
				)
			)
		)
		(property "Value" ""
			(at 0 0 0)
			(layer "F.Fab")
			(effects
				(font
					(size 1.27 1.27)
				)
			)
		)
		(duplicate_pad_numbers_are_jumpers no)
		(fp_line
			(start -2.2098 -0.9398)
			(end 2.2098 -0.9398)
			(stroke
				(width 0.1524)
				(type default)
			)
			(layer "F.SilkS")
		)
		(fp_line
			(start -2.2098 0.9398)
			(end -2.2098 -0.9398)
			(stroke
				(width 0.1524)
				(type default)
			)
			(layer "F.SilkS")
		)
		(fp_line
			(start 2.2098 -0.9398)
			(end 2.2098 0.9398)
			(stroke
				(width 0.1524)
				(type default)
			)
			(layer "F.SilkS")
		)
		(fp_line
			(start 2.2098 0.9398)
			(end -2.2098 0.9398)
			(stroke
				(width 0.1524)
				(type default)
			)
			(layer "F.SilkS")
		)
		(fp_line
			(start -1.700022 -0.899922)
			(end 1.700022 -0.899922)
			(stroke
				(width 0.1)
				(type default)
			)
			(layer "F.Fab")
		)
		(fp_line
			(start -1.700022 0.899922)
			(end -1.700022 -0.899922)
			(stroke
				(width 0.1)
				(type default)
			)
			(layer "F.Fab")
		)
		(fp_line
			(start 1.700022 -0.899922)
			(end 1.700022 0.899922)
			(stroke
				(width 0.1)
				(type default)
			)
			(layer "F.Fab")
		)
		(fp_line
			(start 1.700022 0.899922)
			(end -1.700022 0.899922)
			(stroke
				(width 0.1)
				(type default)
			)
			(layer "F.Fab")
		)
		(pad "1" smd rect
			(at -1.4732 0 180)
			(size 1.1684 1.5748)
			(layers "F.Cu" "F.Mask" "F.Paste")
			(net "P52V_HS_FILTER")
		)
		(pad "2" smd rect
			(at 1.4732 0 180)
			(size 1.1684 1.5748)
			(layers "F.Cu" "F.Mask" "F.Paste")
			(net "GND")
		)
	)
	(footprint ""
		(layer "F.Cu")
		(at 21.02993 -122.48007 -90)
		(property "Reference" "J14"
			(at 6.17474 -8.43407 0)
			(unlocked yes)
			(layer "F.SilkS")
			(effects
				(font
					(size 0.7874 0.5842)
					(thickness 0.1524)
				)
				(justify left)
			)
		)
		(property "Value" ""
			(at 0 0 270)
			(layer "F.Fab")
			(effects
				(font
					(size 1.27 1.27)
				)
			)
		)
		(duplicate_pad_numbers_are_jumpers no)
		(fp_line
			(start -5.32511 21.299932)
			(end -5.32511 -10.500106)
			(stroke
				(width 0.1524)
				(type default)
			)
			(layer "F.SilkS")
		)
		(fp_line
			(start 5.32511 21.299932)
			(end -5.32511 21.299932)
			(stroke
				(width 0.1524)
				(type default)
			)
			(layer "F.SilkS")
		)
		(fp_line
			(start -5.32511 10.6299)
			(end 5.32511 10.6299)
			(stroke
				(width 0.1524)
				(type default)
			)
			(layer "F.SilkS")
		)
		(fp_line
			(start -5.32511 -10.500106)
			(end 5.32511 -10.500106)
			(stroke
				(width 0.1524)
				(type default)
			)
			(layer "F.SilkS")
		)
		(fp_line
			(start 5.32511 -10.500106)
			(end 5.32511 21.299932)
			(stroke
				(width 0.1524)
				(type default)
			)
			(layer "F.SilkS")
		)
		(fp_line
			(start -5.32511 21.299932)
			(end -5.32511 -10.500106)
			(stroke
				(width 0.1)
				(type default)
			)
			(layer "F.Fab")
		)
		(fp_line
			(start 5.32511 21.299932)
			(end -5.32511 21.299932)
			(stroke
				(width 0.1)
				(type default)
			)
			(layer "F.Fab")
		)
		(fp_line
			(start -5.32511 -10.500106)
			(end 5.32511 -10.500106)
			(stroke
				(width 0.1)
				(type default)
			)
			(layer "F.Fab")
		)
		(fp_line
			(start 5.32511 -10.500106)
			(end 5.32511 21.299932)
			(stroke
				(width 0.1)
				(type default)
			)
			(layer "F.Fab")
		)
		(pad "" np_thru_hole circle
			(at 0 -6.620002 270)
			(size 3.9624 3.9624)
			(drill 3.9624)
			(layers "*.Cu" "*.Mask")
			(clearance 0.381)
			(thermal_gap 0.381)
		)
		(pad "" np_thru_hole circle
			(at 0 0 270)
			(size 0 0)
			(drill 3.9624)
			(layers "*.Cu" "*.Mask")
			(clearance 0)
		)
		(pad "" np_thru_hole circle
			(at 0 5.62991 270)
			(size 3.9624 3.9624)
			(drill 3.9624)
			(layers "*.Cu" "*.Mask")
			(clearance 0.381)
			(thermal_gap 0.381)
		)
		(zone
			(layers "F.Cu" "B.Cu" "In1.Cu" "In2.Cu" "In3.Cu" "In4.Cu" "In5.Cu" "In6.Cu"
				"In7.Cu" "In8.Cu"
			)
			(hatch none 0.5)
			(connect_pads
				(clearance 0)
			)
			(min_thickness 0.25)
			(keepout
				(tracks not_allowed)
				(vias allowed)
				(pads allowed)
				(copperpour not_allowed)
				(footprints allowed)
			)
			(placement
				(enabled no)
				(sheetname "")
			)
			(fill
				(thermal_gap 0.5)
				(thermal_bridge_width 0.5)
				(island_removal_mode 0)
			)
			(polygon
				(pts
					(arc
						(start 17.88922 -122.48007)
						(mid 12.91082 -122.48007)
						(end 17.88922 -122.48007)
					)
				)
			)
		)
		(zone
			(layers "F.Cu" "B.Cu" "In1.Cu" "In2.Cu" "In3.Cu" "In4.Cu" "In5.Cu" "In6.Cu"
				"In7.Cu" "In8.Cu"
			)
			(hatch none 0.5)
			(connect_pads
				(clearance 0)
			)
			(min_thickness 0.25)
			(keepout
				(tracks not_allowed)
				(vias allowed)
				(pads allowed)
				(copperpour not_allowed)
				(footprints allowed)
			)
			(placement
				(enabled no)
				(sheetname "")
			)
			(fill
				(thermal_gap 0.5)
				(thermal_bridge_width 0.5)
				(island_removal_mode 0)
			)
			(polygon
				(pts
					(arc
						(start 30.139132 -122.48007)
						(mid 25.160732 -122.48007)
						(end 30.139132 -122.48007)
					)
				)
			)
		)
		(zone
			(layers "F.Cu" "B.Cu" "In1.Cu" "In2.Cu" "In3.Cu" "In4.Cu" "In5.Cu" "In6.Cu"
				"In7.Cu" "In8.Cu"
			)
			(hatch none 0.5)
			(connect_pads
				(clearance 0)
			)
			(min_thickness 0.25)
			(keepout
				(tracks not_allowed)
				(vias allowed)
				(pads allowed)
				(copperpour not_allowed)
				(footprints allowed)
			)
			(placement
				(enabled no)
				(sheetname "")
			)
			(fill
				(thermal_gap 0.5)
				(thermal_bridge_width 0.5)
				(island_removal_mode 0)
			)
			(polygon
				(pts
					(arc
						(start 25.04313 -122.48007)
						(mid 17.01673 -122.48007)
						(end 25.04313 -122.48007)
					)
				)
			)
		)
	)
	(footprint ""
		(layer "F.Cu")
		(at 164.714174 -130.175)
		(property "Reference" "PC120"
			(at 0 0 0)
			(layer "F.SilkS")
			(hide yes)
			(effects
				(font
					(size 1.27 1.27)
				)
			)
		)
		(property "Value" ""
			(at 0 0 0)
			(layer "F.Fab")
			(effects
				(font
					(size 1.27 1.27)
				)
			)
		)
		(duplicate_pad_numbers_are_jumpers no)
		(fp_line
			(start -2.2098 -0.9398)
			(end 2.2098 -0.9398)
			(stroke
				(width 0.1524)
				(type default)
			)
			(layer "F.SilkS")
		)
		(fp_line
			(start -2.2098 0.9398)
			(end -2.2098 -0.9398)
			(stroke
				(width 0.1524)
				(type default)
			)
			(layer "F.SilkS")
		)
		(fp_line
			(start 2.2098 -0.9398)
			(end 2.2098 0.9398)
			(stroke
				(width 0.1524)
				(type default)
			)
			(layer "F.SilkS")
		)
		(fp_line
			(start 2.2098 0.9398)
			(end -2.2098 0.9398)
			(stroke
				(width 0.1524)
				(type default)
			)
			(layer "F.SilkS")
		)
		(fp_line
			(start -1.700022 -0.899922)
			(end 1.700022 -0.899922)
			(stroke
				(width 0.1)
				(type default)
			)
			(layer "F.Fab")
		)
		(fp_line
			(start -1.700022 0.899922)
			(end -1.700022 -0.899922)
			(stroke
				(width 0.1)
				(type default)
			)
			(layer "F.Fab")
		)
		(fp_line
			(start 1.700022 -0.899922)
			(end 1.700022 0.899922)
			(stroke
				(width 0.1)
				(type default)
			)
			(layer "F.Fab")
		)
		(fp_line
			(start 1.700022 0.899922)
			(end -1.700022 0.899922)
			(stroke
				(width 0.1)
				(type default)
			)
			(layer "F.Fab")
		)
		(pad "1" smd rect
			(at -1.4732 0 180)
			(size 1.1684 1.5748)
			(layers "F.Cu" "F.Mask" "F.Paste")
			(net "P52V_HS_FILTER")
		)
		(pad "2" smd rect
			(at 1.4732 0 180)
			(size 1.1684 1.5748)
			(layers "F.Cu" "F.Mask" "F.Paste")
			(net "GND")
		)
	)
	(footprint ""
		(layer "F.Cu")
		(at 54.238906 -136.906 90)
		(property "Reference" "PC72"
			(at 6.06933 1.006094 0)
			(unlocked yes)
			(layer "F.SilkS")
			(effects
				(font
					(size 0.7874 0.5842)
					(thickness 0.1524)
				)
				(justify left)
			)
		)
		(property "Value" ""
			(at 0 0 90)
			(layer "F.Fab")
			(effects
				(font
					(size 1.27 1.27)
				)
			)
		)
		(duplicate_pad_numbers_are_jumpers no)
		(fp_line
			(start 5.2578 2.499868)
			(end -5.2578 2.499868)
			(stroke
				(width 0.1524)
				(type default)
			)
			(layer "F.SilkS")
		)
		(fp_circle
			(center 0 2.500122)
			(end 0 7.758176)
			(stroke
				(width 0.1524)
				(type default)
			)
			(fill no)
			(layer "F.SilkS")
		)
		(fp_poly
			(pts
				(arc
					(start 5.2578 2.499868)
					(mid 0 7.757922)
					(end -5.2578 2.499868)
				)
			)
			(stroke
				(width 0)
				(type default)
			)
			(fill yes)
			(layer "F.SilkS")
		)
		(fp_circle
			(center 0 2.500122)
			(end 0 7.758176)
			(stroke
				(width 0.1)
				(type default)
			)
			(fill no)
			(layer "F.Fab")
		)
		(pad "1" thru_hole rect
			(at 0 0)
			(size 1.5748 1.5748)
			(drill 1.0668)
			(layers "*.Cu" "*.Mask")
			(remove_unused_layers no)
			(net "P52V_HS_FILTER")
			(clearance 0)
			(padstack
				(mode front_inner_back)
				(layer "Inner"
					(shape circle)
					(size 1.5748 1.5748)
					(clearance 0)
				)
				(layer "B.Cu"
					(shape rect)
					(size 1.5748 1.5748)
					(clearance 0)
				)
			)
		)
		(pad "2" thru_hole circle
			(at 0 4.99999)
			(size 1.5748 1.5748)
			(drill 1.0668)
			(layers "*.Cu" "*.Mask")
			(remove_unused_layers no)
			(net "GND")
			(clearance 0)
		)
	)
	(footprint ""
		(layer "F.Cu")
		(at 104.469946 -121.209816)
		(property "Reference" "PU3"
			(at -26.563066 -5.12953 0)
			(unlocked yes)
			(layer "F.SilkS")
			(effects
				(font
					(size 0.7874 0.5842)
					(thickness 0.1524)
				)
				(justify left)
			)
		)
		(property "Value" ""
			(at 0 0 0)
			(layer "F.Fab")
			(effects
				(font
					(size 1.27 1.27)
				)
			)
		)
		(duplicate_pad_numbers_are_jumpers no)
		(fp_line
			(start -26.519886 -4.299966)
			(end -26.519886 55.099966)
			(stroke
				(width 0.1524)
				(type default)
			)
			(layer "F.SilkS")
		)
		(fp_line
			(start -26.519886 55.099966)
			(end 11.279886 55.099966)
			(stroke
				(width 0.1524)
				(type default)
			)
			(layer "F.SilkS")
		)
		(fp_line
			(start -26.020014 -3.800094)
			(end -26.020014 54.59984)
			(stroke
				(width 0.1524)
				(type default)
			)
			(layer "F.SilkS")
		)
		(fp_line
			(start -26.020014 54.59984)
			(end 10.780014 54.59984)
			(stroke
				(width 0.1524)
				(type default)
			)
			(layer "F.SilkS")
		)
		(fp_line
			(start 10.780014 -3.800094)
			(end -26.020014 -3.800094)
			(stroke
				(width 0.1524)
				(type default)
			)
			(layer "F.SilkS")
		)
		(fp_line
			(start 10.780014 54.59984)
			(end 10.780014 -3.800094)
			(stroke
				(width 0.1524)
				(type default)
			)
			(layer "F.SilkS")
		)
		(fp_line
			(start 11.279886 -4.299966)
			(end -26.519886 -4.299966)
			(stroke
				(width 0.1524)
				(type default)
			)
			(layer "F.SilkS")
		)
		(fp_line
			(start 11.279886 55.099966)
			(end 11.279886 -4.299966)
			(stroke
				(width 0.1524)
				(type default)
			)
			(layer "F.SilkS")
		)
		(fp_poly
			(pts
				(xy 1.27 -7.44728) (xy -1.27 -7.44728) (xy 0 -4.90728)
			)
			(stroke
				(width 0)
				(type default)
			)
			(fill yes)
			(layer "F.SilkS")
		)
		(fp_line
			(start -26.020014 -3.800094)
			(end -26.020014 54.59984)
			(stroke
				(width 0.1)
				(type default)
			)
			(layer "F.Fab")
		)
		(fp_line
			(start -26.020014 54.59984)
			(end 10.780014 54.59984)
			(stroke
				(width 0.1)
				(type default)
			)
			(layer "F.Fab")
		)
		(fp_line
			(start 10.780014 -3.800094)
			(end -26.020014 -3.800094)
			(stroke
				(width 0.1)
				(type default)
			)
			(layer "F.Fab")
		)
		(fp_line
			(start 10.780014 54.59984)
			(end 10.780014 -3.800094)
			(stroke
				(width 0.1)
				(type default)
			)
			(layer "F.Fab")
		)
		(fp_poly
			(pts
				(xy 1.27 -7.44728) (xy -1.27 -7.44728) (xy 0 -4.90728)
			)
			(stroke
				(width 0)
				(type default)
			)
			(fill yes)
			(layer "F.Fab")
		)
		(pad "1" thru_hole rect
			(at 0 0 270)
			(size 2.3622 2.3622)
			(drill 1.6002)
			(layers "*.Cu" "*.Mask")
			(remove_unused_layers no)
			(net "P52V_HS_FILTER")
			(clearance -0.127)
			(padstack
				(mode front_inner_back)
				(layer "Inner"
					(shape circle)
					(size 2.3622 2.3622)
					(clearance -0.127)
				)
				(layer "B.Cu"
					(shape rect)
					(size 2.3622 2.3622)
					(clearance -0.127)
				)
			)
		)
		(pad "2" thru_hole circle
			(at -7.62 0 270)
			(size 2.3622 2.3622)
			(drill 1.6002)
			(layers "*.Cu" "*.Mask")
			(remove_unused_layers no)
			(net "BRICK_P12V1_ON_OFF_R")
			(clearance -0.127)
		)
		(pad "3" thru_hole circle
			(at -15.24 0 270)
			(size 2.3622 2.3622)
			(drill 1.6002)
			(layers "*.Cu" "*.Mask")
			(remove_unused_layers no)
			(net "GND")
			(clearance -0.127)
		)
		(pad "4" thru_hole circle
			(at -19.05 50.8 270)
			(size 3.1242 3.1242)
			(drill 2.1082)
			(layers "*.Cu" "*.Mask")
			(remove_unused_layers no)
			(net "GND")
			(clearance -0.254)
		)
		(pad "5" thru_hole circle
			(at -15.24 50.8 270)
			(size 3.1242 3.1242)
			(drill 2.1082)
			(layers "*.Cu" "*.Mask")
			(remove_unused_layers no)
			(net "GND")
			(clearance -0.254)
		)
		(pad "6" thru_hole circle
			(at 0 50.8 270)
			(size 3.1242 3.1242)
			(drill 2.1082)
			(layers "*.Cu" "*.Mask")
			(remove_unused_layers no)
			(net "P12V_BRICK")
			(clearance -0.254)
		)
		(pad "7" thru_hole circle
			(at 3.81 50.8 270)
			(size 3.1242 3.1242)
			(drill 2.1082)
			(layers "*.Cu" "*.Mask")
			(remove_unused_layers no)
			(net "P12V_BRICK")
			(clearance -0.254)
		)
		(pad "8" thru_hole circle
			(at -13.619988 53.34 270)
			(size 1.3208 1.3208)
			(drill 0.9144)
			(layers "*.Cu" "*.Mask")
			(remove_unused_layers no)
			(net "P12V_BRICK_PWRGD")
			(clearance 0.0508)
			(thermal_gap 0.0508)
		)
		(pad "9" thru_hole circle
			(at -11.619992 53.34 270)
			(size 1.3208 1.3208)
			(drill 0.9144)
			(layers "*.Cu" "*.Mask")
			(remove_unused_layers no)
			(net "P12V_MB1_SENSE-")
			(clearance 0.0508)
			(thermal_gap 0.0508)
		)
		(pad "10" thru_hole circle
			(at -9.619996 53.34 270)
			(size 1.3208 1.3208)
			(drill 0.9144)
			(layers "*.Cu" "*.Mask")
			(remove_unused_layers no)
			(net "SMB_BRICK1_SDA")
			(clearance 0.0508)
			(thermal_gap 0.0508)
		)
		(pad "11" thru_hole circle
			(at -7.62 53.34 270)
			(size 1.3208 1.3208)
			(drill 0.9144)
			(layers "*.Cu" "*.Mask")
			(remove_unused_layers no)
			(net "SMB_BRICK1_ALERT")
			(clearance 0.0508)
			(thermal_gap 0.0508)
		)
		(pad "12" thru_hole circle
			(at -5.620004 53.34 270)
			(size 1.3208 1.3208)
			(drill 0.9144)
			(layers "*.Cu" "*.Mask")
			(remove_unused_layers no)
			(net "SMB_BRICK1_SCL")
			(clearance 0.0508)
			(thermal_gap 0.0508)
		)
		(pad "13" thru_hole circle
			(at -3.620008 53.34 270)
			(size 1.3208 1.3208)
			(drill 0.9144)
			(layers "*.Cu" "*.Mask")
			(remove_unused_layers no)
			(net "BRICK1_PMBADD")
			(clearance 0.0508)
			(thermal_gap 0.0508)
		)
		(pad "14" thru_hole circle
			(at -1.620012 53.34 270)
			(size 1.3208 1.3208)
			(drill 0.9144)
			(layers "*.Cu" "*.Mask")
			(remove_unused_layers no)
			(net "P12V_MB1_SENSE+")
			(clearance 0.0508)
			(thermal_gap 0.0508)
		)
	)
	(footprint ""
		(layer "F.Cu")
		(at 37.338 -60.5282 -90)
		(property "Reference" "R5895"
			(at 0 0 270)
			(layer "F.SilkS")
			(hide yes)
			(effects
				(font
					(size 1.27 1.27)
				)
			)
		)
		(property "Value" ""
			(at 0 0 270)
			(layer "F.Fab")
			(effects
				(font
					(size 1.27 1.27)
				)
			)
		)
		(duplicate_pad_numbers_are_jumpers no)
		(fp_line
			(start -1.2954 0.5842)
			(end -1.2954 -0.5842)
			(stroke
				(width 0.1524)
				(type default)
			)
			(layer "F.SilkS")
		)
		(fp_line
			(start 1.2954 0.5842)
			(end -1.2954 0.5842)
			(stroke
				(width 0.1524)
				(type default)
			)
			(layer "F.SilkS")
		)
		(fp_line
			(start -1.2954 -0.5842)
			(end 1.2954 -0.5842)
			(stroke
				(width 0.1524)
				(type default)
			)
			(layer "F.SilkS")
		)
		(fp_line
			(start 1.2954 -0.5842)
			(end 1.2954 0.5842)
			(stroke
				(width 0.1524)
				(type default)
			)
			(layer "F.SilkS")
		)
		(fp_line
			(start -0.8636 0.4572)
			(end -0.8636 0.4318)
			(stroke
				(width 0.1)
				(type default)
			)
			(layer "F.Fab")
		)
		(fp_line
			(start 0.8636 0.4572)
			(end -0.8636 0.4572)
			(stroke
				(width 0.1)
				(type default)
			)
			(layer "F.Fab")
		)
		(fp_line
			(start -0.8636 0.4318)
			(end -0.8636 0.4064)
			(stroke
				(width 0.1)
				(type default)
			)
			(layer "F.Fab")
		)
		(fp_line
			(start -1.1938 0.4064)
			(end -1.1938 -0.406654)
			(stroke
				(width 0.1)
				(type default)
			)
			(layer "F.Fab")
		)
		(fp_line
			(start -0.8636 0.4064)
			(end -1.1938 0.4064)
			(stroke
				(width 0.1)
				(type default)
			)
			(layer "F.Fab")
		)
		(fp_line
			(start 0.8636 0.4064)
			(end 0.8636 0.4572)
			(stroke
				(width 0.1)
				(type default)
			)
			(layer "F.Fab")
		)
		(fp_line
			(start 1.1938 0.4064)
			(end 0.8636 0.4064)
			(stroke
				(width 0.1)
				(type default)
			)
			(layer "F.Fab")
		)
		(fp_line
			(start -1.1938 -0.406654)
			(end -0.8636 -0.406654)
			(stroke
				(width 0.1)
				(type default)
			)
			(layer "F.Fab")
		)
		(fp_line
			(start -0.8636 -0.406654)
			(end -0.8636 -0.4572)
			(stroke
				(width 0.1)
				(type default)
			)
			(layer "F.Fab")
		)
		(fp_line
			(start 0.8636 -0.406654)
			(end 1.1938 -0.406654)
			(stroke
				(width 0.1)
				(type default)
			)
			(layer "F.Fab")
		)
		(fp_line
			(start 1.1938 -0.406654)
			(end 1.1938 0.4064)
			(stroke
				(width 0.1)
				(type default)
			)
			(layer "F.Fab")
		)
		(fp_line
			(start -0.8636 -0.4572)
			(end 0.8636 -0.4572)
			(stroke
				(width 0.1)
				(type default)
			)
			(layer "F.Fab")
		)
		(fp_line
			(start 0.8636 -0.4572)
			(end 0.8636 -0.406654)
			(stroke
				(width 0.1)
				(type default)
			)
			(layer "F.Fab")
		)
		(pad "1" smd rect
			(at -0.7366 0 180)
			(size 0.7112 0.8128)
			(layers "F.Cu" "F.Mask" "F.Paste")
			(net "P12V_BRICK")
		)
		(pad "2" smd rect
			(at 0.7366 0 180)
			(size 0.7112 0.8128)
			(layers "F.Cu" "F.Mask" "F.Paste")
			(net "P12V_HPDB_0_PD")
		)
	)
	(footprint ""
		(layer "F.Cu")
		(at 168.148 -51.816)
		(property "Reference" "PC32"
			(at 0 0 0)
			(layer "F.SilkS")
			(hide yes)
			(effects
				(font
					(size 1.27 1.27)
				)
			)
		)
		(property "Value" ""
			(at 0 0 0)
			(layer "F.Fab")
			(effects
				(font
					(size 1.27 1.27)
				)
			)
		)
		(duplicate_pad_numbers_are_jumpers no)
		(fp_line
			(start -1.524 -0.762)
			(end 1.524 -0.762)
			(stroke
				(width 0.1524)
				(type default)
			)
			(layer "F.SilkS")
		)
		(fp_line
			(start -1.524 0.762)
			(end -1.524 -0.762)
			(stroke
				(width 0.1524)
				(type default)
			)
			(layer "F.SilkS")
		)
		(fp_line
			(start 1.524 -0.762)
			(end 1.524 0.762)
			(stroke
				(width 0.1524)
				(type default)
			)
			(layer "F.SilkS")
		)
		(fp_line
			(start 1.524 0.762)
			(end -1.524 0.762)
			(stroke
				(width 0.1524)
				(type default)
			)
			(layer "F.SilkS")
		)
		(fp_line
			(start -1.1049 -0.724916)
			(end -1.1049 0.724916)
			(stroke
				(width 0.1)
				(type default)
			)
			(layer "F.Fab")
		)
		(fp_line
			(start -1.1049 0.724916)
			(end 1.1049 0.724916)
			(stroke
				(width 0.1)
				(type default)
			)
			(layer "F.Fab")
		)
		(fp_line
			(start 1.1049 -0.724916)
			(end -1.1049 -0.724916)
			(stroke
				(width 0.1)
				(type default)
			)
			(layer "F.Fab")
		)
		(fp_line
			(start 1.1049 0.724916)
			(end 1.1049 -0.724916)
			(stroke
				(width 0.1)
				(type default)
			)
			(layer "F.Fab")
		)
		(pad "1" smd rect
			(at -0.889 0 180)
			(size 1.016 1.27)
			(layers "F.Cu" "F.Mask" "F.Paste")
			(net "P12V_BRICK")
		)
		(pad "2" smd rect
			(at 0.889 0 180)
			(size 1.016 1.27)
			(layers "F.Cu" "F.Mask" "F.Paste")
			(net "GND")
		)
	)
	(footprint ""
		(layer "F.Cu")
		(at 268.732 -47.625 -90)
		(property "Reference" "R5855"
			(at 0 0 270)
			(layer "F.SilkS")
			(hide yes)
			(effects
				(font
					(size 1.27 1.27)
				)
			)
		)
		(property "Value" ""
			(at 0 0 270)
			(layer "F.Fab")
			(effects
				(font
					(size 1.27 1.27)
				)
			)
		)
		(duplicate_pad_numbers_are_jumpers no)
		(fp_line
			(start -0.7874 0.4064)
			(end -0.7874 -0.4064)
			(stroke
				(width 0.1524)
				(type default)
			)
			(layer "F.SilkS")
		)
		(fp_line
			(start 0.7874 0.4064)
			(end -0.7874 0.4064)
			(stroke
				(width 0.1524)
				(type default)
			)
			(layer "F.SilkS")
		)
		(fp_line
			(start -0.7874 -0.4064)
			(end 0.7874 -0.4064)
			(stroke
				(width 0.1524)
				(type default)
			)
			(layer "F.SilkS")
		)
		(fp_line
			(start 0.7874 -0.4064)
			(end 0.7874 0.4064)
			(stroke
				(width 0.1524)
				(type default)
			)
			(layer "F.SilkS")
		)
		(fp_line
			(start -0.67945 0.3048)
			(end -0.67945 -0.305054)
			(stroke
				(width 0.1)
				(type default)
			)
			(layer "F.Fab")
		)
		(fp_line
			(start -0.12065 0.3048)
			(end -0.67945 0.3048)
			(stroke
				(width 0.1)
				(type default)
			)
			(layer "F.Fab")
		)
		(fp_line
			(start 0.120396 0.3048)
			(end 0.120396 0.2794)
			(stroke
				(width 0.1)
				(type default)
			)
			(layer "F.Fab")
		)
		(fp_line
			(start 0.67945 0.3048)
			(end 0.120396 0.3048)
			(stroke
				(width 0.1)
				(type default)
			)
			(layer "F.Fab")
		)
		(fp_line
			(start -0.12065 0.2794)
			(end -0.12065 0.3048)
			(stroke
				(width 0.1)
				(type default)
			)
			(layer "F.Fab")
		)
		(fp_line
			(start 0.120396 0.2794)
			(end -0.12065 0.2794)
			(stroke
				(width 0.1)
				(type default)
			)
			(layer "F.Fab")
		)
		(fp_line
			(start -0.12065 -0.2794)
			(end 0.12065 -0.2794)
			(stroke
				(width 0.1)
				(type default)
			)
			(layer "F.Fab")
		)
		(fp_line
			(start 0.12065 -0.2794)
			(end 0.12065 -0.3048)
			(stroke
				(width 0.1)
				(type default)
			)
			(layer "F.Fab")
		)
		(fp_line
			(start 0.12065 -0.3048)
			(end 0.67945 -0.3048)
			(stroke
				(width 0.1)
				(type default)
			)
			(layer "F.Fab")
		)
		(fp_line
			(start 0.67945 -0.3048)
			(end 0.67945 0.3048)
			(stroke
				(width 0.1)
				(type default)
			)
			(layer "F.Fab")
		)
		(fp_line
			(start -0.67945 -0.305054)
			(end -0.12065 -0.305054)
			(stroke
				(width 0.1)
				(type default)
			)
			(layer "F.Fab")
		)
		(fp_line
			(start -0.12065 -0.305054)
			(end -0.12065 -0.2794)
			(stroke
				(width 0.1)
				(type default)
			)
			(layer "F.Fab")
		)
		(pad "1" smd circle
			(at -0.40005 0 270)
			(size 0 0)
			(layers "F.Cu" "F.Mask" "F.Paste")
			(net "SMB_P52V_HSC_SDA")
		)
		(pad "2" smd circle
			(at 0.40005 0 270)
			(size 0 0)
			(layers "F.Cu" "F.Mask" "F.Paste")
			(net "SMB_P52V_HS1_SDAI")
		)
	)
	(footprint ""
		(layer "F.Cu")
		(at 279.4 -20.955)
		(property "Reference" "R5884"
			(at 0 0 0)
			(layer "F.SilkS")
			(hide yes)
			(effects
				(font
					(size 1.27 1.27)
				)
			)
		)
		(property "Value" ""
			(at 0 0 0)
			(layer "F.Fab")
			(effects
				(font
					(size 1.27 1.27)
				)
			)
		)
		(duplicate_pad_numbers_are_jumpers no)
		(fp_line
			(start -1.651 -0.8382)
			(end 1.651 -0.8382)
			(stroke
				(width 0.1524)
				(type default)
			)
			(layer "F.SilkS")
		)
		(fp_line
			(start -1.651 0.8382)
			(end -1.651 -0.8382)
			(stroke
				(width 0.1524)
				(type default)
			)
			(layer "F.SilkS")
		)
		(fp_line
			(start 1.651 -0.8382)
			(end 1.651 0.8382)
			(stroke
				(width 0.1524)
				(type default)
			)
			(layer "F.SilkS")
		)
		(fp_line
			(start 1.651 0.8382)
			(end -1.651 0.8382)
			(stroke
				(width 0.1524)
				(type default)
			)
			(layer "F.SilkS")
		)
		(fp_line
			(start -1.559814 -0.7366)
			(end -1.559814 0.7366)
			(stroke
				(width 0.1)
				(type default)
			)
			(layer "F.Fab")
		)
		(fp_line
			(start -1.559814 0.7366)
			(end -1.524 0.7366)
			(stroke
				(width 0.1)
				(type default)
			)
			(layer "F.Fab")
		)
		(fp_line
			(start -1.524 -0.7366)
			(end -1.559814 -0.7366)
			(stroke
				(width 0.1)
				(type default)
			)
			(layer "F.Fab")
		)
		(fp_line
			(start -1.524 0.7366)
			(end 1.524 0.7366)
			(stroke
				(width 0.1)
				(type default)
			)
			(layer "F.Fab")
		)
		(fp_line
			(start 1.524 -0.7366)
			(end -1.524 -0.7366)
			(stroke
				(width 0.1)
				(type default)
			)
			(layer "F.Fab")
		)
		(fp_line
			(start 1.524 0.7366)
			(end 1.560576 0.7366)
			(stroke
				(width 0.1)
				(type default)
			)
			(layer "F.Fab")
		)
		(fp_line
			(start 1.560576 -0.7366)
			(end 1.524 -0.7366)
			(stroke
				(width 0.1)
				(type default)
			)
			(layer "F.Fab")
		)
		(fp_line
			(start 1.560576 0.7366)
			(end 1.560576 -0.7366)
			(stroke
				(width 0.1)
				(type default)
			)
			(layer "F.Fab")
		)
		(pad "1" smd rect
			(at -0.94996 0 180)
			(size 1.1176 1.3716)
			(layers "F.Cu" "F.Mask" "F.Paste")
			(net "P52V_BUSBAR")
		)
		(pad "2" smd rect
			(at 0.94996 0 180)
			(size 1.1176 1.3716)
			(layers "F.Cu" "F.Mask" "F.Paste")
			(net "FM_HSC_EN_BUSBAR")
		)
	)
	(footprint ""
		(layer "F.Cu")
		(at 269.875 -47.625 -90)
		(property "Reference" "R5864"
			(at 0 0 270)
			(layer "F.SilkS")
			(hide yes)
			(effects
				(font
					(size 1.27 1.27)
				)
			)
		)
		(property "Value" ""
			(at 0 0 270)
			(layer "F.Fab")
			(effects
				(font
					(size 1.27 1.27)
				)
			)
		)
		(duplicate_pad_numbers_are_jumpers no)
		(fp_line
			(start -0.7874 0.4064)
			(end -0.7874 -0.4064)
			(stroke
				(width 0.1524)
				(type default)
			)
			(layer "F.SilkS")
		)
		(fp_line
			(start 0.7874 0.4064)
			(end -0.7874 0.4064)
			(stroke
				(width 0.1524)
				(type default)
			)
			(layer "F.SilkS")
		)
		(fp_line
			(start -0.7874 -0.4064)
			(end 0.7874 -0.4064)
			(stroke
				(width 0.1524)
				(type default)
			)
			(layer "F.SilkS")
		)
		(fp_line
			(start 0.7874 -0.4064)
			(end 0.7874 0.4064)
			(stroke
				(width 0.1524)
				(type default)
			)
			(layer "F.SilkS")
		)
		(fp_line
			(start -0.67945 0.3048)
			(end -0.67945 -0.305054)
			(stroke
				(width 0.1)
				(type default)
			)
			(layer "F.Fab")
		)
		(fp_line
			(start -0.12065 0.3048)
			(end -0.67945 0.3048)
			(stroke
				(width 0.1)
				(type default)
			)
			(layer "F.Fab")
		)
		(fp_line
			(start 0.120396 0.3048)
			(end 0.120396 0.2794)
			(stroke
				(width 0.1)
				(type default)
			)
			(layer "F.Fab")
		)
		(fp_line
			(start 0.67945 0.3048)
			(end 0.120396 0.3048)
			(stroke
				(width 0.1)
				(type default)
			)
			(layer "F.Fab")
		)
		(fp_line
			(start -0.12065 0.2794)
			(end -0.12065 0.3048)
			(stroke
				(width 0.1)
				(type default)
			)
			(layer "F.Fab")
		)
		(fp_line
			(start 0.120396 0.2794)
			(end -0.12065 0.2794)
			(stroke
				(width 0.1)
				(type default)
			)
			(layer "F.Fab")
		)
		(fp_line
			(start -0.12065 -0.2794)
			(end 0.12065 -0.2794)
			(stroke
				(width 0.1)
				(type default)
			)
			(layer "F.Fab")
		)
		(fp_line
			(start 0.12065 -0.2794)
			(end 0.12065 -0.3048)
			(stroke
				(width 0.1)
				(type default)
			)
			(layer "F.Fab")
		)
		(fp_line
			(start 0.12065 -0.3048)
			(end 0.67945 -0.3048)
			(stroke
				(width 0.1)
				(type default)
			)
			(layer "F.Fab")
		)
		(fp_line
			(start 0.67945 -0.3048)
			(end 0.67945 0.3048)
			(stroke
				(width 0.1)
				(type default)
			)
			(layer "F.Fab")
		)
		(fp_line
			(start -0.67945 -0.305054)
			(end -0.12065 -0.305054)
			(stroke
				(width 0.1)
				(type default)
			)
			(layer "F.Fab")
		)
		(fp_line
			(start -0.12065 -0.305054)
			(end -0.12065 -0.2794)
			(stroke
				(width 0.1)
				(type default)
			)
			(layer "F.Fab")
		)
		(pad "1" smd circle
			(at -0.40005 0 270)
			(size 0 0)
			(layers "F.Cu" "F.Mask" "F.Paste")
			(net "SMB_P52V_HSC_SCL")
		)
		(pad "2" smd circle
			(at 0.40005 0 270)
			(size 0 0)
			(layers "F.Cu" "F.Mask" "F.Paste")
			(net "SMB_P52V_VPDB_SCL_R3")
		)
	)
	(footprint ""
		(layer "F.Cu")
		(at 186.939174 -60.96)
		(property "Reference" "PC136"
			(at -1.773174 -3.52933 0)
			(unlocked yes)
			(layer "F.SilkS")
			(effects
				(font
					(size 0.7874 0.5842)
					(thickness 0.1524)
				)
				(justify left)
			)
		)
		(property "Value" ""
			(at 0 0 0)
			(layer "F.Fab")
			(effects
				(font
					(size 1.27 1.27)
				)
			)
		)
		(duplicate_pad_numbers_are_jumpers no)
		(fp_line
			(start 5.2578 2.499868)
			(end -5.2578 2.499868)
			(stroke
				(width 0.1524)
				(type default)
			)
			(layer "F.SilkS")
		)
		(fp_circle
			(center 0 2.499868)
			(end 5.2578 2.499868)
			(stroke
				(width 0.1524)
				(type default)
			)
			(fill no)
			(layer "F.SilkS")
		)
		(fp_poly
			(pts
				(arc
					(start 5.2578 2.499868)
					(mid 0 7.757922)
					(end -5.2578 2.499868)
				)
			)
			(stroke
				(width 0)
				(type default)
			)
			(fill yes)
			(layer "F.SilkS")
		)
		(fp_circle
			(center 0 2.499868)
			(end 5.2578 2.499868)
			(stroke
				(width 0.1)
				(type default)
			)
			(fill no)
			(layer "F.Fab")
		)
		(pad "1" thru_hole rect
			(at 0 0 270)
			(size 1.524 1.524)
			(drill 1.016)
			(layers "*.Cu" "*.Mask")
			(remove_unused_layers no)
			(net "P12V_BRICK")
			(clearance 0)
			(padstack
				(mode front_inner_back)
				(layer "Inner"
					(shape circle)
					(size 1.524 1.524)
					(clearance 0)
				)
				(layer "B.Cu"
					(shape rect)
					(size 1.524 1.524)
					(clearance 0)
				)
			)
		)
		(pad "2" thru_hole circle
			(at 0 4.99999 270)
			(size 1.524 1.524)
			(drill 1.016)
			(layers "*.Cu" "*.Mask")
			(remove_unused_layers no)
			(net "GND")
			(clearance 0)
		)
	)
	(footprint ""
		(layer "F.Cu")
		(at 263.792716 -41.342818)
		(property "Reference" "PU1"
			(at -5.347716 -4.223512 0)
			(unlocked yes)
			(layer "F.SilkS")
			(effects
				(font
					(size 0.7874 0.5842)
					(thickness 0.1524)
				)
				(justify left)
			)
		)
		(property "Value" ""
			(at 0 0 0)
			(layer "F.Fab")
			(effects
				(font
					(size 1.27 1.27)
				)
			)
		)
		(duplicate_pad_numbers_are_jumpers no)
		(fp_line
			(start -3.549904 -3.549904)
			(end -3.0226 -3.549904)
			(stroke
				(width 0.1524)
				(type default)
			)
			(layer "F.SilkS")
		)
		(fp_line
			(start -3.549904 -3.0226)
			(end -3.549904 -3.549904)
			(stroke
				(width 0.1524)
				(type default)
			)
			(layer "F.SilkS")
		)
		(fp_line
			(start -3.549904 -0.0254)
			(end -3.549904 -1.4732)
			(stroke
				(width 0.1524)
				(type default)
			)
			(layer "F.SilkS")
		)
		(fp_line
			(start -3.549904 3.549904)
			(end -3.549904 3.0226)
			(stroke
				(width 0.1524)
				(type default)
			)
			(layer "F.SilkS")
		)
		(fp_line
			(start -3.0226 3.549904)
			(end -3.549904 3.549904)
			(stroke
				(width 0.1524)
				(type default)
			)
			(layer "F.SilkS")
		)
		(fp_line
			(start -2.4638 -3.549904)
			(end -1.03124 -3.549904)
			(stroke
				(width 0.1524)
				(type default)
			)
			(layer "F.SilkS")
		)
		(fp_line
			(start -1.03124 3.549904)
			(end -2.4638 3.549904)
			(stroke
				(width 0.1524)
				(type default)
			)
			(layer "F.SilkS")
		)
		(fp_line
			(start 3.0226 -3.549904)
			(end 3.549904 -3.549904)
			(stroke
				(width 0.1524)
				(type default)
			)
			(layer "F.SilkS")
		)
		(fp_line
			(start 3.549904 -3.549904)
			(end 3.549904 -3.0226)
			(stroke
				(width 0.1524)
				(type default)
			)
			(layer "F.SilkS")
		)
		(fp_line
			(start 3.549904 3.0226)
			(end 3.549904 3.549904)
			(stroke
				(width 0.1524)
				(type default)
			)
			(layer "F.SilkS")
		)
		(fp_line
			(start 3.549904 3.549904)
			(end 3.0226 3.549904)
			(stroke
				(width 0.1524)
				(type default)
			)
			(layer "F.SilkS")
		)
		(fp_poly
			(pts
				(xy -4.134104 -3.041904) (xy -3.549904 -3.041904) (xy -3.549904 -3.626104) (xy -4.134104 -3.626104)
			)
			(stroke
				(width 0)
				(type default)
			)
			(fill yes)
			(layer "F.SilkS")
		)
		(fp_line
			(start -3.549904 -3.549904)
			(end 3.549904 -3.549904)
			(stroke
				(width 0.1)
				(type default)
			)
			(layer "F.Fab")
		)
		(fp_line
			(start -3.549904 3.549904)
			(end -3.549904 -3.549904)
			(stroke
				(width 0.1)
				(type default)
			)
			(layer "F.Fab")
		)
		(fp_line
			(start 3.549904 -3.549904)
			(end 3.549904 3.549904)
			(stroke
				(width 0.1)
				(type default)
			)
			(layer "F.Fab")
		)
		(fp_line
			(start 3.549904 3.549904)
			(end -3.549904 3.549904)
			(stroke
				(width 0.1)
				(type default)
			)
			(layer "F.Fab")
		)
		(fp_poly
			(pts
				(xy -4.134104 -3.041904) (xy -3.549904 -3.041904) (xy -3.549904 -3.626104) (xy -4.134104 -3.626104)
			)
			(stroke
				(width 0)
				(type default)
			)
			(fill yes)
			(layer "F.Fab")
		)
		(pad "1" smd rect
			(at -3.425444 -2.750058 270)
			(size 0.2794 0.7112)
			(layers "F.Cu" "F.Mask" "F.Paste")
			(net "P52V_HS")
		)
		(pad "2" smd rect
			(at -3.400044 -2.249932 270)
			(size 0.2794 0.762)
			(layers "F.Cu" "F.Mask" "F.Paste")
			(net "P52V_HS1_4287_GATE2_R")
		)
		(pad "3" smd rect
			(at -3.400044 -1.75006 270)
			(size 0.2794 0.762)
			(layers "F.Cu" "F.Mask" "F.Paste")
			(net "P52V_HS1_4287_GATE_R")
		)
		(pad "4" smd rect
			(at -3.400044 0.249936 270)
			(size 0.2794 0.762)
			(layers "F.Cu" "F.Mask" "F.Paste")
			(net "P52V_HS_4287_ADC_N")
		)
		(pad "5" smd rect
			(at -3.400044 0.750062 270)
			(size 0.2794 0.762)
			(layers "F.Cu" "F.Mask" "F.Paste")
			(net "P52V_HS_4287_S1N")
		)
		(pad "6" smd rect
			(at -3.400044 1.249934 270)
			(size 0.2794 0.762)
			(layers "F.Cu" "F.Mask" "F.Paste")
			(net "P52V_HS_4287_S1P")
		)
		(pad "7" smd rect
			(at -3.400044 1.75006 270)
			(size 0.2794 0.762)
			(layers "F.Cu" "F.Mask" "F.Paste")
			(net "P52V_HS_4287_ADC_P")
		)
		(pad "8" smd rect
			(at -3.400044 2.249932 270)
			(size 0.2794 0.762)
			(layers "F.Cu" "F.Mask" "F.Paste")
			(net "P52V_HS_4287_S2N")
		)
		(pad "9" smd rect
			(at -3.425444 2.750058 270)
			(size 0.2794 0.7112)
			(layers "F.Cu" "F.Mask" "F.Paste")
			(net "P52V_HS_4287_S2P")
		)
		(pad "10" smd rect
			(at -2.750058 3.425444)
			(size 0.2794 0.7112)
			(layers "F.Cu" "F.Mask" "F.Paste")
			(net "P52V_1_R")
		)
		(pad "11" smd rect
			(at -0.750062 3.400044)
			(size 0.2794 0.762)
			(layers "F.Cu" "F.Mask" "F.Paste")
			(net "P52V_HS1_UVLO_EN")
		)
		(pad "12" smd rect
			(at -0.249936 3.400044)
			(size 0.2794 0.762)
			(layers "F.Cu" "F.Mask" "F.Paste")
			(net "P52V_HS1_OV")
		)
		(pad "13" smd rect
			(at 0.249936 3.400044)
			(size 0.2794 0.762)
			(layers "F.Cu" "F.Mask" "F.Paste")
			(net "P52V_HS1_INTVCC")
		)
		(pad "14" smd rect
			(at 0.750062 3.400044)
			(size 0.2794 0.762)
			(layers "F.Cu" "F.Mask" "F.Paste")
			(net "GND_FIELD_SIGNAL")
		)
		(pad "15" smd rect
			(at 1.249934 3.400044)
			(size 0.2794 0.762)
			(layers "F.Cu" "F.Mask" "F.Paste")
			(net "P52V_HS1_DVCC")
		)
		(pad "16" smd rect
			(at 1.75006 3.400044)
			(size 0.2794 0.762)
			(layers "F.Cu" "F.Mask" "F.Paste")
			(net "P52V_HS1_ADR0")
		)
		(pad "17" smd rect
			(at 2.249932 3.400044)
			(size 0.2794 0.762)
			(layers "F.Cu" "F.Mask" "F.Paste")
			(net "P52V_HS1_ADR1")
		)
		(pad "18" smd rect
			(at 2.750058 3.425444)
			(size 0.2794 0.7112)
			(layers "F.Cu" "F.Mask" "F.Paste")
			(net "Net_299")
		)
		(pad "19" smd rect
			(at 3.425444 2.750058 270)
			(size 0.2794 0.7112)
			(layers "F.Cu" "F.Mask" "F.Paste")
			(net "P52V_HS1_MODE")
		)
		(pad "20" smd rect
			(at 3.400044 2.249932 270)
			(size 0.2794 0.762)
			(layers "F.Cu" "F.Mask" "F.Paste")
			(net "P52V_HS1_TMR")
		)
		(pad "21" smd rect
			(at 3.400044 1.75006 270)
			(size 0.2794 0.762)
			(layers "F.Cu" "F.Mask" "F.Paste")
			(net "P52V_HS1_CLKIN")
		)
		(pad "22" smd rect
			(at 3.400044 1.249934 270)
			(size 0.2794 0.762)
			(layers "F.Cu" "F.Mask" "F.Paste")
			(net "Net_303")
		)
		(pad "23" smd rect
			(at 3.400044 0.750062 270)
			(size 0.2794 0.762)
			(layers "F.Cu" "F.Mask" "F.Paste")
			(net "P52V_HS1_EN_BUF_DELAY")
		)
		(pad "24" smd rect
			(at 3.400044 0.249936 270)
			(size 0.2794 0.762)
			(layers "F.Cu" "F.Mask" "F.Paste")
			(net "P52V_HS1_SIO")
		)
		(pad "25" smd rect
			(at 3.400044 -0.249936 270)
			(size 0.2794 0.762)
			(layers "F.Cu" "F.Mask" "F.Paste")
			(net "P52V_HS1_SCK")
		)
		(pad "26" smd rect
			(at 3.400044 -0.750062 270)
			(size 0.2794 0.762)
			(layers "F.Cu" "F.Mask" "F.Paste")
			(net "P52V_HS1_CS")
		)
		(pad "27" smd rect
			(at 3.400044 -1.249934 270)
			(size 0.2794 0.762)
			(layers "F.Cu" "F.Mask" "F.Paste")
			(net "SMB_P52V_VPDB_SCL_R3")
		)
		(pad "28" smd rect
			(at 3.400044 -1.75006 270)
			(size 0.2794 0.762)
			(layers "F.Cu" "F.Mask" "F.Paste")
			(net "SMB_P52V_HS1_SDAI")
		)
		(pad "29" smd rect
			(at 3.400044 -2.249932 270)
			(size 0.2794 0.762)
			(layers "F.Cu" "F.Mask" "F.Paste")
			(net "SMB_P52V_HS1_SDAO")
		)
		(pad "30" smd rect
			(at 3.425444 -2.750058 270)
			(size 0.2794 0.7112)
			(layers "F.Cu" "F.Mask" "F.Paste")
			(net "Net_300")
		)
		(pad "31" smd rect
			(at 2.750058 -3.425444)
			(size 0.2794 0.7112)
			(layers "F.Cu" "F.Mask" "F.Paste")
			(net "Net_301")
		)
		(pad "32" smd rect
			(at 2.249932 -3.400044)
			(size 0.2794 0.762)
			(layers "F.Cu" "F.Mask" "F.Paste")
			(net "Net_302")
		)
		(pad "33" smd rect
			(at 1.75006 -3.400044)
			(size 0.2794 0.762)
			(layers "F.Cu" "F.Mask" "F.Paste")
			(net "GND_FIELD_SIGNAL")
		)
		(pad "34" smd rect
			(at 1.249934 -3.400044)
			(size 0.2794 0.762)
			(layers "F.Cu" "F.Mask" "F.Paste")
			(net "GND_FIELD_SIGNAL")
		)
		(pad "35" smd rect
			(at 0.750062 -3.400044)
			(size 0.2794 0.762)
			(layers "F.Cu" "F.Mask" "F.Paste")
			(net "P52V_HS1_TEMP")
		)
		(pad "36" smd rect
			(at 0.249936 -3.400044)
			(size 0.2794 0.762)
			(layers "F.Cu" "F.Mask" "F.Paste")
			(net "P52V_HS1_FLT")
		)
		(pad "37" smd rect
			(at -0.249936 -3.400044)
			(size 0.2794 0.762)
			(layers "F.Cu" "F.Mask" "F.Paste")
			(net "PWRGD_P52V_HS1_PG_N")
		)
		(pad "38" smd rect
			(at -0.750062 -3.400044)
			(size 0.2794 0.762)
			(layers "F.Cu" "F.Mask" "F.Paste")
			(net "P52V_HS1_FB")
		)
		(pad "39" smd rect
			(at -2.750058 -3.425444)
			(size 0.2794 0.7112)
			(layers "F.Cu" "F.Mask" "F.Paste")
			(net "P52V_HS1_VDSFB")
		)
		(pad "40" smd circle
			(at 0.87503 0)
			(size 0 0)
			(layers "F.Cu" "F.Mask" "F.Paste")
			(net "GND_FIELD_SIGNAL")
		)
		(zone
			(layer "F.Cu")
			(hatch none 0.5)
			(connect_pads
				(clearance 0)
			)
			(min_thickness 0.25)
			(keepout
				(tracks not_allowed)
				(vias allowed)
				(pads allowed)
				(copperpour not_allowed)
				(footprints allowed)
			)
			(placement
				(enabled no)
				(sheetname "")
			)
			(fill
				(thermal_gap 0.5)
				(thermal_bridge_width 0.5)
				(island_removal_mode 0)
			)
			(polygon
				(pts
					(xy 260.824472 -43.786298) (xy 260.824472 -42.003218) (xy 262.776716 -42.003218) (xy 262.776716 -43.730418)
					(xy 263.157716 -44.111418) (xy 266.561316 -44.111418) (xy 266.561316 -38.574218) (xy 262.776716 -38.574218)
					(xy 262.776716 -41.977818) (xy 260.824472 -41.977818) (xy 260.824472 -38.896798) (xy 260.773672 -38.896798)
					(xy 260.773672 -38.323774) (xy 262.845296 -38.323774) (xy 262.845296 -38.374574) (xy 266.238736 -38.374574)
					(xy 266.238736 -38.323774) (xy 266.81176 -38.323774) (xy 266.81176 -38.896798) (xy 266.76096 -38.896798)
					(xy 266.76096 -43.788838) (xy 266.81176 -43.788838) (xy 266.81176 -44.361862) (xy 266.238736 -44.361862)
					(xy 266.238736 -44.311062) (xy 262.845296 -44.311062) (xy 262.845296 -44.361862) (xy 260.773672 -44.361862)
					(xy 260.773672 -43.786298)
				)
			)
		)
	)
	(footprint ""
		(layer "F.Cu")
		(at 311.410096 -72.879966)
		(property "Reference" "J5"
			(at -1.911096 -35.170364 0)
			(unlocked yes)
			(layer "F.SilkS")
			(effects
				(font
					(size 0.7874 0.5842)
					(thickness 0.1524)
				)
			)
		)
		(property "Value" ""
			(at 0 0 0)
			(layer "F.Fab")
			(effects
				(font
					(size 1.27 1.27)
				)
			)
		)
		(duplicate_pad_numbers_are_jumpers no)
		(fp_line
			(start -6.469888 -34.36493)
			(end 14.109954 -34.36493)
			(stroke
				(width 0.1524)
				(type default)
			)
			(layer "F.SilkS")
		)
		(fp_line
			(start -6.469888 -15.385034)
			(end -6.469888 -34.36493)
			(stroke
				(width 0.1524)
				(type default)
			)
			(layer "F.SilkS")
		)
		(fp_line
			(start -6.469888 34.36493)
			(end -6.469888 -7.511034)
			(stroke
				(width 0.1524)
				(type default)
			)
			(layer "F.SilkS")
		)
		(fp_line
			(start -3.469894 -31.006034)
			(end -3.469894 -31.364936)
			(stroke
				(width 0.1524)
				(type default)
			)
			(layer "F.SilkS")
		)
		(fp_line
			(start -3.469894 25.635966)
			(end -3.469894 -26.053034)
			(stroke
				(width 0.1524)
				(type default)
			)
			(layer "F.SilkS")
		)
		(fp_line
			(start -3.469894 31.364936)
			(end -3.469894 30.969966)
			(stroke
				(width 0.1524)
				(type default)
			)
			(layer "F.SilkS")
		)
		(fp_line
			(start -3.181096 31.364936)
			(end -3.469894 31.364936)
			(stroke
				(width 0.1524)
				(type default)
			)
			(layer "F.SilkS")
		)
		(fp_line
			(start 3.930904 -31.364936)
			(end 11.10996 -31.364936)
			(stroke
				(width 0.1524)
				(type default)
			)
			(layer "F.SilkS")
		)
		(fp_line
			(start 11.10996 -31.364936)
			(end 11.10996 31.364936)
			(stroke
				(width 0.1524)
				(type default)
			)
			(layer "F.SilkS")
		)
		(fp_line
			(start 11.10996 31.364936)
			(end 3.295904 31.364936)
			(stroke
				(width 0.1524)
				(type default)
			)
			(layer "F.SilkS")
		)
		(fp_line
			(start 14.109954 -34.36493)
			(end 14.109954 34.36493)
			(stroke
				(width 0.1524)
				(type default)
			)
			(layer "F.SilkS")
		)
		(fp_line
			(start 14.109954 34.36493)
			(end -6.469888 34.36493)
			(stroke
				(width 0.1524)
				(type default)
			)
			(layer "F.SilkS")
		)
		(fp_poly
			(pts
				(xy -5.0038 -0.508) (xy -5.0038 0.508) (xy -3.9878 0)
			)
			(stroke
				(width 0)
				(type default)
			)
			(fill yes)
			(layer "F.SilkS")
		)
		(fp_line
			(start -6.469888 -34.36493)
			(end 14.109954 -34.36493)
			(stroke
				(width 0.1524)
				(type default)
			)
			(layer "B.SilkS")
		)
		(fp_line
			(start -6.469888 34.36493)
			(end -6.469888 -34.36493)
			(stroke
				(width 0.1524)
				(type default)
			)
			(layer "B.SilkS")
		)
		(fp_line
			(start 14.109954 -34.36493)
			(end 14.109954 34.36493)
			(stroke
				(width 0.1524)
				(type default)
			)
			(layer "B.SilkS")
		)
		(fp_line
			(start 14.109954 34.36493)
			(end -6.469888 34.36493)
			(stroke
				(width 0.1524)
				(type default)
			)
			(layer "B.SilkS")
		)
		(fp_line
			(start -6.469888 -34.36493)
			(end 14.109954 -34.36493)
			(stroke
				(width 0.1)
				(type default)
			)
			(layer "B.Fab")
		)
		(fp_line
			(start -6.469888 34.36493)
			(end -6.469888 -34.36493)
			(stroke
				(width 0.1)
				(type default)
			)
			(layer "B.Fab")
		)
		(fp_line
			(start 14.109954 -34.36493)
			(end 14.109954 34.36493)
			(stroke
				(width 0.1)
				(type default)
			)
			(layer "B.Fab")
		)
		(fp_line
			(start 14.109954 34.36493)
			(end -6.469888 34.36493)
			(stroke
				(width 0.1)
				(type default)
			)
			(layer "B.Fab")
		)
		(fp_line
			(start -3.469894 -31.364936)
			(end 11.10996 -31.364936)
			(stroke
				(width 0.1)
				(type default)
			)
			(layer "F.Fab")
		)
		(fp_line
			(start -3.469894 31.364936)
			(end -3.469894 -31.364936)
			(stroke
				(width 0.1)
				(type default)
			)
			(layer "F.Fab")
		)
		(fp_line
			(start 11.10996 -31.364936)
			(end 11.10996 31.364936)
			(stroke
				(width 0.1)
				(type default)
			)
			(layer "F.Fab")
		)
		(fp_line
			(start 11.10996 31.364936)
			(end -3.469894 31.364936)
			(stroke
				(width 0.1)
				(type default)
			)
			(layer "F.Fab")
		)
		(fp_poly
			(pts
				(xy -5.0038 -0.508) (xy -5.0038 0.508) (xy -3.9878 0)
			)
			(stroke
				(width 0)
				(type default)
			)
			(fill yes)
			(layer "F.Fab")
		)
		(fp_text user "PRESS-FIT"
			(at 12.598654 -1.669034 90)
			(unlocked yes)
			(layer "F.SilkS")
			(effects
				(font
					(size 1.905 1.4224)
					(thickness 0.1524)
				)
			)
		)
		(fp_text user "PRESS-FIT"
			(at 12.63015 -0.0127 270)
			(unlocked yes)
			(layer "B.SilkS")
			(effects
				(font
					(size 1.905 1.4224)
					(thickness 0.1524)
				)
				(justify mirror)
			)
		)
		(fp_text user "PRESS-FIT"
			(at 12.63015 -0.0127 270)
			(unlocked yes)
			(layer "B.Fab")
			(effects
				(font
					(size 1.905 1.4224)
					(thickness 0.1524)
				)
				(justify mirror)
			)
		)
		(fp_text user "PRESS-FIT"
			(at 12.63015 -0.0127 270)
			(unlocked yes)
			(layer "F.Fab")
			(effects
				(font
					(size 1.905 1.4224)
					(thickness 0.1524)
				)
			)
		)
		(pad "" np_thru_hole circle
			(at 0 -28.575)
			(size 0 0)
			(drill 3.2004)
			(layers "*.Cu" "*.Mask")
			(clearance 0)
		)
		(pad "" np_thru_hole circle
			(at 0 28.575)
			(size 0 0)
			(drill 3.2004)
			(layers "*.Cu" "*.Mask")
			(clearance 0)
		)
		(pad "A1" thru_hole rect
			(at 0 0)
			(size 1.52781 1.52781)
			(drill 1.01981)
			(layers "*.Cu" "*.Mask")
			(remove_unused_layers no)
			(net "P52V_BUSBAR")
			(clearance 0)
			(padstack
				(mode front_inner_back)
				(layer "Inner"
					(shape circle)
					(size 1.52781 1.52781)
					(clearance 0)
				)
				(layer "B.Cu"
					(shape rect)
					(size 1.52781 1.52781)
					(clearance 0)
				)
			)
		)
		(pad "B1" thru_hole circle
			(at 2.54 0)
			(size 1.52781 1.52781)
			(drill 1.01981)
			(layers "*.Cu" "*.Mask")
			(remove_unused_layers no)
			(net "GND_BUSBAR")
			(clearance 0)
		)
		(pad "C1" thru_hole circle
			(at 5.08 0)
			(size 1.52781 1.52781)
			(drill 1.01981)
			(layers "*.Cu" "*.Mask")
			(remove_unused_layers no)
			(net "TP_J5_C1")
			(clearance 0)
		)
		(pad "D1" thru_hole circle
			(at 7.62 0)
			(size 1.52781 1.52781)
			(drill 1.01981)
			(layers "*.Cu" "*.Mask")
			(remove_unused_layers no)
			(net "TP_J5_D1")
			(clearance 0)
		)
		(pad "P1_1" thru_hole circle
			(at 7.62 -16.51)
			(size 1.52781 1.52781)
			(drill 1.01981)
			(layers "*.Cu" "*.Mask")
			(remove_unused_layers no)
			(net "P52V_1")
			(clearance 0)
		)
		(pad "P1_2" thru_hole circle
			(at 5.08 -16.51)
			(size 1.52781 1.52781)
			(drill 1.01981)
			(layers "*.Cu" "*.Mask")
			(remove_unused_layers no)
			(net "P52V_1")
			(clearance 0)
		)
		(pad "P1_3" thru_hole circle
			(at 2.54 -16.51)
			(size 1.52781 1.52781)
			(drill 1.01981)
			(layers "*.Cu" "*.Mask")
			(remove_unused_layers no)
			(net "P52V_1")
			(clearance 0)
		)
		(pad "P1_4" thru_hole circle
			(at 0 -16.51)
			(size 1.52781 1.52781)
			(drill 1.01981)
			(layers "*.Cu" "*.Mask")
			(remove_unused_layers no)
			(net "P52V_1")
			(clearance 0)
		)
		(pad "P1_5" thru_hole circle
			(at 7.62 -13.97)
			(size 1.52781 1.52781)
			(drill 1.01981)
			(layers "*.Cu" "*.Mask")
			(remove_unused_layers no)
			(net "P52V_1")
			(clearance 0)
		)
		(pad "P1_6" thru_hole circle
			(at 5.08 -13.97)
			(size 1.52781 1.52781)
			(drill 1.01981)
			(layers "*.Cu" "*.Mask")
			(remove_unused_layers no)
			(net "P52V_1")
			(clearance 0)
		)
		(pad "P1_7" thru_hole circle
			(at 2.54 -13.97)
			(size 1.52781 1.52781)
			(drill 1.01981)
			(layers "*.Cu" "*.Mask")
			(remove_unused_layers no)
			(net "P52V_1")
			(clearance 0)
		)
		(pad "P1_8" thru_hole circle
			(at 0 -13.97)
			(size 1.52781 1.52781)
			(drill 1.01981)
			(layers "*.Cu" "*.Mask")
			(remove_unused_layers no)
			(net "P52V_1")
			(clearance 0)
		)
		(pad "P2_1" thru_hole circle
			(at 7.62 -7.62)
			(size 1.52781 1.52781)
			(drill 1.01981)
			(layers "*.Cu" "*.Mask")
			(remove_unused_layers no)
			(net "P52V_1")
			(clearance 0)
		)
		(pad "P2_2" thru_hole circle
			(at 5.08 -7.62)
			(size 1.52781 1.52781)
			(drill 1.01981)
			(layers "*.Cu" "*.Mask")
			(remove_unused_layers no)
			(net "P52V_1")
			(clearance 0)
		)
		(pad "P2_3" thru_hole circle
			(at 2.54 -7.62)
			(size 1.52781 1.52781)
			(drill 1.01981)
			(layers "*.Cu" "*.Mask")
			(remove_unused_layers no)
			(net "P52V_1")
			(clearance 0)
		)
		(pad "P2_4" thru_hole circle
			(at 0 -7.62)
			(size 1.52781 1.52781)
			(drill 1.01981)
			(layers "*.Cu" "*.Mask")
			(remove_unused_layers no)
			(net "P52V_1")
			(clearance 0)
		)
		(pad "P2_5" thru_hole circle
			(at 7.62 -5.08)
			(size 1.52781 1.52781)
			(drill 1.01981)
			(layers "*.Cu" "*.Mask")
			(remove_unused_layers no)
			(net "P52V_1")
			(clearance 0)
		)
		(pad "P2_6" thru_hole circle
			(at 5.08 -5.08)
			(size 1.52781 1.52781)
			(drill 1.01981)
			(layers "*.Cu" "*.Mask")
			(remove_unused_layers no)
			(net "P52V_1")
			(clearance 0)
		)
		(pad "P2_7" thru_hole circle
			(at 2.54 -5.08)
			(size 1.52781 1.52781)
			(drill 1.01981)
			(layers "*.Cu" "*.Mask")
			(remove_unused_layers no)
			(net "P52V_1")
			(clearance 0)
		)
		(pad "P2_8" thru_hole circle
			(at 0 -5.08)
			(size 1.52781 1.52781)
			(drill 1.01981)
			(layers "*.Cu" "*.Mask")
			(remove_unused_layers no)
			(net "P52V_1")
			(clearance 0)
		)
		(pad "P3_1" thru_hole circle
			(at 7.62 5.08)
			(size 1.52781 1.52781)
			(drill 1.01981)
			(layers "*.Cu" "*.Mask")
			(remove_unused_layers no)
			(net "GND")
			(clearance 0)
		)
		(pad "P3_2" thru_hole circle
			(at 5.08 5.08)
			(size 1.52781 1.52781)
			(drill 1.01981)
			(layers "*.Cu" "*.Mask")
			(remove_unused_layers no)
			(net "GND")
			(clearance 0)
		)
		(pad "P3_3" thru_hole circle
			(at 2.54 5.08)
			(size 1.52781 1.52781)
			(drill 1.01981)
			(layers "*.Cu" "*.Mask")
			(remove_unused_layers no)
			(net "GND")
			(clearance 0)
		)
		(pad "P3_4" thru_hole circle
			(at 0 5.08)
			(size 1.52781 1.52781)
			(drill 1.01981)
			(layers "*.Cu" "*.Mask")
			(remove_unused_layers no)
			(net "GND")
			(clearance 0)
		)
		(pad "P3_5" thru_hole circle
			(at 7.62 7.62)
			(size 1.52781 1.52781)
			(drill 1.01981)
			(layers "*.Cu" "*.Mask")
			(remove_unused_layers no)
			(net "GND")
			(clearance 0)
		)
		(pad "P3_6" thru_hole circle
			(at 5.08 7.62)
			(size 1.52781 1.52781)
			(drill 1.01981)
			(layers "*.Cu" "*.Mask")
			(remove_unused_layers no)
			(net "GND")
			(clearance 0)
		)
		(pad "P3_7" thru_hole circle
			(at 2.54 7.62)
			(size 1.52781 1.52781)
			(drill 1.01981)
			(layers "*.Cu" "*.Mask")
			(remove_unused_layers no)
			(net "GND")
			(clearance 0)
		)
		(pad "P3_8" thru_hole circle
			(at 0 7.62)
			(size 1.52781 1.52781)
			(drill 1.01981)
			(layers "*.Cu" "*.Mask")
			(remove_unused_layers no)
			(net "GND")
			(clearance 0)
		)
		(pad "P4_1" thru_hole circle
			(at 7.62 13.97)
			(size 1.52781 1.52781)
			(drill 1.01981)
			(layers "*.Cu" "*.Mask")
			(remove_unused_layers no)
			(net "GND")
			(clearance 0)
		)
		(pad "P4_2" thru_hole circle
			(at 5.08 13.97)
			(size 1.52781 1.52781)
			(drill 1.01981)
			(layers "*.Cu" "*.Mask")
			(remove_unused_layers no)
			(net "GND")
			(clearance 0)
		)
		(pad "P4_3" thru_hole circle
			(at 2.54 13.97)
			(size 1.52781 1.52781)
			(drill 1.01981)
			(layers "*.Cu" "*.Mask")
			(remove_unused_layers no)
			(net "GND")
			(clearance 0)
		)
		(pad "P4_4" thru_hole circle
			(at 0 13.97)
			(size 1.52781 1.52781)
			(drill 1.01981)
			(layers "*.Cu" "*.Mask")
			(remove_unused_layers no)
			(net "GND")
			(clearance 0)
		)
		(pad "P4_5" thru_hole circle
			(at 7.62 16.51)
			(size 1.52781 1.52781)
			(drill 1.01981)
			(layers "*.Cu" "*.Mask")
			(remove_unused_layers no)
			(net "GND")
			(clearance 0)
		)
		(pad "P4_6" thru_hole circle
			(at 5.08 16.51)
			(size 1.52781 1.52781)
			(drill 1.01981)
			(layers "*.Cu" "*.Mask")
			(remove_unused_layers no)
			(net "GND")
			(clearance 0)
		)
		(pad "P4_7" thru_hole circle
			(at 2.54 16.51)
			(size 1.52781 1.52781)
			(drill 1.01981)
			(layers "*.Cu" "*.Mask")
			(remove_unused_layers no)
			(net "GND")
			(clearance 0)
		)
		(pad "P4_8" thru_hole circle
			(at 0 16.51)
			(size 1.52781 1.52781)
			(drill 1.01981)
			(layers "*.Cu" "*.Mask")
			(remove_unused_layers no)
			(net "GND")
			(clearance 0)
		)
		(zone
			(layers "F.Cu" "B.Cu" "In1.Cu" "In2.Cu" "In3.Cu" "In4.Cu" "In5.Cu" "In6.Cu"
				"In7.Cu" "In8.Cu"
			)
			(hatch none 0.5)
			(connect_pads
				(clearance 0)
			)
			(min_thickness 0.25)
			(keepout
				(tracks not_allowed)
				(vias allowed)
				(pads allowed)
				(copperpour not_allowed)
				(footprints allowed)
			)
			(placement
				(enabled no)
				(sheetname "")
			)
			(fill
				(thermal_gap 0.5)
				(thermal_bridge_width 0.5)
				(island_removal_mode 0)
			)
			(polygon
				(pts
					(arc
						(start 315.042296 -101.454966)
						(mid 307.777896 -101.454966)
						(end 315.042296 -101.454966)
					)
				)
			)
		)
		(zone
			(layer "B.Cu")
			(hatch none 0.5)
			(connect_pads
				(clearance 0)
			)
			(min_thickness 0.25)
			(keepout
				(tracks allowed)
				(vias not_allowed)
				(pads allowed)
				(copperpour not_allowed)
				(footprints allowed)
			)
			(placement
				(enabled no)
				(sheetname "")
			)
			(fill
				(thermal_gap 0.5)
				(thermal_bridge_width 0.5)
				(island_removal_mode 0)
			)
			(polygon
				(pts
					(xy 310.582818 -90.217244) (xy 310.582818 -55.542688) (xy 319.857374 -55.542688) (xy 319.857374 -90.217244)
				)
			)
		)
	)
	(footprint ""
		(layer "F.Cu")
		(at 164.714174 -127.889)
		(property "Reference" "PC121"
			(at 0 0 0)
			(layer "F.SilkS")
			(hide yes)
			(effects
				(font
					(size 1.27 1.27)
				)
			)
		)
		(property "Value" ""
			(at 0 0 0)
			(layer "F.Fab")
			(effects
				(font
					(size 1.27 1.27)
				)
			)
		)
		(duplicate_pad_numbers_are_jumpers no)
		(fp_line
			(start -2.2098 -0.9398)
			(end 2.2098 -0.9398)
			(stroke
				(width 0.1524)
				(type default)
			)
			(layer "F.SilkS")
		)
		(fp_line
			(start -2.2098 0.9398)
			(end -2.2098 -0.9398)
			(stroke
				(width 0.1524)
				(type default)
			)
			(layer "F.SilkS")
		)
		(fp_line
			(start 2.2098 -0.9398)
			(end 2.2098 0.9398)
			(stroke
				(width 0.1524)
				(type default)
			)
			(layer "F.SilkS")
		)
		(fp_line
			(start 2.2098 0.9398)
			(end -2.2098 0.9398)
			(stroke
				(width 0.1524)
				(type default)
			)
			(layer "F.SilkS")
		)
		(fp_line
			(start -1.700022 -0.899922)
			(end 1.700022 -0.899922)
			(stroke
				(width 0.1)
				(type default)
			)
			(layer "F.Fab")
		)
		(fp_line
			(start -1.700022 0.899922)
			(end -1.700022 -0.899922)
			(stroke
				(width 0.1)
				(type default)
			)
			(layer "F.Fab")
		)
		(fp_line
			(start 1.700022 -0.899922)
			(end 1.700022 0.899922)
			(stroke
				(width 0.1)
				(type default)
			)
			(layer "F.Fab")
		)
		(fp_line
			(start 1.700022 0.899922)
			(end -1.700022 0.899922)
			(stroke
				(width 0.1)
				(type default)
			)
			(layer "F.Fab")
		)
		(pad "1" smd rect
			(at -1.4732 0 180)
			(size 1.1684 1.5748)
			(layers "F.Cu" "F.Mask" "F.Paste")
			(net "P52V_HS_FILTER")
		)
		(pad "2" smd rect
			(at 1.4732 0 180)
			(size 1.1684 1.5748)
			(layers "F.Cu" "F.Mask" "F.Paste")
			(net "GND")
		)
	)
	(footprint ""
		(layer "F.Cu")
		(at 264.808716 -36.389818)
		(property "Reference" "PC5"
			(at 0 0 0)
			(layer "F.SilkS")
			(hide yes)
			(effects
				(font
					(size 1.27 1.27)
				)
			)
		)
		(property "Value" ""
			(at 0 0 0)
			(layer "F.Fab")
			(effects
				(font
					(size 1.27 1.27)
				)
			)
		)
		(duplicate_pad_numbers_are_jumpers no)
		(fp_line
			(start -0.7874 -0.4064)
			(end 0.7874 -0.4064)
			(stroke
				(width 0.1524)
				(type default)
			)
			(layer "F.SilkS")
		)
		(fp_line
			(start -0.7874 0.4064)
			(end -0.7874 -0.4064)
			(stroke
				(width 0.1524)
				(type default)
			)
			(layer "F.SilkS")
		)
		(fp_line
			(start 0.7874 -0.4064)
			(end 0.7874 0.4064)
			(stroke
				(width 0.1524)
				(type default)
			)
			(layer "F.SilkS")
		)
		(fp_line
			(start 0.7874 0.4064)
			(end -0.7874 0.4064)
			(stroke
				(width 0.1524)
				(type default)
			)
			(layer "F.SilkS")
		)
		(fp_line
			(start -0.67945 -0.305054)
			(end -0.12065 -0.305054)
			(stroke
				(width 0.1)
				(type default)
			)
			(layer "F.Fab")
		)
		(fp_line
			(start -0.67945 0.3048)
			(end -0.67945 -0.305054)
			(stroke
				(width 0.1)
				(type default)
			)
			(layer "F.Fab")
		)
		(fp_line
			(start -0.12065 -0.305054)
			(end -0.12065 -0.2794)
			(stroke
				(width 0.1)
				(type default)
			)
			(layer "F.Fab")
		)
		(fp_line
			(start -0.12065 -0.2794)
			(end 0.12065 -0.2794)
			(stroke
				(width 0.1)
				(type default)
			)
			(layer "F.Fab")
		)
		(fp_line
			(start -0.12065 0.2794)
			(end -0.12065 0.3048)
			(stroke
				(width 0.1)
				(type default)
			)
			(layer "F.Fab")
		)
		(fp_line
			(start -0.12065 0.3048)
			(end -0.67945 0.3048)
			(stroke
				(width 0.1)
				(type default)
			)
			(layer "F.Fab")
		)
		(fp_line
			(start 0.120396 0.2794)
			(end -0.12065 0.2794)
			(stroke
				(width 0.1)
				(type default)
			)
			(layer "F.Fab")
		)
		(fp_line
			(start 0.120396 0.3048)
			(end 0.120396 0.2794)
			(stroke
				(width 0.1)
				(type default)
			)
			(layer "F.Fab")
		)
		(fp_line
			(start 0.12065 -0.3048)
			(end 0.67945 -0.3048)
			(stroke
				(width 0.1)
				(type default)
			)
			(layer "F.Fab")
		)
		(fp_line
			(start 0.12065 -0.2794)
			(end 0.12065 -0.3048)
			(stroke
				(width 0.1)
				(type default)
			)
			(layer "F.Fab")
		)
		(fp_line
			(start 0.67945 -0.3048)
			(end 0.67945 0.3048)
			(stroke
				(width 0.1)
				(type default)
			)
			(layer "F.Fab")
		)
		(fp_line
			(start 0.67945 0.3048)
			(end 0.120396 0.3048)
			(stroke
				(width 0.1)
				(type default)
			)
			(layer "F.Fab")
		)
		(pad "1" smd circle
			(at -0.40005 0)
			(size 0 0)
			(layers "F.Cu" "F.Mask" "F.Paste")
			(net "GND_FIELD_SIGNAL")
		)
		(pad "2" smd circle
			(at 0.40005 0)
			(size 0 0)
			(layers "F.Cu" "F.Mask" "F.Paste")
			(net "P52V_HS1_DVCC")
		)
	)
	(footprint ""
		(layer "F.Cu")
		(at 44.45 -25.527)
		(property "Reference" "H21"
			(at -1.016 -3.40233 0)
			(unlocked yes)
			(layer "F.SilkS")
			(effects
				(font
					(size 0.7874 0.5842)
					(thickness 0.1524)
				)
				(justify left)
			)
		)
		(property "Value" ""
			(at 0 0 0)
			(layer "F.Fab")
			(effects
				(font
					(size 1.27 1.27)
				)
			)
		)
		(duplicate_pad_numbers_are_jumpers no)
		(fp_circle
			(center 0 0)
			(end 2.4003 0)
			(stroke
				(width 0.1524)
				(type default)
			)
			(fill no)
			(layer "F.SilkS")
		)
		(fp_circle
			(center 0 0)
			(end 6.5913 0)
			(stroke
				(width 0.1524)
				(type default)
			)
			(fill no)
			(layer "B.SilkS")
		)
		(fp_circle
			(center 0 0)
			(end 6.5913 0)
			(stroke
				(width 0.1)
				(type default)
			)
			(fill no)
			(layer "B.Fab")
		)
		(fp_circle
			(center 0 0)
			(end 2.4003 0)
			(stroke
				(width 0.1)
				(type default)
			)
			(fill no)
			(layer "F.Fab")
		)
		(pad "" np_thru_hole circle
			(at 0 0)
			(size 3.175 3.175)
			(drill 3.175)
			(layers "*.Cu" "*.Mask")
			(clearance 0.381)
			(thermal_gap 0.381)
		)
		(zone
			(layers "F.Cu" "B.Cu" "In1.Cu" "In2.Cu" "In3.Cu" "In4.Cu" "In5.Cu" "In6.Cu"
				"In7.Cu" "In8.Cu"
			)
			(hatch none 0.5)
			(connect_pads
				(clearance 0)
			)
			(min_thickness 0.25)
			(keepout
				(tracks not_allowed)
				(vias allowed)
				(pads allowed)
				(copperpour not_allowed)
				(footprints allowed)
			)
			(placement
				(enabled no)
				(sheetname "")
			)
			(fill
				(thermal_gap 0.5)
				(thermal_bridge_width 0.5)
				(island_removal_mode 0)
			)
			(polygon
				(pts
					(arc
						(start 46.5455 -25.527)
						(mid 42.3545 -25.527)
						(end 46.5455 -25.527)
					)
				)
			)
		)
	)
	(footprint ""
		(layer "F.Cu")
		(at 278.13 -50.673)
		(property "Reference" "PR19"
			(at 0 0 0)
			(layer "F.SilkS")
			(hide yes)
			(effects
				(font
					(size 1.27 1.27)
				)
			)
		)
		(property "Value" ""
			(at 0 0 0)
			(layer "F.Fab")
			(effects
				(font
					(size 1.27 1.27)
				)
			)
		)
		(duplicate_pad_numbers_are_jumpers no)
		(fp_line
			(start -1.651 -0.8382)
			(end 1.651 -0.8382)
			(stroke
				(width 0.1524)
				(type default)
			)
			(layer "F.SilkS")
		)
		(fp_line
			(start -1.651 0.8382)
			(end -1.651 -0.8382)
			(stroke
				(width 0.1524)
				(type default)
			)
			(layer "F.SilkS")
		)
		(fp_line
			(start 1.651 -0.8382)
			(end 1.651 0.8382)
			(stroke
				(width 0.1524)
				(type default)
			)
			(layer "F.SilkS")
		)
		(fp_line
			(start 1.651 0.8382)
			(end -1.651 0.8382)
			(stroke
				(width 0.1524)
				(type default)
			)
			(layer "F.SilkS")
		)
		(fp_line
			(start -1.559814 -0.7366)
			(end -1.559814 0.7366)
			(stroke
				(width 0.1)
				(type default)
			)
			(layer "F.Fab")
		)
		(fp_line
			(start -1.559814 0.7366)
			(end -1.524 0.7366)
			(stroke
				(width 0.1)
				(type default)
			)
			(layer "F.Fab")
		)
		(fp_line
			(start -1.524 -0.7366)
			(end -1.559814 -0.7366)
			(stroke
				(width 0.1)
				(type default)
			)
			(layer "F.Fab")
		)
		(fp_line
			(start -1.524 0.7366)
			(end 1.524 0.7366)
			(stroke
				(width 0.1)
				(type default)
			)
			(layer "F.Fab")
		)
		(fp_line
			(start 1.524 -0.7366)
			(end -1.524 -0.7366)
			(stroke
				(width 0.1)
				(type default)
			)
			(layer "F.Fab")
		)
		(fp_line
			(start 1.524 0.7366)
			(end 1.560576 0.7366)
			(stroke
				(width 0.1)
				(type default)
			)
			(layer "F.Fab")
		)
		(fp_line
			(start 1.560576 -0.7366)
			(end 1.524 -0.7366)
			(stroke
				(width 0.1)
				(type default)
			)
			(layer "F.Fab")
		)
		(fp_line
			(start 1.560576 0.7366)
			(end 1.560576 -0.7366)
			(stroke
				(width 0.1)
				(type default)
			)
			(layer "F.Fab")
		)
		(pad "1" smd rect
			(at -0.94996 0 180)
			(size 1.1176 1.3716)
			(layers "F.Cu" "F.Mask" "F.Paste")
			(net "P52V_HS")
		)
		(pad "2" smd rect
			(at 0.94996 0 180)
			(size 1.1176 1.3716)
			(layers "F.Cu" "F.Mask" "F.Paste")
			(net "P52V_HS1_ISET")
		)
	)
	(footprint ""
		(layer "F.Cu")
		(at 205.613 -67.056 -90)
		(property "Reference" "D3"
			(at 3.048 -0.02667 90)
			(unlocked yes)
			(layer "F.SilkS")
			(effects
				(font
					(size 0.7874 0.5842)
					(thickness 0.1524)
				)
				(justify left)
			)
		)
		(property "Value" ""
			(at 0 0 270)
			(layer "F.Fab")
			(effects
				(font
					(size 1.27 1.27)
				)
			)
		)
		(duplicate_pad_numbers_are_jumpers no)
		(fp_line
			(start -0.90678 0.4826)
			(end -0.90678 -0.4699)
			(stroke
				(width 0.1524)
				(type default)
			)
			(layer "F.SilkS")
		)
		(fp_line
			(start 0.90678 0.4826)
			(end -0.90678 0.4826)
			(stroke
				(width 0.1524)
				(type default)
			)
			(layer "F.SilkS")
		)
		(fp_line
			(start 1.03378 0.4826)
			(end -0.79248 0.4826)
			(stroke
				(width 0.1524)
				(type default)
			)
			(layer "F.SilkS")
		)
		(fp_line
			(start 1.16078 0.4826)
			(end -0.64008 0.4826)
			(stroke
				(width 0.1524)
				(type default)
			)
			(layer "F.SilkS")
		)
		(fp_line
			(start -0.89408 -0.4826)
			(end 0.90678 -0.4826)
			(stroke
				(width 0.1524)
				(type default)
			)
			(layer "F.SilkS")
		)
		(fp_line
			(start -0.79248 -0.4826)
			(end 1.03378 -0.4826)
			(stroke
				(width 0.1524)
				(type default)
			)
			(layer "F.SilkS")
		)
		(fp_line
			(start -0.64008 -0.4826)
			(end 1.16078 -0.4826)
			(stroke
				(width 0.1524)
				(type default)
			)
			(layer "F.SilkS")
		)
		(fp_line
			(start 0.90678 -0.4826)
			(end 0.90678 0.4826)
			(stroke
				(width 0.1524)
				(type default)
			)
			(layer "F.SilkS")
		)
		(fp_line
			(start 1.03378 -0.4826)
			(end 1.03378 0.4826)
			(stroke
				(width 0.1524)
				(type default)
			)
			(layer "F.SilkS")
		)
		(fp_line
			(start 1.16078 -0.4826)
			(end 1.16078 0.4826)
			(stroke
				(width 0.1524)
				(type default)
			)
			(layer "F.SilkS")
		)
		(fp_line
			(start -0.499872 0.249936)
			(end -0.499872 -0.249936)
			(stroke
				(width 0.1)
				(type default)
			)
			(layer "F.Fab")
		)
		(fp_line
			(start 0.499872 0.249936)
			(end -0.499872 0.249936)
			(stroke
				(width 0.1)
				(type default)
			)
			(layer "F.Fab")
		)
		(fp_line
			(start -0.499872 -0.249936)
			(end 0.499872 -0.249936)
			(stroke
				(width 0.1)
				(type default)
			)
			(layer "F.Fab")
		)
		(fp_line
			(start 0.499872 -0.249936)
			(end 0.499872 0.249936)
			(stroke
				(width 0.1)
				(type default)
			)
			(layer "F.Fab")
		)
		(pad "A" smd rect
			(at -0.47498 0 270)
			(size 0.6096 0.7112)
			(layers "F.Cu" "F.Mask" "F.Paste")
			(net "LED_D3_R")
		)
		(pad "C" smd rect
			(at 0.47498 0 270)
			(size 0.6096 0.7112)
			(layers "F.Cu" "F.Mask" "F.Paste")
			(net "GND")
		)
	)
	(footprint ""
		(layer "F.Cu")
		(at 108.839 -60.96)
		(property "Reference" "PC68"
			(at -1.524 -3.52933 0)
			(unlocked yes)
			(layer "F.SilkS")
			(effects
				(font
					(size 0.7874 0.5842)
					(thickness 0.1524)
				)
				(justify left)
			)
		)
		(property "Value" ""
			(at 0 0 0)
			(layer "F.Fab")
			(effects
				(font
					(size 1.27 1.27)
				)
			)
		)
		(duplicate_pad_numbers_are_jumpers no)
		(fp_line
			(start 5.2578 2.499868)
			(end -5.2578 2.499868)
			(stroke
				(width 0.1524)
				(type default)
			)
			(layer "F.SilkS")
		)
		(fp_circle
			(center 0 2.499868)
			(end 5.2578 2.499868)
			(stroke
				(width 0.1524)
				(type default)
			)
			(fill no)
			(layer "F.SilkS")
		)
		(fp_poly
			(pts
				(arc
					(start 5.2578 2.499868)
					(mid 0 7.757922)
					(end -5.2578 2.499868)
				)
			)
			(stroke
				(width 0)
				(type default)
			)
			(fill yes)
			(layer "F.SilkS")
		)
		(fp_circle
			(center 0 2.499868)
			(end 5.2578 2.499868)
			(stroke
				(width 0.1)
				(type default)
			)
			(fill no)
			(layer "F.Fab")
		)
		(pad "1" thru_hole rect
			(at 0 0 270)
			(size 1.524 1.524)
			(drill 1.016)
			(layers "*.Cu" "*.Mask")
			(remove_unused_layers no)
			(net "P12V_BRICK")
			(clearance 0)
			(padstack
				(mode front_inner_back)
				(layer "Inner"
					(shape circle)
					(size 1.524 1.524)
					(clearance 0)
				)
				(layer "B.Cu"
					(shape rect)
					(size 1.524 1.524)
					(clearance 0)
				)
			)
		)
		(pad "2" thru_hole circle
			(at 0 4.99999 270)
			(size 1.524 1.524)
			(drill 1.016)
			(layers "*.Cu" "*.Mask")
			(remove_unused_layers no)
			(net "GND")
			(clearance 0)
		)
	)
	(footprint ""
		(layer "F.Cu")
		(at 264.808716 -35.373818 180)
		(property "Reference" "PC7"
			(at 0 0 180)
			(layer "F.SilkS")
			(hide yes)
			(effects
				(font
					(size 1.27 1.27)
				)
			)
		)
		(property "Value" ""
			(at 0 0 180)
			(layer "F.Fab")
			(effects
				(font
					(size 1.27 1.27)
				)
			)
		)
		(duplicate_pad_numbers_are_jumpers no)
		(fp_line
			(start 0.7874 0.4064)
			(end -0.7874 0.4064)
			(stroke
				(width 0.1524)
				(type default)
			)
			(layer "F.SilkS")
		)
		(fp_line
			(start 0.7874 -0.4064)
			(end 0.7874 0.4064)
			(stroke
				(width 0.1524)
				(type default)
			)
			(layer "F.SilkS")
		)
		(fp_line
			(start -0.7874 0.4064)
			(end -0.7874 -0.4064)
			(stroke
				(width 0.1524)
				(type default)
			)
			(layer "F.SilkS")
		)
		(fp_line
			(start -0.7874 -0.4064)
			(end 0.7874 -0.4064)
			(stroke
				(width 0.1524)
				(type default)
			)
			(layer "F.SilkS")
		)
		(fp_line
			(start 0.67945 0.3048)
			(end 0.120396 0.3048)
			(stroke
				(width 0.1)
				(type default)
			)
			(layer "F.Fab")
		)
		(fp_line
			(start 0.67945 -0.3048)
			(end 0.67945 0.3048)
			(stroke
				(width 0.1)
				(type default)
			)
			(layer "F.Fab")
		)
		(fp_line
			(start 0.12065 -0.2794)
			(end 0.12065 -0.3048)
			(stroke
				(width 0.1)
				(type default)
			)
			(layer "F.Fab")
		)
		(fp_line
			(start 0.12065 -0.3048)
			(end 0.67945 -0.3048)
			(stroke
				(width 0.1)
				(type default)
			)
			(layer "F.Fab")
		)
		(fp_line
			(start 0.120396 0.3048)
			(end 0.120396 0.2794)
			(stroke
				(width 0.1)
				(type default)
			)
			(layer "F.Fab")
		)
		(fp_line
			(start 0.120396 0.2794)
			(end -0.12065 0.2794)
			(stroke
				(width 0.1)
				(type default)
			)
			(layer "F.Fab")
		)
		(fp_line
			(start -0.12065 0.3048)
			(end -0.67945 0.3048)
			(stroke
				(width 0.1)
				(type default)
			)
			(layer "F.Fab")
		)
		(fp_line
			(start -0.12065 0.2794)
			(end -0.12065 0.3048)
			(stroke
				(width 0.1)
				(type default)
			)
			(layer "F.Fab")
		)
		(fp_line
			(start -0.12065 -0.2794)
			(end 0.12065 -0.2794)
			(stroke
				(width 0.1)
				(type default)
			)
			(layer "F.Fab")
		)
		(fp_line
			(start -0.12065 -0.305054)
			(end -0.12065 -0.2794)
			(stroke
				(width 0.1)
				(type default)
			)
			(layer "F.Fab")
		)
		(fp_line
			(start -0.67945 0.3048)
			(end -0.67945 -0.305054)
			(stroke
				(width 0.1)
				(type default)
			)
			(layer "F.Fab")
		)
		(fp_line
			(start -0.67945 -0.305054)
			(end -0.12065 -0.305054)
			(stroke
				(width 0.1)
				(type default)
			)
			(layer "F.Fab")
		)
		(pad "1" smd circle
			(at -0.40005 0 180)
			(size 0 0)
			(layers "F.Cu" "F.Mask" "F.Paste")
			(net "P52V_HS1_TMR")
		)
		(pad "2" smd circle
			(at 0.40005 0 180)
			(size 0 0)
			(layers "F.Cu" "F.Mask" "F.Paste")
			(net "GND_FIELD_SIGNAL")
		)
	)
	(footprint ""
		(layer "F.Cu")
		(at 297.538394 -86.8045 180)
		(property "Reference" "PR6954"
			(at 0 0 180)
			(layer "F.SilkS")
			(hide yes)
			(effects
				(font
					(size 1.27 1.27)
				)
			)
		)
		(property "Value" ""
			(at 0 0 180)
			(layer "F.Fab")
			(effects
				(font
					(size 1.27 1.27)
				)
			)
		)
		(duplicate_pad_numbers_are_jumpers no)
		(fp_line
			(start 1.2954 0.5842)
			(end -1.2954 0.5842)
			(stroke
				(width 0.1524)
				(type default)
			)
			(layer "F.SilkS")
		)
		(fp_line
			(start 1.2954 -0.5842)
			(end 1.2954 0.5842)
			(stroke
				(width 0.1524)
				(type default)
			)
			(layer "F.SilkS")
		)
		(fp_line
			(start -1.2954 0.5842)
			(end -1.2954 -0.5842)
			(stroke
				(width 0.1524)
				(type default)
			)
			(layer "F.SilkS")
		)
		(fp_line
			(start -1.2954 -0.5842)
			(end 1.2954 -0.5842)
			(stroke
				(width 0.1524)
				(type default)
			)
			(layer "F.SilkS")
		)
		(fp_line
			(start 1.1938 0.4064)
			(end 0.8636 0.4064)
			(stroke
				(width 0.1)
				(type default)
			)
			(layer "F.Fab")
		)
		(fp_line
			(start 1.1938 -0.406654)
			(end 1.1938 0.4064)
			(stroke
				(width 0.1)
				(type default)
			)
			(layer "F.Fab")
		)
		(fp_line
			(start 0.8636 0.4572)
			(end -0.8636 0.4572)
			(stroke
				(width 0.1)
				(type default)
			)
			(layer "F.Fab")
		)
		(fp_line
			(start 0.8636 0.4064)
			(end 0.8636 0.4572)
			(stroke
				(width 0.1)
				(type default)
			)
			(layer "F.Fab")
		)
		(fp_line
			(start 0.8636 -0.406654)
			(end 1.1938 -0.406654)
			(stroke
				(width 0.1)
				(type default)
			)
			(layer "F.Fab")
		)
		(fp_line
			(start 0.8636 -0.4572)
			(end 0.8636 -0.406654)
			(stroke
				(width 0.1)
				(type default)
			)
			(layer "F.Fab")
		)
		(fp_line
			(start -0.8636 0.4572)
			(end -0.8636 0.4318)
			(stroke
				(width 0.1)
				(type default)
			)
			(layer "F.Fab")
		)
		(fp_line
			(start -0.8636 0.4318)
			(end -0.8636 0.4064)
			(stroke
				(width 0.1)
				(type default)
			)
			(layer "F.Fab")
		)
		(fp_line
			(start -0.8636 0.4064)
			(end -1.1938 0.4064)
			(stroke
				(width 0.1)
				(type default)
			)
			(layer "F.Fab")
		)
		(fp_line
			(start -0.8636 -0.406654)
			(end -0.8636 -0.4572)
			(stroke
				(width 0.1)
				(type default)
			)
			(layer "F.Fab")
		)
		(fp_line
			(start -0.8636 -0.4572)
			(end 0.8636 -0.4572)
			(stroke
				(width 0.1)
				(type default)
			)
			(layer "F.Fab")
		)
		(fp_line
			(start -1.1938 0.4064)
			(end -1.1938 -0.406654)
			(stroke
				(width 0.1)
				(type default)
			)
			(layer "F.Fab")
		)
		(fp_line
			(start -1.1938 -0.406654)
			(end -0.8636 -0.406654)
			(stroke
				(width 0.1)
				(type default)
			)
			(layer "F.Fab")
		)
		(pad "1" smd rect
			(at -0.7366 0 90)
			(size 0.7112 0.8128)
			(layers "F.Cu" "F.Mask" "F.Paste")
			(net "P52V_HS_4287_S2N")
		)
		(pad "2" smd rect
			(at 0.7366 0 90)
			(size 0.7112 0.8128)
			(layers "F.Cu" "F.Mask" "F.Paste")
			(net "P52V_HS1_SENSE_N_R2")
		)
	)
	(footprint ""
		(layer "F.Cu")
		(at 226.59594 -20.604988)
		(property "Reference" ""
			(at 0 0 0)
			(layer "F.SilkS")
			(hide yes)
			(effects
				(font
					(size 1.27 1.27)
				)
			)
		)
		(property "Value" ""
			(at 0 0 0)
			(layer "F.Fab")
			(effects
				(font
					(size 1.27 1.27)
				)
			)
		)
		(duplicate_pad_numbers_are_jumpers no)
		(pad "1" smd circle
			(at 0 0)
			(size 0.9906 0.9906)
			(layers "F.Cu" "F.Mask" "F.Paste")
			(net "Net_155")
		)
		(zone
			(layer "F.Cu")
			(hatch none 0.5)
			(connect_pads
				(clearance 0)
			)
			(min_thickness 0.25)
			(keepout
				(tracks not_allowed)
				(vias allowed)
				(pads allowed)
				(copperpour not_allowed)
				(footprints allowed)
			)
			(placement
				(enabled no)
				(sheetname "")
			)
			(fill
				(thermal_gap 0.5)
				(thermal_bridge_width 0.5)
				(island_removal_mode 0)
			)
			(polygon
				(pts
					(arc
						(start 228.22154 -20.604988)
						(mid 224.97034 -20.604988)
						(end 228.22154 -20.604988)
					)
				)
			)
		)
	)
	(footprint ""
		(layer "F.Cu")
		(at 174.0662 -12.4968 90)
		(property "Reference" "PC100"
			(at 0 0 90)
			(layer "F.SilkS")
			(hide yes)
			(effects
				(font
					(size 1.27 1.27)
				)
			)
		)
		(property "Value" ""
			(at 0 0 90)
			(layer "F.Fab")
			(effects
				(font
					(size 1.27 1.27)
				)
			)
		)
		(duplicate_pad_numbers_are_jumpers no)
		(fp_line
			(start 1.524 -0.762)
			(end 1.524 0.762)
			(stroke
				(width 0.1524)
				(type default)
			)
			(layer "F.SilkS")
		)
		(fp_line
			(start -1.524 -0.762)
			(end 1.524 -0.762)
			(stroke
				(width 0.1524)
				(type default)
			)
			(layer "F.SilkS")
		)
		(fp_line
			(start 1.524 0.762)
			(end -1.524 0.762)
			(stroke
				(width 0.1524)
				(type default)
			)
			(layer "F.SilkS")
		)
		(fp_line
			(start -1.524 0.762)
			(end -1.524 -0.762)
			(stroke
				(width 0.1524)
				(type default)
			)
			(layer "F.SilkS")
		)
		(fp_line
			(start 1.1049 -0.724916)
			(end -1.1049 -0.724916)
			(stroke
				(width 0.1)
				(type default)
			)
			(layer "F.Fab")
		)
		(fp_line
			(start -1.1049 -0.724916)
			(end -1.1049 0.724916)
			(stroke
				(width 0.1)
				(type default)
			)
			(layer "F.Fab")
		)
		(fp_line
			(start 1.1049 0.724916)
			(end 1.1049 -0.724916)
			(stroke
				(width 0.1)
				(type default)
			)
			(layer "F.Fab")
		)
		(fp_line
			(start -1.1049 0.724916)
			(end 1.1049 0.724916)
			(stroke
				(width 0.1)
				(type default)
			)
			(layer "F.Fab")
		)
		(pad "1" smd rect
			(at -0.889 0 270)
			(size 1.016 1.27)
			(layers "F.Cu" "F.Mask" "F.Paste")
			(net "SW_P12V_FILT__P3V3_AUX")
		)
		(pad "2" smd rect
			(at 0.889 0 270)
			(size 1.016 1.27)
			(layers "F.Cu" "F.Mask" "F.Paste")
			(net "GND")
		)
	)
	(footprint ""
		(layer "F.Cu")
		(at 278.003 -44.069 180)
		(property "Reference" "PR20"
			(at 0 0 180)
			(layer "F.SilkS")
			(hide yes)
			(effects
				(font
					(size 1.27 1.27)
				)
			)
		)
		(property "Value" ""
			(at 0 0 180)
			(layer "F.Fab")
			(effects
				(font
					(size 1.27 1.27)
				)
			)
		)
		(duplicate_pad_numbers_are_jumpers no)
		(fp_line
			(start 0.7874 0.4064)
			(end -0.7874 0.4064)
			(stroke
				(width 0.1524)
				(type default)
			)
			(layer "F.SilkS")
		)
		(fp_line
			(start 0.7874 -0.4064)
			(end 0.7874 0.4064)
			(stroke
				(width 0.1524)
				(type default)
			)
			(layer "F.SilkS")
		)
		(fp_line
			(start -0.7874 0.4064)
			(end -0.7874 -0.4064)
			(stroke
				(width 0.1524)
				(type default)
			)
			(layer "F.SilkS")
		)
		(fp_line
			(start -0.7874 -0.4064)
			(end 0.7874 -0.4064)
			(stroke
				(width 0.1524)
				(type default)
			)
			(layer "F.SilkS")
		)
		(fp_line
			(start 0.67945 0.3048)
			(end 0.120396 0.3048)
			(stroke
				(width 0.1)
				(type default)
			)
			(layer "F.Fab")
		)
		(fp_line
			(start 0.67945 -0.3048)
			(end 0.67945 0.3048)
			(stroke
				(width 0.1)
				(type default)
			)
			(layer "F.Fab")
		)
		(fp_line
			(start 0.12065 -0.2794)
			(end 0.12065 -0.3048)
			(stroke
				(width 0.1)
				(type default)
			)
			(layer "F.Fab")
		)
		(fp_line
			(start 0.12065 -0.3048)
			(end 0.67945 -0.3048)
			(stroke
				(width 0.1)
				(type default)
			)
			(layer "F.Fab")
		)
		(fp_line
			(start 0.120396 0.3048)
			(end 0.120396 0.2794)
			(stroke
				(width 0.1)
				(type default)
			)
			(layer "F.Fab")
		)
		(fp_line
			(start 0.120396 0.2794)
			(end -0.12065 0.2794)
			(stroke
				(width 0.1)
				(type default)
			)
			(layer "F.Fab")
		)
		(fp_line
			(start -0.12065 0.3048)
			(end -0.67945 0.3048)
			(stroke
				(width 0.1)
				(type default)
			)
			(layer "F.Fab")
		)
		(fp_line
			(start -0.12065 0.2794)
			(end -0.12065 0.3048)
			(stroke
				(width 0.1)
				(type default)
			)
			(layer "F.Fab")
		)
		(fp_line
			(start -0.12065 -0.2794)
			(end 0.12065 -0.2794)
			(stroke
				(width 0.1)
				(type default)
			)
			(layer "F.Fab")
		)
		(fp_line
			(start -0.12065 -0.305054)
			(end -0.12065 -0.2794)
			(stroke
				(width 0.1)
				(type default)
			)
			(layer "F.Fab")
		)
		(fp_line
			(start -0.67945 0.3048)
			(end -0.67945 -0.305054)
			(stroke
				(width 0.1)
				(type default)
			)
			(layer "F.Fab")
		)
		(fp_line
			(start -0.67945 -0.305054)
			(end -0.12065 -0.305054)
			(stroke
				(width 0.1)
				(type default)
			)
			(layer "F.Fab")
		)
		(pad "1" smd circle
			(at -0.40005 0 180)
			(size 0 0)
			(layers "F.Cu" "F.Mask" "F.Paste")
			(net "P52V_HS1_ISTART")
		)
		(pad "2" smd circle
			(at 0.40005 0 180)
			(size 0 0)
			(layers "F.Cu" "F.Mask" "F.Paste")
			(net "GND_FIELD_SIGNAL")
		)
	)
	(footprint ""
		(layer "F.Cu")
		(at 291.74059 -31.727902)
		(property "Reference" "PJ1"
			(at -2.18059 -1.011428 0)
			(unlocked yes)
			(layer "F.SilkS")
			(effects
				(font
					(size 0.7874 0.5842)
					(thickness 0.1524)
				)
				(justify left)
			)
		)
		(property "Value" ""
			(at 0 0 0)
			(layer "F.Fab")
			(effects
				(font
					(size 1.27 1.27)
				)
			)
		)
		(duplicate_pad_numbers_are_jumpers no)
		(pad "1" smd circle
			(at -0.7493 0 90)
			(size 0 0)
			(layers "F.Cu" "F.Mask" "F.Paste")
			(net "GND_FIELD_SIGNAL")
		)
		(pad "2" smd rect
			(at 0.7493 0 270)
			(size 0.7112 0.8128)
			(layers "F.Cu" "F.Mask" "F.Paste")
			(net "GND")
		)
		(zone
			(layer "F.Cu")
			(hatch none 0.5)
			(connect_pads
				(clearance 0)
			)
			(min_thickness 0.25)
			(keepout
				(tracks allowed)
				(vias not_allowed)
				(pads allowed)
				(copperpour not_allowed)
				(footprints allowed)
			)
			(placement
				(enabled no)
				(sheetname "")
			)
			(fill
				(thermal_gap 0.5)
				(thermal_bridge_width 0.5)
				(island_removal_mode 0)
			)
			(polygon
				(pts
					(xy 292.94709 -32.134302) (xy 290.55949 -32.134302) (xy 290.55949 -31.316676) (xy 292.94709 -31.316676)
				)
			)
		)
	)
	(footprint ""
		(layer "F.Cu")
		(at 170.053 -12.4968 90)
		(property "Reference" "PC566"
			(at 0 0 90)
			(layer "F.SilkS")
			(hide yes)
			(effects
				(font
					(size 1.27 1.27)
				)
			)
		)
		(property "Value" ""
			(at 0 0 90)
			(layer "F.Fab")
			(effects
				(font
					(size 1.27 1.27)
				)
			)
		)
		(duplicate_pad_numbers_are_jumpers no)
		(fp_line
			(start 1.524 -0.762)
			(end 1.524 0.762)
			(stroke
				(width 0.1524)
				(type default)
			)
			(layer "F.SilkS")
		)
		(fp_line
			(start -1.524 -0.762)
			(end 1.524 -0.762)
			(stroke
				(width 0.1524)
				(type default)
			)
			(layer "F.SilkS")
		)
		(fp_line
			(start 1.524 0.762)
			(end -1.524 0.762)
			(stroke
				(width 0.1524)
				(type default)
			)
			(layer "F.SilkS")
		)
		(fp_line
			(start -1.524 0.762)
			(end -1.524 -0.762)
			(stroke
				(width 0.1524)
				(type default)
			)
			(layer "F.SilkS")
		)
		(fp_line
			(start 1.1049 -0.724916)
			(end -1.1049 -0.724916)
			(stroke
				(width 0.1)
				(type default)
			)
			(layer "F.Fab")
		)
		(fp_line
			(start -1.1049 -0.724916)
			(end -1.1049 0.724916)
			(stroke
				(width 0.1)
				(type default)
			)
			(layer "F.Fab")
		)
		(fp_line
			(start 1.1049 0.724916)
			(end 1.1049 -0.724916)
			(stroke
				(width 0.1)
				(type default)
			)
			(layer "F.Fab")
		)
		(fp_line
			(start -1.1049 0.724916)
			(end 1.1049 0.724916)
			(stroke
				(width 0.1)
				(type default)
			)
			(layer "F.Fab")
		)
		(pad "1" smd rect
			(at -0.889 0 270)
			(size 1.016 1.27)
			(layers "F.Cu" "F.Mask" "F.Paste")
			(net "SW_P12V_FILT__P3V3_AUX")
		)
		(pad "2" smd rect
			(at 0.889 0 270)
			(size 1.016 1.27)
			(layers "F.Cu" "F.Mask" "F.Paste")
			(net "GND")
		)
	)
	(footprint ""
		(layer "F.Cu")
		(at 96.905826 -127.889)
		(property "Reference" "PC49"
			(at 0 0 0)
			(layer "F.SilkS")
			(hide yes)
			(effects
				(font
					(size 1.27 1.27)
				)
			)
		)
		(property "Value" ""
			(at 0 0 0)
			(layer "F.Fab")
			(effects
				(font
					(size 1.27 1.27)
				)
			)
		)
		(duplicate_pad_numbers_are_jumpers no)
		(fp_line
			(start -2.2098 -0.9398)
			(end 2.2098 -0.9398)
			(stroke
				(width 0.1524)
				(type default)
			)
			(layer "F.SilkS")
		)
		(fp_line
			(start -2.2098 0.9398)
			(end -2.2098 -0.9398)
			(stroke
				(width 0.1524)
				(type default)
			)
			(layer "F.SilkS")
		)
		(fp_line
			(start 2.2098 -0.9398)
			(end 2.2098 0.9398)
			(stroke
				(width 0.1524)
				(type default)
			)
			(layer "F.SilkS")
		)
		(fp_line
			(start 2.2098 0.9398)
			(end -2.2098 0.9398)
			(stroke
				(width 0.1524)
				(type default)
			)
			(layer "F.SilkS")
		)
		(fp_line
			(start -1.700022 -0.899922)
			(end 1.700022 -0.899922)
			(stroke
				(width 0.1)
				(type default)
			)
			(layer "F.Fab")
		)
		(fp_line
			(start -1.700022 0.899922)
			(end -1.700022 -0.899922)
			(stroke
				(width 0.1)
				(type default)
			)
			(layer "F.Fab")
		)
		(fp_line
			(start 1.700022 -0.899922)
			(end 1.700022 0.899922)
			(stroke
				(width 0.1)
				(type default)
			)
			(layer "F.Fab")
		)
		(fp_line
			(start 1.700022 0.899922)
			(end -1.700022 0.899922)
			(stroke
				(width 0.1)
				(type default)
			)
			(layer "F.Fab")
		)
		(pad "1" smd rect
			(at -1.4732 0 180)
			(size 1.1684 1.5748)
			(layers "F.Cu" "F.Mask" "F.Paste")
			(net "P52V_HS_FILTER")
		)
		(pad "2" smd rect
			(at 1.4732 0 180)
			(size 1.1684 1.5748)
			(layers "F.Cu" "F.Mask" "F.Paste")
			(net "GND")
		)
	)
	(footprint ""
		(layer "F.Cu")
		(at 162.047174 -136.906 90)
		(property "Reference" "PC115"
			(at 6.19633 0.766826 0)
			(unlocked yes)
			(layer "F.SilkS")
			(effects
				(font
					(size 0.7874 0.5842)
					(thickness 0.1524)
				)
				(justify left)
			)
		)
		(property "Value" ""
			(at 0 0 90)
			(layer "F.Fab")
			(effects
				(font
					(size 1.27 1.27)
				)
			)
		)
		(duplicate_pad_numbers_are_jumpers no)
		(fp_line
			(start 5.2578 2.499868)
			(end -5.2578 2.499868)
			(stroke
				(width 0.1524)
				(type default)
			)
			(layer "F.SilkS")
		)
		(fp_circle
			(center 0 2.500122)
			(end 0 7.758176)
			(stroke
				(width 0.1524)
				(type default)
			)
			(fill no)
			(layer "F.SilkS")
		)
		(fp_poly
			(pts
				(arc
					(start 5.2578 2.499868)
					(mid 0 7.757922)
					(end -5.2578 2.499868)
				)
			)
			(stroke
				(width 0)
				(type default)
			)
			(fill yes)
			(layer "F.SilkS")
		)
		(fp_circle
			(center 0 2.500122)
			(end 0 7.758176)
			(stroke
				(width 0.1)
				(type default)
			)
			(fill no)
			(layer "F.Fab")
		)
		(pad "1" thru_hole rect
			(at 0 0)
			(size 1.5748 1.5748)
			(drill 1.0668)
			(layers "*.Cu" "*.Mask")
			(remove_unused_layers no)
			(net "P52V_HS_FILTER")
			(clearance 0)
			(padstack
				(mode front_inner_back)
				(layer "Inner"
					(shape circle)
					(size 1.5748 1.5748)
					(clearance 0)
				)
				(layer "B.Cu"
					(shape rect)
					(size 1.5748 1.5748)
					(clearance 0)
				)
			)
		)
		(pad "2" thru_hole circle
			(at 0 4.99999)
			(size 1.5748 1.5748)
			(drill 1.0668)
			(layers "*.Cu" "*.Mask")
			(remove_unused_layers no)
			(net "GND")
			(clearance 0)
		)
	)
	(footprint ""
		(layer "F.Cu")
		(at 139.065 -60.325)
		(property "Reference" "PR59"
			(at 0 0 0)
			(layer "F.SilkS")
			(hide yes)
			(effects
				(font
					(size 1.27 1.27)
				)
			)
		)
		(property "Value" ""
			(at 0 0 0)
			(layer "F.Fab")
			(effects
				(font
					(size 1.27 1.27)
				)
			)
		)
		(duplicate_pad_numbers_are_jumpers no)
		(fp_line
			(start -1.651 -0.8382)
			(end 1.651 -0.8382)
			(stroke
				(width 0.1524)
				(type default)
			)
			(layer "F.SilkS")
		)
		(fp_line
			(start -1.651 0.8382)
			(end -1.651 -0.8382)
			(stroke
				(width 0.1524)
				(type default)
			)
			(layer "F.SilkS")
		)
		(fp_line
			(start 1.651 -0.8382)
			(end 1.651 0.8382)
			(stroke
				(width 0.1524)
				(type default)
			)
			(layer "F.SilkS")
		)
		(fp_line
			(start 1.651 0.8382)
			(end -1.651 0.8382)
			(stroke
				(width 0.1524)
				(type default)
			)
			(layer "F.SilkS")
		)
		(fp_line
			(start -1.559814 -0.7366)
			(end -1.559814 0.7366)
			(stroke
				(width 0.1)
				(type default)
			)
			(layer "F.Fab")
		)
		(fp_line
			(start -1.559814 0.7366)
			(end -1.524 0.7366)
			(stroke
				(width 0.1)
				(type default)
			)
			(layer "F.Fab")
		)
		(fp_line
			(start -1.524 -0.7366)
			(end -1.559814 -0.7366)
			(stroke
				(width 0.1)
				(type default)
			)
			(layer "F.Fab")
		)
		(fp_line
			(start -1.524 0.7366)
			(end 1.524 0.7366)
			(stroke
				(width 0.1)
				(type default)
			)
			(layer "F.Fab")
		)
		(fp_line
			(start 1.524 -0.7366)
			(end -1.524 -0.7366)
			(stroke
				(width 0.1)
				(type default)
			)
			(layer "F.Fab")
		)
		(fp_line
			(start 1.524 0.7366)
			(end 1.560576 0.7366)
			(stroke
				(width 0.1)
				(type default)
			)
			(layer "F.Fab")
		)
		(fp_line
			(start 1.560576 -0.7366)
			(end 1.524 -0.7366)
			(stroke
				(width 0.1)
				(type default)
			)
			(layer "F.Fab")
		)
		(fp_line
			(start 1.560576 0.7366)
			(end 1.560576 -0.7366)
			(stroke
				(width 0.1)
				(type default)
			)
			(layer "F.Fab")
		)
		(pad "1" smd rect
			(at -0.94996 0 180)
			(size 1.1176 1.3716)
			(layers "F.Cu" "F.Mask" "F.Paste")
			(net "P12V_BRICK")
		)
		(pad "2" smd rect
			(at 0.94996 0 180)
			(size 1.1176 1.3716)
			(layers "F.Cu" "F.Mask" "F.Paste")
			(net "GND")
		)
	)
	(footprint ""
		(layer "F.Cu")
		(at 222.504 -95.504 -90)
		(property "Reference" "C29"
			(at 0 0 270)
			(layer "F.SilkS")
			(hide yes)
			(effects
				(font
					(size 1.27 1.27)
				)
			)
		)
		(property "Value" ""
			(at 0 0 270)
			(layer "F.Fab")
			(effects
				(font
					(size 1.27 1.27)
				)
			)
		)
		(duplicate_pad_numbers_are_jumpers no)
		(fp_line
			(start -2.2098 0.9398)
			(end -2.2098 -0.9398)
			(stroke
				(width 0.1524)
				(type default)
			)
			(layer "F.SilkS")
		)
		(fp_line
			(start 2.2098 0.9398)
			(end -2.2098 0.9398)
			(stroke
				(width 0.1524)
				(type default)
			)
			(layer "F.SilkS")
		)
		(fp_line
			(start -2.2098 -0.9398)
			(end 2.2098 -0.9398)
			(stroke
				(width 0.1524)
				(type default)
			)
			(layer "F.SilkS")
		)
		(fp_line
			(start 2.2098 -0.9398)
			(end 2.2098 0.9398)
			(stroke
				(width 0.1524)
				(type default)
			)
			(layer "F.SilkS")
		)
		(fp_line
			(start -1.700022 0.899922)
			(end -1.700022 -0.899922)
			(stroke
				(width 0.1)
				(type default)
			)
			(layer "F.Fab")
		)
		(fp_line
			(start 1.700022 0.899922)
			(end -1.700022 0.899922)
			(stroke
				(width 0.1)
				(type default)
			)
			(layer "F.Fab")
		)
		(fp_line
			(start -1.700022 -0.899922)
			(end 1.700022 -0.899922)
			(stroke
				(width 0.1)
				(type default)
			)
			(layer "F.Fab")
		)
		(fp_line
			(start 1.700022 -0.899922)
			(end 1.700022 0.899922)
			(stroke
				(width 0.1)
				(type default)
			)
			(layer "F.Fab")
		)
		(pad "1" smd rect
			(at -1.4732 0 90)
			(size 1.1684 1.5748)
			(layers "F.Cu" "F.Mask" "F.Paste")
			(net "P52V_HS")
		)
		(pad "2" smd rect
			(at 1.4732 0 90)
			(size 1.1684 1.5748)
			(layers "F.Cu" "F.Mask" "F.Paste")
			(net "GND")
		)
	)
	(footprint ""
		(layer "F.Cu")
		(at 199.987916 -66.956686 -90)
		(property "Reference" "R58"
			(at 0 0 270)
			(layer "F.SilkS")
			(hide yes)
			(effects
				(font
					(size 1.27 1.27)
				)
			)
		)
		(property "Value" ""
			(at 0 0 270)
			(layer "F.Fab")
			(effects
				(font
					(size 1.27 1.27)
				)
			)
		)
		(duplicate_pad_numbers_are_jumpers no)
		(fp_line
			(start -0.7874 0.4064)
			(end -0.7874 -0.4064)
			(stroke
				(width 0.1524)
				(type default)
			)
			(layer "F.SilkS")
		)
		(fp_line
			(start 0.7874 0.4064)
			(end -0.7874 0.4064)
			(stroke
				(width 0.1524)
				(type default)
			)
			(layer "F.SilkS")
		)
		(fp_line
			(start -0.7874 -0.4064)
			(end 0.7874 -0.4064)
			(stroke
				(width 0.1524)
				(type default)
			)
			(layer "F.SilkS")
		)
		(fp_line
			(start 0.7874 -0.4064)
			(end 0.7874 0.4064)
			(stroke
				(width 0.1524)
				(type default)
			)
			(layer "F.SilkS")
		)
		(fp_line
			(start -0.67945 0.3048)
			(end -0.67945 -0.305054)
			(stroke
				(width 0.1)
				(type default)
			)
			(layer "F.Fab")
		)
		(fp_line
			(start -0.12065 0.3048)
			(end -0.67945 0.3048)
			(stroke
				(width 0.1)
				(type default)
			)
			(layer "F.Fab")
		)
		(fp_line
			(start 0.120396 0.3048)
			(end 0.120396 0.2794)
			(stroke
				(width 0.1)
				(type default)
			)
			(layer "F.Fab")
		)
		(fp_line
			(start 0.67945 0.3048)
			(end 0.120396 0.3048)
			(stroke
				(width 0.1)
				(type default)
			)
			(layer "F.Fab")
		)
		(fp_line
			(start -0.12065 0.2794)
			(end -0.12065 0.3048)
			(stroke
				(width 0.1)
				(type default)
			)
			(layer "F.Fab")
		)
		(fp_line
			(start 0.120396 0.2794)
			(end -0.12065 0.2794)
			(stroke
				(width 0.1)
				(type default)
			)
			(layer "F.Fab")
		)
		(fp_line
			(start -0.12065 -0.2794)
			(end 0.12065 -0.2794)
			(stroke
				(width 0.1)
				(type default)
			)
			(layer "F.Fab")
		)
		(fp_line
			(start 0.12065 -0.2794)
			(end 0.12065 -0.3048)
			(stroke
				(width 0.1)
				(type default)
			)
			(layer "F.Fab")
		)
		(fp_line
			(start 0.12065 -0.3048)
			(end 0.67945 -0.3048)
			(stroke
				(width 0.1)
				(type default)
			)
			(layer "F.Fab")
		)
		(fp_line
			(start 0.67945 -0.3048)
			(end 0.67945 0.3048)
			(stroke
				(width 0.1)
				(type default)
			)
			(layer "F.Fab")
		)
		(fp_line
			(start -0.67945 -0.305054)
			(end -0.12065 -0.305054)
			(stroke
				(width 0.1)
				(type default)
			)
			(layer "F.Fab")
		)
		(fp_line
			(start -0.12065 -0.305054)
			(end -0.12065 -0.2794)
			(stroke
				(width 0.1)
				(type default)
			)
			(layer "F.Fab")
		)
		(pad "1" smd circle
			(at -0.40005 0 270)
			(size 0 0)
			(layers "F.Cu" "F.Mask" "F.Paste")
			(net "LED_D2_R1")
		)
		(pad "2" smd circle
			(at 0.40005 0 270)
			(size 0 0)
			(layers "F.Cu" "F.Mask" "F.Paste")
			(net "LED_D2_R2")
		)
	)
	(footprint ""
		(layer "F.Cu")
		(at 298.069 -28.321)
		(property "Reference" "R5887"
			(at 0 0 0)
			(layer "F.SilkS")
			(hide yes)
			(effects
				(font
					(size 1.27 1.27)
				)
			)
		)
		(property "Value" ""
			(at 0 0 0)
			(layer "F.Fab")
			(effects
				(font
					(size 1.27 1.27)
				)
			)
		)
		(duplicate_pad_numbers_are_jumpers no)
		(fp_line
			(start -0.7874 -0.4064)
			(end 0.7874 -0.4064)
			(stroke
				(width 0.1524)
				(type default)
			)
			(layer "F.SilkS")
		)
		(fp_line
			(start -0.7874 0.4064)
			(end -0.7874 -0.4064)
			(stroke
				(width 0.1524)
				(type default)
			)
			(layer "F.SilkS")
		)
		(fp_line
			(start 0.7874 -0.4064)
			(end 0.7874 0.4064)
			(stroke
				(width 0.1524)
				(type default)
			)
			(layer "F.SilkS")
		)
		(fp_line
			(start 0.7874 0.4064)
			(end -0.7874 0.4064)
			(stroke
				(width 0.1524)
				(type default)
			)
			(layer "F.SilkS")
		)
		(fp_line
			(start -0.67945 -0.305054)
			(end -0.12065 -0.305054)
			(stroke
				(width 0.1)
				(type default)
			)
			(layer "F.Fab")
		)
		(fp_line
			(start -0.67945 0.3048)
			(end -0.67945 -0.305054)
			(stroke
				(width 0.1)
				(type default)
			)
			(layer "F.Fab")
		)
		(fp_line
			(start -0.12065 -0.305054)
			(end -0.12065 -0.2794)
			(stroke
				(width 0.1)
				(type default)
			)
			(layer "F.Fab")
		)
		(fp_line
			(start -0.12065 -0.2794)
			(end 0.12065 -0.2794)
			(stroke
				(width 0.1)
				(type default)
			)
			(layer "F.Fab")
		)
		(fp_line
			(start -0.12065 0.2794)
			(end -0.12065 0.3048)
			(stroke
				(width 0.1)
				(type default)
			)
			(layer "F.Fab")
		)
		(fp_line
			(start -0.12065 0.3048)
			(end -0.67945 0.3048)
			(stroke
				(width 0.1)
				(type default)
			)
			(layer "F.Fab")
		)
		(fp_line
			(start 0.120396 0.2794)
			(end -0.12065 0.2794)
			(stroke
				(width 0.1)
				(type default)
			)
			(layer "F.Fab")
		)
		(fp_line
			(start 0.120396 0.3048)
			(end 0.120396 0.2794)
			(stroke
				(width 0.1)
				(type default)
			)
			(layer "F.Fab")
		)
		(fp_line
			(start 0.12065 -0.3048)
			(end 0.67945 -0.3048)
			(stroke
				(width 0.1)
				(type default)
			)
			(layer "F.Fab")
		)
		(fp_line
			(start 0.12065 -0.2794)
			(end 0.12065 -0.3048)
			(stroke
				(width 0.1)
				(type default)
			)
			(layer "F.Fab")
		)
		(fp_line
			(start 0.67945 -0.3048)
			(end 0.67945 0.3048)
			(stroke
				(width 0.1)
				(type default)
			)
			(layer "F.Fab")
		)
		(fp_line
			(start 0.67945 0.3048)
			(end 0.120396 0.3048)
			(stroke
				(width 0.1)
				(type default)
			)
			(layer "F.Fab")
		)
		(pad "1" smd circle
			(at -0.40005 0)
			(size 0 0)
			(layers "F.Cu" "F.Mask" "F.Paste")
			(net "FM_HSC_EN_FUSE")
		)
		(pad "2" smd circle
			(at 0.40005 0)
			(size 0 0)
			(layers "F.Cu" "F.Mask" "F.Paste")
			(net "GND")
		)
	)
	(footprint ""
		(layer "F.Cu")
		(at 261.747 -137.795 -90)
		(property "Reference" "H2"
			(at -6.213094 11.432794 0)
			(unlocked yes)
			(layer "F.SilkS")
			(effects
				(font
					(size 0.7874 0.5842)
					(thickness 0.1524)
				)
				(justify left)
			)
		)
		(property "Value" ""
			(at 0 0 270)
			(layer "F.Fab")
			(effects
				(font
					(size 1.27 1.27)
				)
			)
		)
		(duplicate_pad_numbers_are_jumpers no)
		(pad "1" thru_hole oval
			(at 0 0 270)
			(size 10.0076 32.004)
			(drill 3.0226
				(offset 0 10.999978)
			)
			(layers "*.Cu" "*.Mask")
			(remove_unused_layers no)
			(net "GND")
			(clearance -1.995678)
			(padstack
				(mode front_inner_back)
				(layer "Inner"
					(shape circle)
					(size 0 0)
					(clearance 0)
				)
				(layer "B.Cu"
					(shape oval)
					(size 10.0076 32.004)
					(offset 0 10.999978)
					(clearance -1.995678)
				)
			)
		)
	)
	(footprint ""
		(layer "F.Cu")
		(at 301.625 -122.9995)
		(property "Reference" "PR6956"
			(at 0 0 0)
			(layer "F.SilkS")
			(hide yes)
			(effects
				(font
					(size 1.27 1.27)
				)
			)
		)
		(property "Value" ""
			(at 0 0 0)
			(layer "F.Fab")
			(effects
				(font
					(size 1.27 1.27)
				)
			)
		)
		(duplicate_pad_numbers_are_jumpers no)
		(fp_line
			(start -1.2954 -0.5842)
			(end 1.2954 -0.5842)
			(stroke
				(width 0.1524)
				(type default)
			)
			(layer "F.SilkS")
		)
		(fp_line
			(start -1.2954 0.5842)
			(end -1.2954 -0.5842)
			(stroke
				(width 0.1524)
				(type default)
			)
			(layer "F.SilkS")
		)
		(fp_line
			(start 1.2954 -0.5842)
			(end 1.2954 0.5842)
			(stroke
				(width 0.1524)
				(type default)
			)
			(layer "F.SilkS")
		)
		(fp_line
			(start 1.2954 0.5842)
			(end -1.2954 0.5842)
			(stroke
				(width 0.1524)
				(type default)
			)
			(layer "F.SilkS")
		)
		(fp_line
			(start -1.1938 -0.406654)
			(end -0.8636 -0.406654)
			(stroke
				(width 0.1)
				(type default)
			)
			(layer "F.Fab")
		)
		(fp_line
			(start -1.1938 0.4064)
			(end -1.1938 -0.406654)
			(stroke
				(width 0.1)
				(type default)
			)
			(layer "F.Fab")
		)
		(fp_line
			(start -0.8636 -0.4572)
			(end 0.8636 -0.4572)
			(stroke
				(width 0.1)
				(type default)
			)
			(layer "F.Fab")
		)
		(fp_line
			(start -0.8636 -0.406654)
			(end -0.8636 -0.4572)
			(stroke
				(width 0.1)
				(type default)
			)
			(layer "F.Fab")
		)
		(fp_line
			(start -0.8636 0.4064)
			(end -1.1938 0.4064)
			(stroke
				(width 0.1)
				(type default)
			)
			(layer "F.Fab")
		)
		(fp_line
			(start -0.8636 0.4318)
			(end -0.8636 0.4064)
			(stroke
				(width 0.1)
				(type default)
			)
			(layer "F.Fab")
		)
		(fp_line
			(start -0.8636 0.4572)
			(end -0.8636 0.4318)
			(stroke
				(width 0.1)
				(type default)
			)
			(layer "F.Fab")
		)
		(fp_line
			(start 0.8636 -0.4572)
			(end 0.8636 -0.406654)
			(stroke
				(width 0.1)
				(type default)
			)
			(layer "F.Fab")
		)
		(fp_line
			(start 0.8636 -0.406654)
			(end 1.1938 -0.406654)
			(stroke
				(width 0.1)
				(type default)
			)
			(layer "F.Fab")
		)
		(fp_line
			(start 0.8636 0.4064)
			(end 0.8636 0.4572)
			(stroke
				(width 0.1)
				(type default)
			)
			(layer "F.Fab")
		)
		(fp_line
			(start 0.8636 0.4572)
			(end -0.8636 0.4572)
			(stroke
				(width 0.1)
				(type default)
			)
			(layer "F.Fab")
		)
		(fp_line
			(start 1.1938 -0.406654)
			(end 1.1938 0.4064)
			(stroke
				(width 0.1)
				(type default)
			)
			(layer "F.Fab")
		)
		(fp_line
			(start 1.1938 0.4064)
			(end 0.8636 0.4064)
			(stroke
				(width 0.1)
				(type default)
			)
			(layer "F.Fab")
		)
		(pad "1" smd rect
			(at -0.7366 0 270)
			(size 0.7112 0.8128)
			(layers "F.Cu" "F.Mask" "F.Paste")
			(net "P52V_HS_4287_S1P")
		)
		(pad "2" smd rect
			(at 0.7366 0 270)
			(size 0.7112 0.8128)
			(layers "F.Cu" "F.Mask" "F.Paste")
			(net "P52V_HS1_SENSE_P_R1")
		)
	)
	(footprint ""
		(layer "F.Cu")
		(at 66.430906 -136.906 90)
		(property "Reference" "PC71"
			(at 6.19633 1.133094 0)
			(unlocked yes)
			(layer "F.SilkS")
			(effects
				(font
					(size 0.7874 0.5842)
					(thickness 0.1524)
				)
				(justify left)
			)
		)
		(property "Value" ""
			(at 0 0 90)
			(layer "F.Fab")
			(effects
				(font
					(size 1.27 1.27)
				)
			)
		)
		(duplicate_pad_numbers_are_jumpers no)
		(fp_line
			(start 5.2578 2.499868)
			(end -5.2578 2.499868)
			(stroke
				(width 0.1524)
				(type default)
			)
			(layer "F.SilkS")
		)
		(fp_circle
			(center 0 2.500122)
			(end 0 7.758176)
			(stroke
				(width 0.1524)
				(type default)
			)
			(fill no)
			(layer "F.SilkS")
		)
		(fp_poly
			(pts
				(arc
					(start 5.2578 2.499868)
					(mid 0 7.757922)
					(end -5.2578 2.499868)
				)
			)
			(stroke
				(width 0)
				(type default)
			)
			(fill yes)
			(layer "F.SilkS")
		)
		(fp_circle
			(center 0 2.500122)
			(end 0 7.758176)
			(stroke
				(width 0.1)
				(type default)
			)
			(fill no)
			(layer "F.Fab")
		)
		(pad "1" thru_hole rect
			(at 0 0)
			(size 1.5748 1.5748)
			(drill 1.0668)
			(layers "*.Cu" "*.Mask")
			(remove_unused_layers no)
			(net "P52V_HS_FILTER")
			(clearance 0)
			(padstack
				(mode front_inner_back)
				(layer "Inner"
					(shape circle)
					(size 1.5748 1.5748)
					(clearance 0)
				)
				(layer "B.Cu"
					(shape rect)
					(size 1.5748 1.5748)
					(clearance 0)
				)
			)
		)
		(pad "2" thru_hole circle
			(at 0 4.99999)
			(size 1.5748 1.5748)
			(drill 1.0668)
			(layers "*.Cu" "*.Mask")
			(remove_unused_layers no)
			(net "GND")
			(clearance 0)
		)
	)
	(footprint ""
		(layer "F.Cu")
		(at 289.722814 -50.698146 90)
		(property "Reference" "PC558"
			(at 0 0 90)
			(layer "F.SilkS")
			(hide yes)
			(effects
				(font
					(size 1.27 1.27)
				)
			)
		)
		(property "Value" ""
			(at 0 0 90)
			(layer "F.Fab")
			(effects
				(font
					(size 1.27 1.27)
				)
			)
		)
		(duplicate_pad_numbers_are_jumpers no)
		(fp_line
			(start 2.2098 -0.9398)
			(end 2.2098 0.9398)
			(stroke
				(width 0.1524)
				(type default)
			)
			(layer "F.SilkS")
		)
		(fp_line
			(start -2.2098 -0.9398)
			(end 2.2098 -0.9398)
			(stroke
				(width 0.1524)
				(type default)
			)
			(layer "F.SilkS")
		)
		(fp_line
			(start 2.2098 0.9398)
			(end -2.2098 0.9398)
			(stroke
				(width 0.1524)
				(type default)
			)
			(layer "F.SilkS")
		)
		(fp_line
			(start -2.2098 0.9398)
			(end -2.2098 -0.9398)
			(stroke
				(width 0.1524)
				(type default)
			)
			(layer "F.SilkS")
		)
		(fp_line
			(start 1.6764 -0.9398)
			(end -1.6764 -0.9398)
			(stroke
				(width 0.1)
				(type default)
			)
			(layer "F.Fab")
		)
		(fp_line
			(start -1.6764 -0.9398)
			(end -1.6764 0.9398)
			(stroke
				(width 0.1)
				(type default)
			)
			(layer "F.Fab")
		)
		(fp_line
			(start 1.6764 0.9398)
			(end 1.6764 -0.9398)
			(stroke
				(width 0.1)
				(type default)
			)
			(layer "F.Fab")
		)
		(fp_line
			(start -1.6764 0.9398)
			(end 1.6764 0.9398)
			(stroke
				(width 0.1)
				(type default)
			)
			(layer "F.Fab")
		)
		(pad "1" smd rect
			(at -1.4732 0 270)
			(size 1.1684 1.5748)
			(layers "F.Cu" "F.Mask" "F.Paste")
			(net "P52V_HS1_VCC")
		)
		(pad "2" smd rect
			(at 1.4732 0 270)
			(size 1.1684 1.5748)
			(layers "F.Cu" "F.Mask" "F.Paste")
			(net "GND_FIELD_SIGNAL")
		)
	)
	(footprint ""
		(layer "F.Cu")
		(at 163.6268 -11.4808)
		(property "Reference" "PL1"
			(at 0 0 0)
			(layer "F.SilkS")
			(hide yes)
			(effects
				(font
					(size 1.27 1.27)
				)
			)
		)
		(property "Value" ""
			(at 0 0 0)
			(layer "F.Fab")
			(effects
				(font
					(size 1.27 1.27)
				)
			)
		)
		(duplicate_pad_numbers_are_jumpers no)
		(fp_line
			(start -1.27 -0.5842)
			(end 1.27 -0.5842)
			(stroke
				(width 0.1524)
				(type default)
			)
			(layer "F.SilkS")
		)
		(fp_line
			(start -1.27 -0.5588)
			(end -1.27 -0.5842)
			(stroke
				(width 0.1524)
				(type default)
			)
			(layer "F.SilkS")
		)
		(fp_line
			(start -1.27 0.5842)
			(end -1.27 -0.5842)
			(stroke
				(width 0.1524)
				(type default)
			)
			(layer "F.SilkS")
		)
		(fp_line
			(start 1.27 0.5842)
			(end -1.27 0.5842)
			(stroke
				(width 0.1524)
				(type default)
			)
			(layer "F.SilkS")
		)
		(fp_line
			(start 1.27 0.5842)
			(end 1.27 -0.5842)
			(stroke
				(width 0.1524)
				(type default)
			)
			(layer "F.SilkS")
		)
		(fp_line
			(start -1.194308 -0.406654)
			(end -0.9144 -0.406654)
			(stroke
				(width 0.1)
				(type default)
			)
			(layer "F.Fab")
		)
		(fp_line
			(start -1.194308 0.406654)
			(end -1.194308 -0.406654)
			(stroke
				(width 0.1)
				(type default)
			)
			(layer "F.Fab")
		)
		(fp_line
			(start -0.9144 -0.508)
			(end 0.9144 -0.508)
			(stroke
				(width 0.1)
				(type default)
			)
			(layer "F.Fab")
		)
		(fp_line
			(start -0.9144 -0.406654)
			(end -0.9144 -0.508)
			(stroke
				(width 0.1)
				(type default)
			)
			(layer "F.Fab")
		)
		(fp_line
			(start -0.9144 0.406654)
			(end -1.194308 0.406654)
			(stroke
				(width 0.1)
				(type default)
			)
			(layer "F.Fab")
		)
		(fp_line
			(start -0.9144 0.508)
			(end -0.9144 0.406654)
			(stroke
				(width 0.1)
				(type default)
			)
			(layer "F.Fab")
		)
		(fp_line
			(start 0.9144 -0.508)
			(end 0.9144 -0.406654)
			(stroke
				(width 0.1)
				(type default)
			)
			(layer "F.Fab")
		)
		(fp_line
			(start 0.9144 -0.406654)
			(end 1.1938 -0.406654)
			(stroke
				(width 0.1)
				(type default)
			)
			(layer "F.Fab")
		)
		(fp_line
			(start 0.9144 0.4064)
			(end 0.9144 0.508)
			(stroke
				(width 0.1)
				(type default)
			)
			(layer "F.Fab")
		)
		(fp_line
			(start 0.9144 0.508)
			(end -0.9144 0.508)
			(stroke
				(width 0.1)
				(type default)
			)
			(layer "F.Fab")
		)
		(fp_line
			(start 1.1938 -0.406654)
			(end 1.1938 0.4064)
			(stroke
				(width 0.1)
				(type default)
			)
			(layer "F.Fab")
		)
		(fp_line
			(start 1.1938 0.4064)
			(end 0.9144 0.4064)
			(stroke
				(width 0.1)
				(type default)
			)
			(layer "F.Fab")
		)
		(pad "1" smd rect
			(at -0.7366 0 270)
			(size 0.7112 0.8128)
			(layers "F.Cu" "F.Mask" "F.Paste")
			(net "P12V_BRICK")
		)
		(pad "2" smd rect
			(at 0.7366 0 270)
			(size 0.7112 0.8128)
			(layers "F.Cu" "F.Mask" "F.Paste")
			(net "SW_P12V_FILT__P3V3_AUX")
		)
	)
	(footprint ""
		(layer "F.Cu")
		(at 151.765 -51.816)
		(property "Reference" "PC38"
			(at 0 0 0)
			(layer "F.SilkS")
			(hide yes)
			(effects
				(font
					(size 1.27 1.27)
				)
			)
		)
		(property "Value" ""
			(at 0 0 0)
			(layer "F.Fab")
			(effects
				(font
					(size 1.27 1.27)
				)
			)
		)
		(duplicate_pad_numbers_are_jumpers no)
		(fp_line
			(start -1.524 -0.762)
			(end 1.524 -0.762)
			(stroke
				(width 0.1524)
				(type default)
			)
			(layer "F.SilkS")
		)
		(fp_line
			(start -1.524 0.762)
			(end -1.524 -0.762)
			(stroke
				(width 0.1524)
				(type default)
			)
			(layer "F.SilkS")
		)
		(fp_line
			(start 1.524 -0.762)
			(end 1.524 0.762)
			(stroke
				(width 0.1524)
				(type default)
			)
			(layer "F.SilkS")
		)
		(fp_line
			(start 1.524 0.762)
			(end -1.524 0.762)
			(stroke
				(width 0.1524)
				(type default)
			)
			(layer "F.SilkS")
		)
		(fp_line
			(start -1.1049 -0.724916)
			(end -1.1049 0.724916)
			(stroke
				(width 0.1)
				(type default)
			)
			(layer "F.Fab")
		)
		(fp_line
			(start -1.1049 0.724916)
			(end 1.1049 0.724916)
			(stroke
				(width 0.1)
				(type default)
			)
			(layer "F.Fab")
		)
		(fp_line
			(start 1.1049 -0.724916)
			(end -1.1049 -0.724916)
			(stroke
				(width 0.1)
				(type default)
			)
			(layer "F.Fab")
		)
		(fp_line
			(start 1.1049 0.724916)
			(end 1.1049 -0.724916)
			(stroke
				(width 0.1)
				(type default)
			)
			(layer "F.Fab")
		)
		(pad "1" smd rect
			(at -0.889 0 180)
			(size 1.016 1.27)
			(layers "F.Cu" "F.Mask" "F.Paste")
			(net "P12V_BRICK")
		)
		(pad "2" smd rect
			(at 0.889 0 180)
			(size 1.016 1.27)
			(layers "F.Cu" "F.Mask" "F.Paste")
			(net "GND")
		)
	)
	(footprint ""
		(layer "F.Cu")
		(at 284.988 -49.276 90)
		(property "Reference" "PC557"
			(at 0 0 90)
			(layer "F.SilkS")
			(hide yes)
			(effects
				(font
					(size 1.27 1.27)
				)
			)
		)
		(property "Value" ""
			(at 0 0 90)
			(layer "F.Fab")
			(effects
				(font
					(size 1.27 1.27)
				)
			)
		)
		(duplicate_pad_numbers_are_jumpers no)
		(fp_line
			(start 0.7874 -0.4064)
			(end 0.7874 0.4064)
			(stroke
				(width 0.1524)
				(type default)
			)
			(layer "F.SilkS")
		)
		(fp_line
			(start -0.7874 -0.4064)
			(end 0.7874 -0.4064)
			(stroke
				(width 0.1524)
				(type default)
			)
			(layer "F.SilkS")
		)
		(fp_line
			(start 0.7874 0.4064)
			(end -0.7874 0.4064)
			(stroke
				(width 0.1524)
				(type default)
			)
			(layer "F.SilkS")
		)
		(fp_line
			(start -0.7874 0.4064)
			(end -0.7874 -0.4064)
			(stroke
				(width 0.1524)
				(type default)
			)
			(layer "F.SilkS")
		)
		(fp_line
			(start -0.12065 -0.305054)
			(end -0.12065 -0.2794)
			(stroke
				(width 0.1)
				(type default)
			)
			(layer "F.Fab")
		)
		(fp_line
			(start -0.67945 -0.305054)
			(end -0.12065 -0.305054)
			(stroke
				(width 0.1)
				(type default)
			)
			(layer "F.Fab")
		)
		(fp_line
			(start 0.67945 -0.3048)
			(end 0.67945 0.3048)
			(stroke
				(width 0.1)
				(type default)
			)
			(layer "F.Fab")
		)
		(fp_line
			(start 0.12065 -0.3048)
			(end 0.67945 -0.3048)
			(stroke
				(width 0.1)
				(type default)
			)
			(layer "F.Fab")
		)
		(fp_line
			(start 0.12065 -0.2794)
			(end 0.12065 -0.3048)
			(stroke
				(width 0.1)
				(type default)
			)
			(layer "F.Fab")
		)
		(fp_line
			(start -0.12065 -0.2794)
			(end 0.12065 -0.2794)
			(stroke
				(width 0.1)
				(type default)
			)
			(layer "F.Fab")
		)
		(fp_line
			(start 0.120396 0.2794)
			(end -0.12065 0.2794)
			(stroke
				(width 0.1)
				(type default)
			)
			(layer "F.Fab")
		)
		(fp_line
			(start -0.12065 0.2794)
			(end -0.12065 0.3048)
			(stroke
				(width 0.1)
				(type default)
			)
			(layer "F.Fab")
		)
		(fp_line
			(start 0.67945 0.3048)
			(end 0.120396 0.3048)
			(stroke
				(width 0.1)
				(type default)
			)
			(layer "F.Fab")
		)
		(fp_line
			(start 0.120396 0.3048)
			(end 0.120396 0.2794)
			(stroke
				(width 0.1)
				(type default)
			)
			(layer "F.Fab")
		)
		(fp_line
			(start -0.12065 0.3048)
			(end -0.67945 0.3048)
			(stroke
				(width 0.1)
				(type default)
			)
			(layer "F.Fab")
		)
		(fp_line
			(start -0.67945 0.3048)
			(end -0.67945 -0.305054)
			(stroke
				(width 0.1)
				(type default)
			)
			(layer "F.Fab")
		)
		(pad "1" smd circle
			(at -0.40005 0 90)
			(size 0 0)
			(layers "F.Cu" "F.Mask" "F.Paste")
			(net "P52V_HS1_UVH")
		)
		(pad "2" smd circle
			(at 0.40005 0 90)
			(size 0 0)
			(layers "F.Cu" "F.Mask" "F.Paste")
			(net "GND_FIELD_SIGNAL")
		)
	)
	(footprint ""
		(layer "F.Cu")
		(at 173.609 -51.816)
		(property "Reference" "PC30"
			(at 0 0 0)
			(layer "F.SilkS")
			(hide yes)
			(effects
				(font
					(size 1.27 1.27)
				)
			)
		)
		(property "Value" ""
			(at 0 0 0)
			(layer "F.Fab")
			(effects
				(font
					(size 1.27 1.27)
				)
			)
		)
		(duplicate_pad_numbers_are_jumpers no)
		(fp_line
			(start -1.524 -0.762)
			(end 1.524 -0.762)
			(stroke
				(width 0.1524)
				(type default)
			)
			(layer "F.SilkS")
		)
		(fp_line
			(start -1.524 0.762)
			(end -1.524 -0.762)
			(stroke
				(width 0.1524)
				(type default)
			)
			(layer "F.SilkS")
		)
		(fp_line
			(start 1.524 -0.762)
			(end 1.524 0.762)
			(stroke
				(width 0.1524)
				(type default)
			)
			(layer "F.SilkS")
		)
		(fp_line
			(start 1.524 0.762)
			(end -1.524 0.762)
			(stroke
				(width 0.1524)
				(type default)
			)
			(layer "F.SilkS")
		)
		(fp_line
			(start -1.1049 -0.724916)
			(end -1.1049 0.724916)
			(stroke
				(width 0.1)
				(type default)
			)
			(layer "F.Fab")
		)
		(fp_line
			(start -1.1049 0.724916)
			(end 1.1049 0.724916)
			(stroke
				(width 0.1)
				(type default)
			)
			(layer "F.Fab")
		)
		(fp_line
			(start 1.1049 -0.724916)
			(end -1.1049 -0.724916)
			(stroke
				(width 0.1)
				(type default)
			)
			(layer "F.Fab")
		)
		(fp_line
			(start 1.1049 0.724916)
			(end 1.1049 -0.724916)
			(stroke
				(width 0.1)
				(type default)
			)
			(layer "F.Fab")
		)
		(pad "1" smd rect
			(at -0.889 0 180)
			(size 1.016 1.27)
			(layers "F.Cu" "F.Mask" "F.Paste")
			(net "P12V_BRICK")
		)
		(pad "2" smd rect
			(at 0.889 0 180)
			(size 1.016 1.27)
			(layers "F.Cu" "F.Mask" "F.Paste")
			(net "GND")
		)
	)
	(footprint ""
		(layer "F.Cu")
		(at 211.455 -83.566 180)
		(property "Reference" "D1"
			(at 0.67564 -1.40335 0)
			(unlocked yes)
			(layer "F.SilkS")
			(effects
				(font
					(size 0.7874 0.5842)
					(thickness 0.1524)
				)
				(justify left)
			)
		)
		(property "Value" ""
			(at 0 0 180)
			(layer "F.Fab")
			(effects
				(font
					(size 1.27 1.27)
				)
			)
		)
		(duplicate_pad_numbers_are_jumpers no)
		(fp_line
			(start 1.16078 0.4826)
			(end -0.64008 0.4826)
			(stroke
				(width 0.1524)
				(type default)
			)
			(layer "F.SilkS")
		)
		(fp_line
			(start 1.16078 -0.4826)
			(end 1.16078 0.4826)
			(stroke
				(width 0.1524)
				(type default)
			)
			(layer "F.SilkS")
		)
		(fp_line
			(start 1.03378 0.4826)
			(end -0.79248 0.4826)
			(stroke
				(width 0.1524)
				(type default)
			)
			(layer "F.SilkS")
		)
		(fp_line
			(start 1.03378 -0.4826)
			(end 1.03378 0.4826)
			(stroke
				(width 0.1524)
				(type default)
			)
			(layer "F.SilkS")
		)
		(fp_line
			(start 0.90678 0.4826)
			(end -0.90678 0.4826)
			(stroke
				(width 0.1524)
				(type default)
			)
			(layer "F.SilkS")
		)
		(fp_line
			(start 0.90678 -0.4826)
			(end 0.90678 0.4826)
			(stroke
				(width 0.1524)
				(type default)
			)
			(layer "F.SilkS")
		)
		(fp_line
			(start -0.64008 -0.4826)
			(end 1.16078 -0.4826)
			(stroke
				(width 0.1524)
				(type default)
			)
			(layer "F.SilkS")
		)
		(fp_line
			(start -0.79248 -0.4826)
			(end 1.03378 -0.4826)
			(stroke
				(width 0.1524)
				(type default)
			)
			(layer "F.SilkS")
		)
		(fp_line
			(start -0.89408 -0.4826)
			(end 0.90678 -0.4826)
			(stroke
				(width 0.1524)
				(type default)
			)
			(layer "F.SilkS")
		)
		(fp_line
			(start -0.90678 0.4826)
			(end -0.90678 -0.4699)
			(stroke
				(width 0.1524)
				(type default)
			)
			(layer "F.SilkS")
		)
		(fp_line
			(start 0.499872 0.249936)
			(end -0.499872 0.249936)
			(stroke
				(width 0.1)
				(type default)
			)
			(layer "F.Fab")
		)
		(fp_line
			(start 0.499872 -0.249936)
			(end 0.499872 0.249936)
			(stroke
				(width 0.1)
				(type default)
			)
			(layer "F.Fab")
		)
		(fp_line
			(start -0.499872 0.249936)
			(end -0.499872 -0.249936)
			(stroke
				(width 0.1)
				(type default)
			)
			(layer "F.Fab")
		)
		(fp_line
			(start -0.499872 -0.249936)
			(end 0.499872 -0.249936)
			(stroke
				(width 0.1)
				(type default)
			)
			(layer "F.Fab")
		)
		(pad "A" smd rect
			(at -0.47498 0 180)
			(size 0.6096 0.7112)
			(layers "F.Cu" "F.Mask" "F.Paste")
			(net "LED_D1_R5")
		)
		(pad "C" smd rect
			(at 0.47498 0 180)
			(size 0.6096 0.7112)
			(layers "F.Cu" "F.Mask" "F.Paste")
			(net "GND")
		)
	)
	(footprint ""
		(layer "F.Cu")
		(at 79.121 -49.911)
		(property "Reference" "PC93"
			(at 0 0 0)
			(layer "F.SilkS")
			(hide yes)
			(effects
				(font
					(size 1.27 1.27)
				)
			)
		)
		(property "Value" ""
			(at 0 0 0)
			(layer "F.Fab")
			(effects
				(font
					(size 1.27 1.27)
				)
			)
		)
		(duplicate_pad_numbers_are_jumpers no)
		(fp_line
			(start -1.524 -0.762)
			(end 1.524 -0.762)
			(stroke
				(width 0.1524)
				(type default)
			)
			(layer "F.SilkS")
		)
		(fp_line
			(start -1.524 0.762)
			(end -1.524 -0.762)
			(stroke
				(width 0.1524)
				(type default)
			)
			(layer "F.SilkS")
		)
		(fp_line
			(start 1.524 -0.762)
			(end 1.524 0.762)
			(stroke
				(width 0.1524)
				(type default)
			)
			(layer "F.SilkS")
		)
		(fp_line
			(start 1.524 0.762)
			(end -1.524 0.762)
			(stroke
				(width 0.1524)
				(type default)
			)
			(layer "F.SilkS")
		)
		(fp_line
			(start -1.1049 -0.724916)
			(end -1.1049 0.724916)
			(stroke
				(width 0.1)
				(type default)
			)
			(layer "F.Fab")
		)
		(fp_line
			(start -1.1049 0.724916)
			(end 1.1049 0.724916)
			(stroke
				(width 0.1)
				(type default)
			)
			(layer "F.Fab")
		)
		(fp_line
			(start 1.1049 -0.724916)
			(end -1.1049 -0.724916)
			(stroke
				(width 0.1)
				(type default)
			)
			(layer "F.Fab")
		)
		(fp_line
			(start 1.1049 0.724916)
			(end 1.1049 -0.724916)
			(stroke
				(width 0.1)
				(type default)
			)
			(layer "F.Fab")
		)
		(pad "1" smd rect
			(at -0.889 0 180)
			(size 1.016 1.27)
			(layers "F.Cu" "F.Mask" "F.Paste")
			(net "P12V_BRICK")
		)
		(pad "2" smd rect
			(at 0.889 0 180)
			(size 1.016 1.27)
			(layers "F.Cu" "F.Mask" "F.Paste")
			(net "GND")
		)
	)
	(footprint ""
		(layer "F.Cu")
		(at 287.545272 -42.341546)
		(property "Reference" "PU7"
			(at -5.478272 -4.240784 0)
			(unlocked yes)
			(layer "F.SilkS")
			(effects
				(font
					(size 0.7874 0.5842)
					(thickness 0.1524)
				)
				(justify left)
			)
		)
		(property "Value" ""
			(at 0 0 0)
			(layer "F.Fab")
			(effects
				(font
					(size 1.27 1.27)
				)
			)
		)
		(duplicate_pad_numbers_are_jumpers no)
		(fp_line
			(start -4.05003 -3.549904)
			(end -4.05003 -3.0226)
			(stroke
				(width 0.1524)
				(type default)
			)
			(layer "F.SilkS")
		)
		(fp_line
			(start -4.05003 3.0226)
			(end -4.05003 3.549904)
			(stroke
				(width 0.1524)
				(type default)
			)
			(layer "F.SilkS")
		)
		(fp_line
			(start -4.05003 3.549904)
			(end -3.5052 3.549904)
			(stroke
				(width 0.1524)
				(type default)
			)
			(layer "F.SilkS")
		)
		(fp_line
			(start -3.5052 -3.549904)
			(end -4.05003 -3.549904)
			(stroke
				(width 0.1524)
				(type default)
			)
			(layer "F.SilkS")
		)
		(fp_line
			(start 0.0254 3.549904)
			(end 0.9906 3.549904)
			(stroke
				(width 0.1524)
				(type default)
			)
			(layer "F.SilkS")
		)
		(fp_line
			(start 0.9906 -3.549904)
			(end 0.0254 -3.549904)
			(stroke
				(width 0.1524)
				(type default)
			)
			(layer "F.SilkS")
		)
		(fp_line
			(start 3.5052 3.549904)
			(end 4.05003 3.549904)
			(stroke
				(width 0.1524)
				(type default)
			)
			(layer "F.SilkS")
		)
		(fp_line
			(start 4.05003 -3.549904)
			(end 3.5052 -3.549904)
			(stroke
				(width 0.1524)
				(type default)
			)
			(layer "F.SilkS")
		)
		(fp_line
			(start 4.05003 -3.0226)
			(end 4.05003 -3.549904)
			(stroke
				(width 0.1524)
				(type default)
			)
			(layer "F.SilkS")
		)
		(fp_line
			(start 4.05003 3.549904)
			(end 4.05003 3.0226)
			(stroke
				(width 0.1524)
				(type default)
			)
			(layer "F.SilkS")
		)
		(fp_poly
			(pts
				(xy -5.478272 -2.297684) (xy -5.478272 -3.203956) (xy -4.572 -2.75082)
			)
			(stroke
				(width 0)
				(type default)
			)
			(fill yes)
			(layer "F.SilkS")
		)
		(fp_line
			(start -4.05003 -3.549904)
			(end -4.05003 3.549904)
			(stroke
				(width 0.1)
				(type default)
			)
			(layer "F.Fab")
		)
		(fp_line
			(start -4.05003 3.549904)
			(end 4.05003 3.549904)
			(stroke
				(width 0.1)
				(type default)
			)
			(layer "F.Fab")
		)
		(fp_line
			(start 4.05003 -3.549904)
			(end -4.05003 -3.549904)
			(stroke
				(width 0.1)
				(type default)
			)
			(layer "F.Fab")
		)
		(fp_line
			(start 4.05003 3.549904)
			(end 4.05003 -3.549904)
			(stroke
				(width 0.1)
				(type default)
			)
			(layer "F.Fab")
		)
		(fp_poly
			(pts
				(xy -5.588 -3.25882) (xy -5.588 -2.24282) (xy -4.572 -2.75082)
			)
			(stroke
				(width 0)
				(type default)
			)
			(fill yes)
			(layer "F.Fab")
		)
		(pad "1" smd oval
			(at -3.9497 -2.75082 270)
			(size 0.3048 0.8382)
			(layers "F.Cu" "F.Mask" "F.Paste")
			(net "P52V_HS1_ISET")
		)
		(pad "2" smd oval
			(at -3.9497 -2.25044 270)
			(size 0.3048 0.8382)
			(layers "F.Cu" "F.Mask" "F.Paste")
			(net "P52V_HS1_ISTART")
		)
		(pad "3" smd oval
			(at -3.9497 -1.75006 270)
			(size 0.3048 0.8382)
			(layers "F.Cu" "F.Mask" "F.Paste")
			(net "P52V_HS1_VCAP")
		)
		(pad "4" smd oval
			(at -3.9497 -1.24968 270)
			(size 0.3048 0.8382)
			(layers "F.Cu" "F.Mask" "F.Paste")
			(net "P52V_HS1_ESTART_R")
		)
		(pad "5" smd oval
			(at -3.9497 -0.7493 270)
			(size 0.3048 0.8382)
			(layers "F.Cu" "F.Mask" "F.Paste")
			(net "P52V_HS1_EFAULT_R")
		)
		(pad "6" smd oval
			(at -3.9497 -0.24892 270)
			(size 0.3048 0.8382)
			(layers "F.Cu" "F.Mask" "F.Paste")
			(net "P52V_HS1_EN_BUF_DELAY")
		)
		(pad "7" smd oval
			(at -3.9497 0.24892 270)
			(size 0.3048 0.8382)
			(layers "F.Cu" "F.Mask" "F.Paste")
			(net "P52V_HS1_ADR0")
		)
		(pad "8" smd oval
			(at -3.9497 0.7493 270)
			(size 0.3048 0.8382)
			(layers "F.Cu" "F.Mask" "F.Paste")
			(net "P52V_HS1_ADR1")
		)
		(pad "9" smd oval
			(at -3.9497 1.24968 270)
			(size 0.3048 0.8382)
			(layers "F.Cu" "F.Mask" "F.Paste")
			(net "SMB_P52V_VPDB_SCL_R2")
		)
		(pad "10" smd oval
			(at -3.9497 1.75006 270)
			(size 0.3048 0.8382)
			(layers "F.Cu" "F.Mask" "F.Paste")
			(net "SMB_CM_HS1_3V3SB_DATI")
		)
		(pad "11" smd oval
			(at -3.9497 2.25044 270)
			(size 0.3048 0.8382)
			(layers "F.Cu" "F.Mask" "F.Paste")
			(net "SMB_CM_HS1_3V3SB_DATO")
		)
		(pad "12" smd oval
			(at -3.9497 2.75082 270)
			(size 0.3048 0.8382)
			(layers "F.Cu" "F.Mask" "F.Paste")
			(net "P52V_HS1_MCB")
		)
		(pad "13" smd oval
			(at -3.2512 3.44932)
			(size 0.3048 0.8382)
			(layers "F.Cu" "F.Mask" "F.Paste")
			(net "P52V_HS1_GPO2")
		)
		(pad "14" smd oval
			(at -2.75082 3.44932)
			(size 0.3048 0.8382)
			(layers "F.Cu" "F.Mask" "F.Paste")
			(net "P52V_HS1_GPO1")
		)
		(pad "15" smd oval
			(at -2.25044 3.44932)
			(size 0.3048 0.8382)
			(layers "F.Cu" "F.Mask" "F.Paste")
			(net "Net_298")
		)
		(pad "16" smd oval
			(at -1.75006 3.44932)
			(size 0.3048 0.8382)
			(layers "F.Cu" "F.Mask" "F.Paste")
			(net "Net_297")
		)
		(pad "17" smd oval
			(at -1.24968 3.44932)
			(size 0.3048 0.8382)
			(layers "F.Cu" "F.Mask" "F.Paste")
			(net "PWRGD_P52V_HS1_PG")
		)
		(pad "18" smd oval
			(at -0.7493 3.44932)
			(size 0.3048 0.8382)
			(layers "F.Cu" "F.Mask" "F.Paste")
			(net "P52V_HS1_PWRGIN")
		)
		(pad "19" smd oval
			(at -0.24892 3.44932)
			(size 0.3048 0.8382)
			(layers "F.Cu" "F.Mask" "F.Paste")
			(net "GND_FIELD_SIGNAL")
		)
		(pad "20" smd oval
			(at 1.24968 3.44932)
			(size 0.3048 0.8382)
			(layers "F.Cu" "F.Mask" "F.Paste")
			(net "P52V_HS1_VCC")
		)
		(pad "21" smd oval
			(at 1.75006 3.44932)
			(size 0.3048 0.8382)
			(layers "F.Cu" "F.Mask" "F.Paste")
			(net "P52V_HS1_VCC")
		)
		(pad "22" smd oval
			(at 2.25044 3.44932)
			(size 0.3048 0.8382)
			(layers "F.Cu" "F.Mask" "F.Paste")
			(net "P52V_HS1_VCC")
		)
		(pad "23" smd oval
			(at 2.75082 3.44932)
			(size 0.3048 0.8382)
			(layers "F.Cu" "F.Mask" "F.Paste")
			(net "P52V_HS1_VCC")
		)
		(pad "24" smd oval
			(at 3.2512 3.44932)
			(size 0.3048 0.8382)
			(layers "F.Cu" "F.Mask" "F.Paste")
			(net "P52V_HS1_VCC")
		)
		(pad "25" smd oval
			(at 3.9497 2.75082 270)
			(size 0.3048 0.8382)
			(layers "F.Cu" "F.Mask" "F.Paste")
			(net "Net_7")
		)
		(pad "26" smd oval
			(at 3.9497 2.25044 270)
			(size 0.3048 0.8382)
			(layers "F.Cu" "F.Mask" "F.Paste")
			(net "Net_11")
		)
		(pad "27" smd oval
			(at 3.9497 1.75006 270)
			(size 0.3048 0.8382)
			(layers "F.Cu" "F.Mask" "F.Paste")
			(net "Net_6")
		)
		(pad "28" smd oval
			(at 3.9497 1.24968 270)
			(size 0.3048 0.8382)
			(layers "F.Cu" "F.Mask" "F.Paste")
			(net "Net_5")
		)
		(pad "29" smd oval
			(at 3.9497 0.7493 270)
			(size 0.3048 0.8382)
			(layers "F.Cu" "F.Mask" "F.Paste")
			(net "P52V_HS1_VCP")
		)
		(pad "30" smd oval
			(at 3.9497 0.24892 270)
			(size 0.3048 0.8382)
			(layers "F.Cu" "F.Mask" "F.Paste")
			(net "P52V_HS1_DV_DT_R")
		)
		(pad "31" smd oval
			(at 3.9497 -0.24892 270)
			(size 0.3048 0.8382)
			(layers "F.Cu" "F.Mask" "F.Paste")
			(net "P52V_HS")
		)
		(pad "32" smd oval
			(at 3.9497 -0.7493 270)
			(size 0.3048 0.8382)
			(layers "F.Cu" "F.Mask" "F.Paste")
			(net "P52V_HS1_1272_GATE")
		)
		(pad "33" smd oval
			(at 3.9497 -1.24968 270)
			(size 0.3048 0.8382)
			(layers "F.Cu" "F.Mask" "F.Paste")
			(net "Net_9")
		)
		(pad "34" smd oval
			(at 3.9497 -1.75006 270)
			(size 0.3048 0.8382)
			(layers "F.Cu" "F.Mask" "F.Paste")
			(net "Net_4")
		)
		(pad "35" smd oval
			(at 3.9497 -2.25044 270)
			(size 0.3048 0.8382)
			(layers "F.Cu" "F.Mask" "F.Paste")
			(net "Net_3")
		)
		(pad "36" smd oval
			(at 3.9497 -2.75082 270)
			(size 0.3048 0.8382)
			(layers "F.Cu" "F.Mask" "F.Paste")
			(net "Net_12")
		)
		(pad "37" smd oval
			(at 3.2512 -3.44932)
			(size 0.3048 0.8382)
			(layers "F.Cu" "F.Mask" "F.Paste")
			(net "Net_10")
		)
		(pad "38" smd oval
			(at 2.75082 -3.44932)
			(size 0.3048 0.8382)
			(layers "F.Cu" "F.Mask" "F.Paste")
			(net "P52V_HS_1272_S_N")
		)
		(pad "39" smd oval
			(at 2.25044 -3.44932)
			(size 0.3048 0.8382)
			(layers "F.Cu" "F.Mask" "F.Paste")
			(net "P52V_HS_1272_S_P")
		)
		(pad "40" smd oval
			(at 1.75006 -3.44932)
			(size 0.3048 0.8382)
			(layers "F.Cu" "F.Mask" "F.Paste")
			(net "Net_8")
		)
		(pad "41" smd oval
			(at 1.24968 -3.44932)
			(size 0.3048 0.8382)
			(layers "F.Cu" "F.Mask" "F.Paste")
			(net "P52V_HS1_VCC")
		)
		(pad "42" smd oval
			(at -0.24892 -3.44932)
			(size 0.3048 0.8382)
			(layers "F.Cu" "F.Mask" "F.Paste")
			(net "P52V_HS1_VREG")
		)
		(pad "43" smd oval
			(at -0.7493 -3.44932)
			(size 0.3048 0.8382)
			(layers "F.Cu" "F.Mask" "F.Paste")
			(net "P52V_HS1_TEMPN")
		)
		(pad "44" smd oval
			(at -1.24968 -3.44932)
			(size 0.3048 0.8382)
			(layers "F.Cu" "F.Mask" "F.Paste")
			(net "P52V_HS1_TEMPP")
		)
		(pad "45" smd oval
			(at -1.75006 -3.44932)
			(size 0.3048 0.8382)
			(layers "F.Cu" "F.Mask" "F.Paste")
			(net "P52V_HS1_UVH")
		)
		(pad "46" smd oval
			(at -2.25044 -3.44932)
			(size 0.3048 0.8382)
			(layers "F.Cu" "F.Mask" "F.Paste")
			(net "P52V_HS1_UVLO_EN")
		)
		(pad "47" smd oval
			(at -2.75082 -3.44932)
			(size 0.3048 0.8382)
			(layers "F.Cu" "F.Mask" "F.Paste")
			(net "P52V_HS1_OV")
		)
		(pad "48" smd oval
			(at -3.2512 -3.44932)
			(size 0.3048 0.8382)
			(layers "F.Cu" "F.Mask" "F.Paste")
			(net "P52V_HS1_RND")
		)
		(pad "PAD1" smd rect
			(at -1.89738 0)
			(size 2.794 5.588)
			(layers "F.Cu" "F.Mask" "F.Paste")
			(net "GND_FIELD_SIGNAL")
		)
		(pad "PAD2" smd rect
			(at 1.55194 0)
			(size 1.4986 3.4036)
			(layers "F.Cu" "F.Mask" "F.Paste")
			(net "P52V_HS1_VCC")
		)
		(zone
			(layer "F.Cu")
			(hatch none 0.5)
			(connect_pads
				(clearance 0)
			)
			(min_thickness 0.25)
			(keepout
				(tracks not_allowed)
				(vias allowed)
				(pads allowed)
				(copperpour not_allowed)
				(footprints allowed)
			)
			(placement
				(enabled no)
				(sheetname "")
			)
			(fill
				(thermal_gap 0.5)
				(thermal_bridge_width 0.5)
				(island_removal_mode 0)
			)
			(polygon
				(pts
					(xy 291.025072 -45.313346) (xy 291.025072 -39.369746) (xy 288.307272 -39.369746) (xy 288.307272 -40.588946)
					(xy 289.907472 -40.588946) (xy 289.907472 -44.094146) (xy 288.307272 -44.094146) (xy 288.307272 -45.313346)
				)
			)
		)
		(zone
			(layer "F.Cu")
			(hatch none 0.5)
			(connect_pads
				(clearance 0)
			)
			(min_thickness 0.25)
			(keepout
				(tracks not_allowed)
				(vias allowed)
				(pads allowed)
				(copperpour not_allowed)
				(footprints allowed)
			)
			(placement
				(enabled no)
				(sheetname "")
			)
			(fill
				(thermal_gap 0.5)
				(thermal_bridge_width 0.5)
				(island_removal_mode 0)
			)
			(polygon
				(pts
					(xy 284.065472 -43.662346) (xy 284.065472 -39.369746) (xy 288.281872 -39.369746) (xy 288.281872 -45.313346)
					(xy 284.065472 -45.313346) (xy 284.065472 -43.687746) (xy 284.192472 -43.687746) (xy 284.192472 -45.186346)
					(xy 287.113472 -45.186346) (xy 287.113472 -39.496746) (xy 284.192472 -39.496746) (xy 284.192472 -43.662346)
				)
			)
		)
	)
	(footprint ""
		(layer "F.Cu")
		(at 283.972 -49.276 90)
		(property "Reference" "PR6931"
			(at 0 0 90)
			(layer "F.SilkS")
			(hide yes)
			(effects
				(font
					(size 1.27 1.27)
				)
			)
		)
		(property "Value" ""
			(at 0 0 90)
			(layer "F.Fab")
			(effects
				(font
					(size 1.27 1.27)
				)
			)
		)
		(duplicate_pad_numbers_are_jumpers no)
		(fp_line
			(start 0.7874 -0.4064)
			(end 0.7874 0.4064)
			(stroke
				(width 0.1524)
				(type default)
			)
			(layer "F.SilkS")
		)
		(fp_line
			(start -0.7874 -0.4064)
			(end 0.7874 -0.4064)
			(stroke
				(width 0.1524)
				(type default)
			)
			(layer "F.SilkS")
		)
		(fp_line
			(start 0.7874 0.4064)
			(end -0.7874 0.4064)
			(stroke
				(width 0.1524)
				(type default)
			)
			(layer "F.SilkS")
		)
		(fp_line
			(start -0.7874 0.4064)
			(end -0.7874 -0.4064)
			(stroke
				(width 0.1524)
				(type default)
			)
			(layer "F.SilkS")
		)
		(fp_line
			(start -0.12065 -0.305054)
			(end -0.12065 -0.2794)
			(stroke
				(width 0.1)
				(type default)
			)
			(layer "F.Fab")
		)
		(fp_line
			(start -0.67945 -0.305054)
			(end -0.12065 -0.305054)
			(stroke
				(width 0.1)
				(type default)
			)
			(layer "F.Fab")
		)
		(fp_line
			(start 0.67945 -0.3048)
			(end 0.67945 0.3048)
			(stroke
				(width 0.1)
				(type default)
			)
			(layer "F.Fab")
		)
		(fp_line
			(start 0.12065 -0.3048)
			(end 0.67945 -0.3048)
			(stroke
				(width 0.1)
				(type default)
			)
			(layer "F.Fab")
		)
		(fp_line
			(start 0.12065 -0.2794)
			(end 0.12065 -0.3048)
			(stroke
				(width 0.1)
				(type default)
			)
			(layer "F.Fab")
		)
		(fp_line
			(start -0.12065 -0.2794)
			(end 0.12065 -0.2794)
			(stroke
				(width 0.1)
				(type default)
			)
			(layer "F.Fab")
		)
		(fp_line
			(start 0.120396 0.2794)
			(end -0.12065 0.2794)
			(stroke
				(width 0.1)
				(type default)
			)
			(layer "F.Fab")
		)
		(fp_line
			(start -0.12065 0.2794)
			(end -0.12065 0.3048)
			(stroke
				(width 0.1)
				(type default)
			)
			(layer "F.Fab")
		)
		(fp_line
			(start 0.67945 0.3048)
			(end 0.120396 0.3048)
			(stroke
				(width 0.1)
				(type default)
			)
			(layer "F.Fab")
		)
		(fp_line
			(start 0.120396 0.3048)
			(end 0.120396 0.2794)
			(stroke
				(width 0.1)
				(type default)
			)
			(layer "F.Fab")
		)
		(fp_line
			(start -0.12065 0.3048)
			(end -0.67945 0.3048)
			(stroke
				(width 0.1)
				(type default)
			)
			(layer "F.Fab")
		)
		(fp_line
			(start -0.67945 0.3048)
			(end -0.67945 -0.305054)
			(stroke
				(width 0.1)
				(type default)
			)
			(layer "F.Fab")
		)
		(pad "1" smd circle
			(at -0.40005 0 90)
			(size 0 0)
			(layers "F.Cu" "F.Mask" "F.Paste")
			(net "P52V_HS1_UVH")
		)
		(pad "2" smd circle
			(at 0.40005 0 90)
			(size 0 0)
			(layers "F.Cu" "F.Mask" "F.Paste")
			(net "GND_FIELD_SIGNAL")
		)
	)
	(footprint ""
		(layer "F.Cu")
		(at 217.932 -95.504 -90)
		(property "Reference" "C25"
			(at 0 0 270)
			(layer "F.SilkS")
			(hide yes)
			(effects
				(font
					(size 1.27 1.27)
				)
			)
		)
		(property "Value" ""
			(at 0 0 270)
			(layer "F.Fab")
			(effects
				(font
					(size 1.27 1.27)
				)
			)
		)
		(duplicate_pad_numbers_are_jumpers no)
		(fp_line
			(start -2.2098 0.9398)
			(end -2.2098 -0.9398)
			(stroke
				(width 0.1524)
				(type default)
			)
			(layer "F.SilkS")
		)
		(fp_line
			(start 2.2098 0.9398)
			(end -2.2098 0.9398)
			(stroke
				(width 0.1524)
				(type default)
			)
			(layer "F.SilkS")
		)
		(fp_line
			(start -2.2098 -0.9398)
			(end 2.2098 -0.9398)
			(stroke
				(width 0.1524)
				(type default)
			)
			(layer "F.SilkS")
		)
		(fp_line
			(start 2.2098 -0.9398)
			(end 2.2098 0.9398)
			(stroke
				(width 0.1524)
				(type default)
			)
			(layer "F.SilkS")
		)
		(fp_line
			(start -1.700022 0.899922)
			(end -1.700022 -0.899922)
			(stroke
				(width 0.1)
				(type default)
			)
			(layer "F.Fab")
		)
		(fp_line
			(start 1.700022 0.899922)
			(end -1.700022 0.899922)
			(stroke
				(width 0.1)
				(type default)
			)
			(layer "F.Fab")
		)
		(fp_line
			(start -1.700022 -0.899922)
			(end 1.700022 -0.899922)
			(stroke
				(width 0.1)
				(type default)
			)
			(layer "F.Fab")
		)
		(fp_line
			(start 1.700022 -0.899922)
			(end 1.700022 0.899922)
			(stroke
				(width 0.1)
				(type default)
			)
			(layer "F.Fab")
		)
		(pad "1" smd rect
			(at -1.4732 0 90)
			(size 1.1684 1.5748)
			(layers "F.Cu" "F.Mask" "F.Paste")
			(net "P52V_HS")
		)
		(pad "2" smd rect
			(at 1.4732 0 90)
			(size 1.1684 1.5748)
			(layers "F.Cu" "F.Mask" "F.Paste")
			(net "GND")
		)
	)
	(footprint ""
		(layer "F.Cu")
		(at 168.0464 -12.4968 90)
		(property "Reference" "PC567"
			(at 0 0 90)
			(layer "F.SilkS")
			(hide yes)
			(effects
				(font
					(size 1.27 1.27)
				)
			)
		)
		(property "Value" ""
			(at 0 0 90)
			(layer "F.Fab")
			(effects
				(font
					(size 1.27 1.27)
				)
			)
		)
		(duplicate_pad_numbers_are_jumpers no)
		(fp_line
			(start 1.524 -0.762)
			(end 1.524 0.762)
			(stroke
				(width 0.1524)
				(type default)
			)
			(layer "F.SilkS")
		)
		(fp_line
			(start -1.524 -0.762)
			(end 1.524 -0.762)
			(stroke
				(width 0.1524)
				(type default)
			)
			(layer "F.SilkS")
		)
		(fp_line
			(start 1.524 0.762)
			(end -1.524 0.762)
			(stroke
				(width 0.1524)
				(type default)
			)
			(layer "F.SilkS")
		)
		(fp_line
			(start -1.524 0.762)
			(end -1.524 -0.762)
			(stroke
				(width 0.1524)
				(type default)
			)
			(layer "F.SilkS")
		)
		(fp_line
			(start 1.1049 -0.724916)
			(end -1.1049 -0.724916)
			(stroke
				(width 0.1)
				(type default)
			)
			(layer "F.Fab")
		)
		(fp_line
			(start -1.1049 -0.724916)
			(end -1.1049 0.724916)
			(stroke
				(width 0.1)
				(type default)
			)
			(layer "F.Fab")
		)
		(fp_line
			(start 1.1049 0.724916)
			(end 1.1049 -0.724916)
			(stroke
				(width 0.1)
				(type default)
			)
			(layer "F.Fab")
		)
		(fp_line
			(start -1.1049 0.724916)
			(end 1.1049 0.724916)
			(stroke
				(width 0.1)
				(type default)
			)
			(layer "F.Fab")
		)
		(pad "1" smd rect
			(at -0.889 0 270)
			(size 1.016 1.27)
			(layers "F.Cu" "F.Mask" "F.Paste")
			(net "SW_P12V_FILT__P3V3_AUX")
		)
		(pad "2" smd rect
			(at 0.889 0 270)
			(size 1.016 1.27)
			(layers "F.Cu" "F.Mask" "F.Paste")
			(net "GND")
		)
	)
	(footprint ""
		(layer "F.Cu")
		(at 179.065174 -62.992)
		(property "Reference" "PC122"
			(at 0 0 0)
			(layer "F.SilkS")
			(hide yes)
			(effects
				(font
					(size 1.27 1.27)
				)
			)
		)
		(property "Value" ""
			(at 0 0 0)
			(layer "F.Fab")
			(effects
				(font
					(size 1.27 1.27)
				)
			)
		)
		(duplicate_pad_numbers_are_jumpers no)
		(fp_line
			(start -0.7874 -0.4064)
			(end 0.7874 -0.4064)
			(stroke
				(width 0.1524)
				(type default)
			)
			(layer "F.SilkS")
		)
		(fp_line
			(start -0.7874 0.4064)
			(end -0.7874 -0.4064)
			(stroke
				(width 0.1524)
				(type default)
			)
			(layer "F.SilkS")
		)
		(fp_line
			(start 0.7874 -0.4064)
			(end 0.7874 0.4064)
			(stroke
				(width 0.1524)
				(type default)
			)
			(layer "F.SilkS")
		)
		(fp_line
			(start 0.7874 0.4064)
			(end -0.7874 0.4064)
			(stroke
				(width 0.1524)
				(type default)
			)
			(layer "F.SilkS")
		)
		(fp_line
			(start -0.6858 -0.3048)
			(end -0.1016 -0.3048)
			(stroke
				(width 0.1)
				(type default)
			)
			(layer "F.Fab")
		)
		(fp_line
			(start -0.6858 0.3048)
			(end -0.6858 -0.3048)
			(stroke
				(width 0.1)
				(type default)
			)
			(layer "F.Fab")
		)
		(fp_line
			(start -0.1016 -0.3048)
			(end -0.1016 -0.2794)
			(stroke
				(width 0.1)
				(type default)
			)
			(layer "F.Fab")
		)
		(fp_line
			(start -0.1016 -0.2794)
			(end 0.1016 -0.2794)
			(stroke
				(width 0.1)
				(type default)
			)
			(layer "F.Fab")
		)
		(fp_line
			(start -0.1016 0.2794)
			(end -0.1016 0.3048)
			(stroke
				(width 0.1)
				(type default)
			)
			(layer "F.Fab")
		)
		(fp_line
			(start -0.1016 0.3048)
			(end -0.6858 0.3048)
			(stroke
				(width 0.1)
				(type default)
			)
			(layer "F.Fab")
		)
		(fp_line
			(start 0.1016 -0.3048)
			(end 0.6858 -0.3048)
			(stroke
				(width 0.1)
				(type default)
			)
			(layer "F.Fab")
		)
		(fp_line
			(start 0.1016 -0.2794)
			(end 0.1016 -0.3048)
			(stroke
				(width 0.1)
				(type default)
			)
			(layer "F.Fab")
		)
		(fp_line
			(start 0.1016 0.2794)
			(end -0.1016 0.2794)
			(stroke
				(width 0.1)
				(type default)
			)
			(layer "F.Fab")
		)
		(fp_line
			(start 0.1016 0.3048)
			(end 0.1016 0.2794)
			(stroke
				(width 0.1)
				(type default)
			)
			(layer "F.Fab")
		)
		(fp_line
			(start 0.6858 -0.3048)
			(end 0.6858 0.3048)
			(stroke
				(width 0.1)
				(type default)
			)
			(layer "F.Fab")
		)
		(fp_line
			(start 0.6858 0.3048)
			(end 0.1016 0.3048)
			(stroke
				(width 0.1)
				(type default)
			)
			(layer "F.Fab")
		)
		(pad "1" smd rect
			(at -0.40005 0 180)
			(size 0.4572 0.508)
			(layers "F.Cu" "F.Mask" "F.Paste")
			(net "P12V_BRICK")
		)
		(pad "2" smd rect
			(at 0.40005 0 180)
			(size 0.4572 0.508)
			(layers "F.Cu" "F.Mask" "F.Paste")
			(net "GND")
		)
	)
	(footprint ""
		(layer "F.Cu")
		(at 272.936716 -41.342818 -90)
		(property "Reference" "U29"
			(at -2.916682 -2.083054 90)
			(unlocked yes)
			(layer "F.SilkS")
			(effects
				(font
					(size 0.7874 0.5842)
					(thickness 0.1524)
				)
				(justify left)
			)
		)
		(property "Value" ""
			(at 0 0 270)
			(layer "F.Fab")
			(effects
				(font
					(size 1.27 1.27)
				)
			)
		)
		(duplicate_pad_numbers_are_jumpers no)
		(fp_line
			(start -2.249932 1.549908)
			(end 2.249932 1.549908)
			(stroke
				(width 0.1524)
				(type default)
			)
			(layer "F.SilkS")
		)
		(fp_line
			(start 2.249932 1.549908)
			(end 2.249932 -1.549908)
			(stroke
				(width 0.1524)
				(type default)
			)
			(layer "F.SilkS")
		)
		(fp_line
			(start 0 -0.8128)
			(end -0.737108 -1.549908)
			(stroke
				(width 0.1524)
				(type default)
			)
			(layer "F.SilkS")
		)
		(fp_line
			(start -2.249932 -1.549908)
			(end -2.249932 1.549908)
			(stroke
				(width 0.1524)
				(type default)
			)
			(layer "F.SilkS")
		)
		(fp_line
			(start -0.737108 -1.549908)
			(end -2.249932 -1.549908)
			(stroke
				(width 0.1524)
				(type default)
			)
			(layer "F.SilkS")
		)
		(fp_line
			(start 0.737108 -1.549908)
			(end 0 -0.8128)
			(stroke
				(width 0.1524)
				(type default)
			)
			(layer "F.SilkS")
		)
		(fp_line
			(start 2.249932 -1.549908)
			(end 0.737108 -1.549908)
			(stroke
				(width 0.1524)
				(type default)
			)
			(layer "F.SilkS")
		)
		(fp_poly
			(pts
				(xy -4.7498 -0.467106) (xy -4.7498 -1.483106) (xy -3.7338 -0.975106)
			)
			(stroke
				(width 0)
				(type default)
			)
			(fill yes)
			(layer "F.SilkS")
		)
		(fp_line
			(start -2.249932 1.549908)
			(end 2.249932 1.549908)
			(stroke
				(width 0.1)
				(type default)
			)
			(layer "F.Fab")
		)
		(fp_line
			(start 2.249932 1.549908)
			(end 2.249932 -1.549908)
			(stroke
				(width 0.1)
				(type default)
			)
			(layer "F.Fab")
		)
		(fp_line
			(start -2.249932 -1.549908)
			(end -2.249932 1.549908)
			(stroke
				(width 0.1)
				(type default)
			)
			(layer "F.Fab")
		)
		(fp_line
			(start 2.249932 -1.549908)
			(end -2.249932 -1.549908)
			(stroke
				(width 0.1)
				(type default)
			)
			(layer "F.Fab")
		)
		(fp_poly
			(pts
				(xy -4.7498 -0.467106) (xy -4.7498 -1.483106) (xy -3.7338 -0.975106)
			)
			(stroke
				(width 0)
				(type default)
			)
			(fill yes)
			(layer "F.Fab")
		)
		(pad "1" smd rect
			(at -3.052572 -0.975106 180)
			(size 0.381 1.1684)
			(layers "F.Cu" "F.Mask" "F.Paste")
			(net "P52V_HS1_CS")
		)
		(pad "2" smd rect
			(at -3.052572 -0.32512 180)
			(size 0.381 1.1684)
			(layers "F.Cu" "F.Mask" "F.Paste")
			(net "P52V_HS1_SIO")
		)
		(pad "3" smd rect
			(at -3.052572 0.32512 180)
			(size 0.381 1.1684)
			(layers "F.Cu" "F.Mask" "F.Paste")
			(net "P52V_HS1_DVCC")
		)
		(pad "4" smd rect
			(at -3.052572 0.975106 180)
			(size 0.381 1.1684)
			(layers "F.Cu" "F.Mask" "F.Paste")
			(net "GND")
		)
		(pad "5" smd rect
			(at 3.052572 0.975106 180)
			(size 0.381 1.1684)
			(layers "F.Cu" "F.Mask" "F.Paste")
			(net "P52V_HS1_SIO")
		)
		(pad "6" smd rect
			(at 3.052572 0.32512 180)
			(size 0.381 1.1684)
			(layers "F.Cu" "F.Mask" "F.Paste")
			(net "P52V_HS1_SCK")
		)
		(pad "7" smd rect
			(at 3.052572 -0.32512 180)
			(size 0.381 1.1684)
			(layers "F.Cu" "F.Mask" "F.Paste")
			(net "P52V_HS1_DVCC")
		)
		(pad "8" smd rect
			(at 3.052572 -0.975106 180)
			(size 0.381 1.1684)
			(layers "F.Cu" "F.Mask" "F.Paste")
			(net "P52V_HS1_DVCC")
		)
	)
	(footprint ""
		(layer "F.Cu")
		(at 42.17416 -61.93282 -90)
		(property "Reference" "R5891"
			(at 0 0 270)
			(layer "F.SilkS")
			(hide yes)
			(effects
				(font
					(size 1.27 1.27)
				)
			)
		)
		(property "Value" ""
			(at 0 0 270)
			(layer "F.Fab")
			(effects
				(font
					(size 1.27 1.27)
				)
			)
		)
		(duplicate_pad_numbers_are_jumpers no)
		(fp_line
			(start -0.7874 0.4064)
			(end -0.7874 -0.4064)
			(stroke
				(width 0.1524)
				(type default)
			)
			(layer "F.SilkS")
		)
		(fp_line
			(start 0.7874 0.4064)
			(end -0.7874 0.4064)
			(stroke
				(width 0.1524)
				(type default)
			)
			(layer "F.SilkS")
		)
		(fp_line
			(start -0.7874 -0.4064)
			(end 0.7874 -0.4064)
			(stroke
				(width 0.1524)
				(type default)
			)
			(layer "F.SilkS")
		)
		(fp_line
			(start 0.7874 -0.4064)
			(end 0.7874 0.4064)
			(stroke
				(width 0.1524)
				(type default)
			)
			(layer "F.SilkS")
		)
		(fp_line
			(start -0.67945 0.3048)
			(end -0.67945 -0.305054)
			(stroke
				(width 0.1)
				(type default)
			)
			(layer "F.Fab")
		)
		(fp_line
			(start -0.12065 0.3048)
			(end -0.67945 0.3048)
			(stroke
				(width 0.1)
				(type default)
			)
			(layer "F.Fab")
		)
		(fp_line
			(start 0.120396 0.3048)
			(end 0.120396 0.2794)
			(stroke
				(width 0.1)
				(type default)
			)
			(layer "F.Fab")
		)
		(fp_line
			(start 0.67945 0.3048)
			(end 0.120396 0.3048)
			(stroke
				(width 0.1)
				(type default)
			)
			(layer "F.Fab")
		)
		(fp_line
			(start -0.12065 0.2794)
			(end -0.12065 0.3048)
			(stroke
				(width 0.1)
				(type default)
			)
			(layer "F.Fab")
		)
		(fp_line
			(start 0.120396 0.2794)
			(end -0.12065 0.2794)
			(stroke
				(width 0.1)
				(type default)
			)
			(layer "F.Fab")
		)
		(fp_line
			(start -0.12065 -0.2794)
			(end 0.12065 -0.2794)
			(stroke
				(width 0.1)
				(type default)
			)
			(layer "F.Fab")
		)
		(fp_line
			(start 0.12065 -0.2794)
			(end 0.12065 -0.3048)
			(stroke
				(width 0.1)
				(type default)
			)
			(layer "F.Fab")
		)
		(fp_line
			(start 0.12065 -0.3048)
			(end 0.67945 -0.3048)
			(stroke
				(width 0.1)
				(type default)
			)
			(layer "F.Fab")
		)
		(fp_line
			(start 0.67945 -0.3048)
			(end 0.67945 0.3048)
			(stroke
				(width 0.1)
				(type default)
			)
			(layer "F.Fab")
		)
		(fp_line
			(start -0.67945 -0.305054)
			(end -0.12065 -0.305054)
			(stroke
				(width 0.1)
				(type default)
			)
			(layer "F.Fab")
		)
		(fp_line
			(start -0.12065 -0.305054)
			(end -0.12065 -0.2794)
			(stroke
				(width 0.1)
				(type default)
			)
			(layer "F.Fab")
		)
		(pad "1" smd circle
			(at -0.40005 0 270)
			(size 0 0)
			(layers "F.Cu" "F.Mask" "F.Paste")
			(net "P3V3_AUX")
		)
		(pad "2" smd circle
			(at 0.40005 0 270)
			(size 0 0)
			(layers "F.Cu" "F.Mask" "F.Paste")
			(net "P12V_HPDB_PWRGD")
		)
	)
	(footprint ""
		(layer "F.Cu")
		(at 277.114 -138.557 180)
		(property "Reference" "PD8"
			(at -2.921 -3.96367 0)
			(unlocked yes)
			(layer "F.SilkS")
			(effects
				(font
					(size 0.7874 0.5842)
					(thickness 0.1524)
				)
				(justify left)
			)
		)
		(property "Value" ""
			(at 0 0 180)
			(layer "F.Fab")
			(effects
				(font
					(size 1.27 1.27)
				)
			)
		)
		(duplicate_pad_numbers_are_jumpers no)
		(fp_line
			(start 5.334 3.109976)
			(end 5.334 0)
			(stroke
				(width 0.1524)
				(type default)
			)
			(layer "F.SilkS")
		)
		(fp_line
			(start 5.334 3.109976)
			(end 4.8133 3.109976)
			(stroke
				(width 0.1524)
				(type default)
			)
			(layer "F.SilkS")
		)
		(fp_line
			(start 5.334 0)
			(end 5.334 -3.109976)
			(stroke
				(width 0.1524)
				(type default)
			)
			(layer "F.SilkS")
		)
		(fp_line
			(start 5.207 3.109976)
			(end 5.207 -3.109976)
			(stroke
				(width 0.1524)
				(type default)
			)
			(layer "F.SilkS")
		)
		(fp_line
			(start 5.1308 3.109976)
			(end 5.1308 -3.109976)
			(stroke
				(width 0.1524)
				(type default)
			)
			(layer "F.SilkS")
		)
		(fp_line
			(start 5.0292 3.109976)
			(end 5.0292 -3.109976)
			(stroke
				(width 0.1524)
				(type default)
			)
			(layer "F.SilkS")
		)
		(fp_line
			(start 4.9276 3.109976)
			(end 4.9276 -3.109976)
			(stroke
				(width 0.1524)
				(type default)
			)
			(layer "F.SilkS")
		)
		(fp_line
			(start 4.826 3.109976)
			(end -4.826 3.109976)
			(stroke
				(width 0.1524)
				(type default)
			)
			(layer "F.SilkS")
		)
		(fp_line
			(start 4.826 0)
			(end 4.826 3.109976)
			(stroke
				(width 0.1524)
				(type default)
			)
			(layer "F.SilkS")
		)
		(fp_line
			(start 4.826 -3.109976)
			(end 4.826 0)
			(stroke
				(width 0.1524)
				(type default)
			)
			(layer "F.SilkS")
		)
		(fp_line
			(start 4.8133 -3.109976)
			(end 5.3467 -3.109976)
			(stroke
				(width 0.1524)
				(type default)
			)
			(layer "F.SilkS")
		)
		(fp_line
			(start 1.143 1.397)
			(end 1.143 -1.397)
			(stroke
				(width 0.1524)
				(type default)
			)
			(layer "F.SilkS")
		)
		(fp_line
			(start 1.143 0)
			(end 1.8034 0)
			(stroke
				(width 0.1524)
				(type default)
			)
			(layer "F.SilkS")
		)
		(fp_line
			(start 1.143 0)
			(end -1.016 -1.016)
			(stroke
				(width 0.1524)
				(type default)
			)
			(layer "F.SilkS")
		)
		(fp_line
			(start -1.016 1.016)
			(end 1.016 0)
			(stroke
				(width 0.1524)
				(type default)
			)
			(layer "F.SilkS")
		)
		(fp_line
			(start -1.016 -1.016)
			(end -1.016 1.016)
			(stroke
				(width 0.1524)
				(type default)
			)
			(layer "F.SilkS")
		)
		(fp_line
			(start -1.0922 0)
			(end -1.7018 0)
			(stroke
				(width 0.1524)
				(type default)
			)
			(layer "F.SilkS")
		)
		(fp_line
			(start -4.826 3.109976)
			(end -4.826 0)
			(stroke
				(width 0.1524)
				(type default)
			)
			(layer "F.SilkS")
		)
		(fp_line
			(start -4.826 0)
			(end -4.826 -3.109976)
			(stroke
				(width 0.1524)
				(type default)
			)
			(layer "F.SilkS")
		)
		(fp_line
			(start -4.826 -3.109976)
			(end 4.826 -3.109976)
			(stroke
				(width 0.1524)
				(type default)
			)
			(layer "F.SilkS")
		)
		(fp_line
			(start 3.554984 3.109976)
			(end -3.554984 3.109976)
			(stroke
				(width 0.1)
				(type default)
			)
			(layer "F.Fab")
		)
		(fp_line
			(start 3.554984 -3.109976)
			(end 3.554984 3.109976)
			(stroke
				(width 0.1)
				(type default)
			)
			(layer "F.Fab")
		)
		(fp_line
			(start 1.143 1.397)
			(end 1.143 -1.397)
			(stroke
				(width 0.1)
				(type default)
			)
			(layer "F.Fab")
		)
		(fp_line
			(start 1.143 0)
			(end 1.8034 0)
			(stroke
				(width 0.1)
				(type default)
			)
			(layer "F.Fab")
		)
		(fp_line
			(start 1.143 0)
			(end -1.016 -1.016)
			(stroke
				(width 0.1)
				(type default)
			)
			(layer "F.Fab")
		)
		(fp_line
			(start -1.016 1.016)
			(end 1.016 0)
			(stroke
				(width 0.1)
				(type default)
			)
			(layer "F.Fab")
		)
		(fp_line
			(start -1.016 -1.016)
			(end -1.016 1.016)
			(stroke
				(width 0.1)
				(type default)
			)
			(layer "F.Fab")
		)
		(fp_line
			(start -1.0922 0)
			(end -1.7018 0)
			(stroke
				(width 0.1)
				(type default)
			)
			(layer "F.Fab")
		)
		(fp_line
			(start -3.554984 3.109976)
			(end -3.554984 -3.109976)
			(stroke
				(width 0.1)
				(type default)
			)
			(layer "F.Fab")
		)
		(fp_line
			(start -3.554984 -3.109976)
			(end 3.554984 -3.109976)
			(stroke
				(width 0.1)
				(type default)
			)
			(layer "F.Fab")
		)
		(fp_text user "-"
			(at 7.62 0.34925 0)
			(unlocked yes)
			(layer "F.SilkS")
			(effects
				(font
					(size 1.905 1.4224)
					(thickness 0.1524)
				)
				(justify left)
			)
		)
		(fp_text user "+"
			(at -6.731 0.47625 0)
			(unlocked yes)
			(layer "F.SilkS")
			(effects
				(font
					(size 1.905 1.4224)
					(thickness 0.1524)
				)
				(justify left)
			)
		)
		(fp_text user "-"
			(at 6.6802 0.22225 0)
			(unlocked yes)
			(layer "F.Fab")
			(effects
				(font
					(size 1.905 1.4224)
					(thickness 0.1524)
				)
				(justify left)
			)
		)
		(fp_text user "+"
			(at -4.5466 0.19685 0)
			(unlocked yes)
			(layer "F.Fab")
			(effects
				(font
					(size 1.905 1.4224)
					(thickness 0.1524)
				)
				(justify left)
			)
		)
		(pad "A" smd rect
			(at -3.400044 0)
			(size 2.5146 3.302)
			(layers "F.Cu" "F.Mask" "F.Paste")
			(net "GND")
		)
		(pad "C" smd rect
			(at 3.400044 0)
			(size 2.5146 3.302)
			(layers "F.Cu" "F.Mask" "F.Paste")
			(net "P52V_HS")
		)
	)
	(footprint ""
		(layer "F.Cu")
		(at 45.67936 -58.75782)
		(property "Reference" "C96"
			(at 0 0 0)
			(layer "F.SilkS")
			(hide yes)
			(effects
				(font
					(size 1.27 1.27)
				)
			)
		)
		(property "Value" ""
			(at 0 0 0)
			(layer "F.Fab")
			(effects
				(font
					(size 1.27 1.27)
				)
			)
		)
		(duplicate_pad_numbers_are_jumpers no)
		(fp_line
			(start -0.7874 -0.4064)
			(end 0.7874 -0.4064)
			(stroke
				(width 0.1524)
				(type default)
			)
			(layer "F.SilkS")
		)
		(fp_line
			(start -0.7874 0.4064)
			(end -0.7874 -0.4064)
			(stroke
				(width 0.1524)
				(type default)
			)
			(layer "F.SilkS")
		)
		(fp_line
			(start 0.7874 -0.4064)
			(end 0.7874 0.4064)
			(stroke
				(width 0.1524)
				(type default)
			)
			(layer "F.SilkS")
		)
		(fp_line
			(start 0.7874 0.4064)
			(end -0.7874 0.4064)
			(stroke
				(width 0.1524)
				(type default)
			)
			(layer "F.SilkS")
		)
		(fp_line
			(start -0.67945 -0.305054)
			(end -0.12065 -0.305054)
			(stroke
				(width 0.1)
				(type default)
			)
			(layer "F.Fab")
		)
		(fp_line
			(start -0.67945 0.3048)
			(end -0.67945 -0.305054)
			(stroke
				(width 0.1)
				(type default)
			)
			(layer "F.Fab")
		)
		(fp_line
			(start -0.12065 -0.305054)
			(end -0.12065 -0.2794)
			(stroke
				(width 0.1)
				(type default)
			)
			(layer "F.Fab")
		)
		(fp_line
			(start -0.12065 -0.2794)
			(end 0.12065 -0.2794)
			(stroke
				(width 0.1)
				(type default)
			)
			(layer "F.Fab")
		)
		(fp_line
			(start -0.12065 0.2794)
			(end -0.12065 0.3048)
			(stroke
				(width 0.1)
				(type default)
			)
			(layer "F.Fab")
		)
		(fp_line
			(start -0.12065 0.3048)
			(end -0.67945 0.3048)
			(stroke
				(width 0.1)
				(type default)
			)
			(layer "F.Fab")
		)
		(fp_line
			(start 0.120396 0.2794)
			(end -0.12065 0.2794)
			(stroke
				(width 0.1)
				(type default)
			)
			(layer "F.Fab")
		)
		(fp_line
			(start 0.120396 0.3048)
			(end 0.120396 0.2794)
			(stroke
				(width 0.1)
				(type default)
			)
			(layer "F.Fab")
		)
		(fp_line
			(start 0.12065 -0.3048)
			(end 0.67945 -0.3048)
			(stroke
				(width 0.1)
				(type default)
			)
			(layer "F.Fab")
		)
		(fp_line
			(start 0.12065 -0.2794)
			(end 0.12065 -0.3048)
			(stroke
				(width 0.1)
				(type default)
			)
			(layer "F.Fab")
		)
		(fp_line
			(start 0.67945 -0.3048)
			(end 0.67945 0.3048)
			(stroke
				(width 0.1)
				(type default)
			)
			(layer "F.Fab")
		)
		(fp_line
			(start 0.67945 0.3048)
			(end 0.120396 0.3048)
			(stroke
				(width 0.1)
				(type default)
			)
			(layer "F.Fab")
		)
		(pad "1" smd circle
			(at -0.40005 0)
			(size 0 0)
			(layers "F.Cu" "F.Mask" "F.Paste")
			(net "P12V_HPDB_0_SS")
		)
		(pad "2" smd circle
			(at 0.40005 0)
			(size 0 0)
			(layers "F.Cu" "F.Mask" "F.Paste")
			(net "GND")
		)
	)
	(footprint ""
		(layer "F.Cu")
		(at 282.702 -21.082)
		(property "Reference" "C89"
			(at 0 0 0)
			(layer "F.SilkS")
			(hide yes)
			(effects
				(font
					(size 1.27 1.27)
				)
			)
		)
		(property "Value" ""
			(at 0 0 0)
			(layer "F.Fab")
			(effects
				(font
					(size 1.27 1.27)
				)
			)
		)
		(duplicate_pad_numbers_are_jumpers no)
		(fp_line
			(start -1.2954 -0.5842)
			(end 1.2954 -0.5842)
			(stroke
				(width 0.1524)
				(type default)
			)
			(layer "F.SilkS")
		)
		(fp_line
			(start -1.2954 0.5842)
			(end -1.2954 -0.5842)
			(stroke
				(width 0.1524)
				(type default)
			)
			(layer "F.SilkS")
		)
		(fp_line
			(start 1.2954 -0.5842)
			(end 1.2954 0.5842)
			(stroke
				(width 0.1524)
				(type default)
			)
			(layer "F.SilkS")
		)
		(fp_line
			(start 1.2954 0.5842)
			(end -1.2954 0.5842)
			(stroke
				(width 0.1524)
				(type default)
			)
			(layer "F.SilkS")
		)
		(fp_line
			(start -1.1938 -0.4064)
			(end -0.8636 -0.4064)
			(stroke
				(width 0.1)
				(type default)
			)
			(layer "F.Fab")
		)
		(fp_line
			(start -1.1938 0.4064)
			(end -1.1938 -0.4064)
			(stroke
				(width 0.1)
				(type default)
			)
			(layer "F.Fab")
		)
		(fp_line
			(start -0.8636 -0.4572)
			(end 0.8636 -0.4572)
			(stroke
				(width 0.1)
				(type default)
			)
			(layer "F.Fab")
		)
		(fp_line
			(start -0.8636 -0.4064)
			(end -0.8636 -0.4572)
			(stroke
				(width 0.1)
				(type default)
			)
			(layer "F.Fab")
		)
		(fp_line
			(start -0.8636 0.4064)
			(end -1.1938 0.4064)
			(stroke
				(width 0.1)
				(type default)
			)
			(layer "F.Fab")
		)
		(fp_line
			(start -0.8636 0.4572)
			(end -0.8636 0.4064)
			(stroke
				(width 0.1)
				(type default)
			)
			(layer "F.Fab")
		)
		(fp_line
			(start 0.8636 -0.4572)
			(end 0.8636 -0.4064)
			(stroke
				(width 0.1)
				(type default)
			)
			(layer "F.Fab")
		)
		(fp_line
			(start 0.8636 -0.4064)
			(end 1.1938 -0.4064)
			(stroke
				(width 0.1)
				(type default)
			)
			(layer "F.Fab")
		)
		(fp_line
			(start 0.8636 0.4064)
			(end 0.8636 0.4572)
			(stroke
				(width 0.1)
				(type default)
			)
			(layer "F.Fab")
		)
		(fp_line
			(start 0.8636 0.4572)
			(end -0.8636 0.4572)
			(stroke
				(width 0.1)
				(type default)
			)
			(layer "F.Fab")
		)
		(fp_line
			(start 1.1938 -0.4064)
			(end 1.1938 0.4064)
			(stroke
				(width 0.1)
				(type default)
			)
			(layer "F.Fab")
		)
		(fp_line
			(start 1.1938 0.4064)
			(end 0.8636 0.4064)
			(stroke
				(width 0.1)
				(type default)
			)
			(layer "F.Fab")
		)
		(pad "1" smd rect
			(at -0.7366 0 270)
			(size 0.7112 0.8128)
			(layers "F.Cu" "F.Mask" "F.Paste")
			(net "FM_HSC_EN_BUSBAR")
		)
		(pad "2" smd rect
			(at 0.7366 0 270)
			(size 0.7112 0.8128)
			(layers "F.Cu" "F.Mask" "F.Paste")
			(net "GND")
		)
	)
	(footprint ""
		(layer "F.Cu")
		(at 173.609 -49.911)
		(property "Reference" "PC31"
			(at 0 0 0)
			(layer "F.SilkS")
			(hide yes)
			(effects
				(font
					(size 1.27 1.27)
				)
			)
		)
		(property "Value" ""
			(at 0 0 0)
			(layer "F.Fab")
			(effects
				(font
					(size 1.27 1.27)
				)
			)
		)
		(duplicate_pad_numbers_are_jumpers no)
		(fp_line
			(start -1.524 -0.762)
			(end 1.524 -0.762)
			(stroke
				(width 0.1524)
				(type default)
			)
			(layer "F.SilkS")
		)
		(fp_line
			(start -1.524 0.762)
			(end -1.524 -0.762)
			(stroke
				(width 0.1524)
				(type default)
			)
			(layer "F.SilkS")
		)
		(fp_line
			(start 1.524 -0.762)
			(end 1.524 0.762)
			(stroke
				(width 0.1524)
				(type default)
			)
			(layer "F.SilkS")
		)
		(fp_line
			(start 1.524 0.762)
			(end -1.524 0.762)
			(stroke
				(width 0.1524)
				(type default)
			)
			(layer "F.SilkS")
		)
		(fp_line
			(start -1.1049 -0.724916)
			(end -1.1049 0.724916)
			(stroke
				(width 0.1)
				(type default)
			)
			(layer "F.Fab")
		)
		(fp_line
			(start -1.1049 0.724916)
			(end 1.1049 0.724916)
			(stroke
				(width 0.1)
				(type default)
			)
			(layer "F.Fab")
		)
		(fp_line
			(start 1.1049 -0.724916)
			(end -1.1049 -0.724916)
			(stroke
				(width 0.1)
				(type default)
			)
			(layer "F.Fab")
		)
		(fp_line
			(start 1.1049 0.724916)
			(end 1.1049 -0.724916)
			(stroke
				(width 0.1)
				(type default)
			)
			(layer "F.Fab")
		)
		(pad "1" smd rect
			(at -0.889 0 180)
			(size 1.016 1.27)
			(layers "F.Cu" "F.Mask" "F.Paste")
			(net "P12V_BRICK")
		)
		(pad "2" smd rect
			(at 0.889 0 180)
			(size 1.016 1.27)
			(layers "F.Cu" "F.Mask" "F.Paste")
			(net "GND")
		)
	)
	(footprint ""
		(layer "F.Cu")
		(at 44.713906 -127.889)
		(property "Reference" "PC74"
			(at 0 0 0)
			(layer "F.SilkS")
			(hide yes)
			(effects
				(font
					(size 1.27 1.27)
				)
			)
		)
		(property "Value" ""
			(at 0 0 0)
			(layer "F.Fab")
			(effects
				(font
					(size 1.27 1.27)
				)
			)
		)
		(duplicate_pad_numbers_are_jumpers no)
		(fp_line
			(start -2.2098 -0.9398)
			(end 2.2098 -0.9398)
			(stroke
				(width 0.1524)
				(type default)
			)
			(layer "F.SilkS")
		)
		(fp_line
			(start -2.2098 0.9398)
			(end -2.2098 -0.9398)
			(stroke
				(width 0.1524)
				(type default)
			)
			(layer "F.SilkS")
		)
		(fp_line
			(start 2.2098 -0.9398)
			(end 2.2098 0.9398)
			(stroke
				(width 0.1524)
				(type default)
			)
			(layer "F.SilkS")
		)
		(fp_line
			(start 2.2098 0.9398)
			(end -2.2098 0.9398)
			(stroke
				(width 0.1524)
				(type default)
			)
			(layer "F.SilkS")
		)
		(fp_line
			(start -1.700022 -0.899922)
			(end 1.700022 -0.899922)
			(stroke
				(width 0.1)
				(type default)
			)
			(layer "F.Fab")
		)
		(fp_line
			(start -1.700022 0.899922)
			(end -1.700022 -0.899922)
			(stroke
				(width 0.1)
				(type default)
			)
			(layer "F.Fab")
		)
		(fp_line
			(start 1.700022 -0.899922)
			(end 1.700022 0.899922)
			(stroke
				(width 0.1)
				(type default)
			)
			(layer "F.Fab")
		)
		(fp_line
			(start 1.700022 0.899922)
			(end -1.700022 0.899922)
			(stroke
				(width 0.1)
				(type default)
			)
			(layer "F.Fab")
		)
		(pad "1" smd rect
			(at -1.4732 0 180)
			(size 1.1684 1.5748)
			(layers "F.Cu" "F.Mask" "F.Paste")
			(net "P52V_HS_FILTER")
		)
		(pad "2" smd rect
			(at 1.4732 0 180)
			(size 1.1684 1.5748)
			(layers "F.Cu" "F.Mask" "F.Paste")
			(net "GND")
		)
	)
	(footprint ""
		(layer "F.Cu")
		(at 232.156 -95.504 -90)
		(property "Reference" "C37"
			(at 0 0 270)
			(layer "F.SilkS")
			(hide yes)
			(effects
				(font
					(size 1.27 1.27)
				)
			)
		)
		(property "Value" ""
			(at 0 0 270)
			(layer "F.Fab")
			(effects
				(font
					(size 1.27 1.27)
				)
			)
		)
		(duplicate_pad_numbers_are_jumpers no)
		(fp_line
			(start -2.2098 0.9398)
			(end -2.2098 -0.9398)
			(stroke
				(width 0.1524)
				(type default)
			)
			(layer "F.SilkS")
		)
		(fp_line
			(start 2.2098 0.9398)
			(end -2.2098 0.9398)
			(stroke
				(width 0.1524)
				(type default)
			)
			(layer "F.SilkS")
		)
		(fp_line
			(start -2.2098 -0.9398)
			(end 2.2098 -0.9398)
			(stroke
				(width 0.1524)
				(type default)
			)
			(layer "F.SilkS")
		)
		(fp_line
			(start 2.2098 -0.9398)
			(end 2.2098 0.9398)
			(stroke
				(width 0.1524)
				(type default)
			)
			(layer "F.SilkS")
		)
		(fp_line
			(start -1.700022 0.899922)
			(end -1.700022 -0.899922)
			(stroke
				(width 0.1)
				(type default)
			)
			(layer "F.Fab")
		)
		(fp_line
			(start 1.700022 0.899922)
			(end -1.700022 0.899922)
			(stroke
				(width 0.1)
				(type default)
			)
			(layer "F.Fab")
		)
		(fp_line
			(start -1.700022 -0.899922)
			(end 1.700022 -0.899922)
			(stroke
				(width 0.1)
				(type default)
			)
			(layer "F.Fab")
		)
		(fp_line
			(start 1.700022 -0.899922)
			(end 1.700022 0.899922)
			(stroke
				(width 0.1)
				(type default)
			)
			(layer "F.Fab")
		)
		(pad "1" smd rect
			(at -1.4732 0 90)
			(size 1.1684 1.5748)
			(layers "F.Cu" "F.Mask" "F.Paste")
			(net "P52V_HS")
		)
		(pad "2" smd rect
			(at 1.4732 0 90)
			(size 1.1684 1.5748)
			(layers "F.Cu" "F.Mask" "F.Paste")
			(net "GND")
		)
	)
	(footprint ""
		(layer "F.Cu")
		(at 50.1396 -56.8198 -90)
		(property "Reference" "D4"
			(at -4.36753 -1.5494 0)
			(unlocked yes)
			(layer "F.SilkS")
			(effects
				(font
					(size 0.7874 0.5842)
					(thickness 0.1524)
				)
				(justify left)
			)
		)
		(property "Value" ""
			(at 0 0 270)
			(layer "F.Fab")
			(effects
				(font
					(size 1.27 1.27)
				)
			)
		)
		(duplicate_pad_numbers_are_jumpers no)
		(fp_line
			(start -3.656584 1.970024)
			(end 4.240784 1.970024)
			(stroke
				(width 0.1524)
				(type default)
			)
			(layer "F.SilkS")
		)
		(fp_line
			(start 4.240784 1.970024)
			(end 4.240784 -1.970024)
			(stroke
				(width 0.1524)
				(type default)
			)
			(layer "F.SilkS")
		)
		(fp_line
			(start -3.656584 -1.970024)
			(end -3.656584 1.970024)
			(stroke
				(width 0.1524)
				(type default)
			)
			(layer "F.SilkS")
		)
		(fp_line
			(start 4.240784 -1.970024)
			(end -3.656584 -1.970024)
			(stroke
				(width 0.1524)
				(type default)
			)
			(layer "F.SilkS")
		)
		(fp_poly
			(pts
				(xy 3.580384 1.970024) (xy 3.580384 -1.970024) (xy 4.240784 -1.970024) (xy 4.240784 1.970024)
			)
			(stroke
				(width 0)
				(type default)
			)
			(fill yes)
			(layer "F.SilkS")
		)
		(fp_line
			(start -2.3749 1.970024)
			(end 2.3749 1.970024)
			(stroke
				(width 0.1)
				(type default)
			)
			(layer "F.Fab")
		)
		(fp_line
			(start 2.3749 1.970024)
			(end 2.3749 -1.970024)
			(stroke
				(width 0.1)
				(type default)
			)
			(layer "F.Fab")
		)
		(fp_line
			(start -2.3749 -1.970024)
			(end -2.3749 1.970024)
			(stroke
				(width 0.1)
				(type default)
			)
			(layer "F.Fab")
		)
		(fp_line
			(start 2.3749 -1.970024)
			(end -2.3749 -1.970024)
			(stroke
				(width 0.1)
				(type default)
			)
			(layer "F.Fab")
		)
		(fp_text user "+"
			(at -4.9784 -0.23495 270)
			(unlocked yes)
			(layer "F.Fab")
			(effects
				(font
					(size 1.905 1.4224)
					(thickness 0.1524)
				)
				(justify left)
			)
		)
		(fp_text user "-"
			(at 4.1656 -0.23495 270)
			(unlocked yes)
			(layer "F.Fab")
			(effects
				(font
					(size 1.905 1.4224)
					(thickness 0.1524)
				)
				(justify left)
			)
		)
		(pad "A" smd rect
			(at -2.450084 0 270)
			(size 2.159 2.2606)
			(layers "F.Cu" "F.Mask" "F.Paste")
			(net "GND")
		)
		(pad "C" smd rect
			(at 2.450084 0 270)
			(size 2.159 2.2606)
			(layers "F.Cu" "F.Mask" "F.Paste")
			(net "P12V_BRICK")
		)
	)
	(footprint ""
		(layer "F.Cu")
		(at 264.808716 -34.357818 180)
		(property "Reference" "PC551"
			(at 0 0 180)
			(layer "F.SilkS")
			(hide yes)
			(effects
				(font
					(size 1.27 1.27)
				)
			)
		)
		(property "Value" ""
			(at 0 0 180)
			(layer "F.Fab")
			(effects
				(font
					(size 1.27 1.27)
				)
			)
		)
		(duplicate_pad_numbers_are_jumpers no)
		(fp_line
			(start 0.7874 0.4064)
			(end -0.7874 0.4064)
			(stroke
				(width 0.1524)
				(type default)
			)
			(layer "F.SilkS")
		)
		(fp_line
			(start 0.7874 -0.4064)
			(end 0.7874 0.4064)
			(stroke
				(width 0.1524)
				(type default)
			)
			(layer "F.SilkS")
		)
		(fp_line
			(start -0.7874 0.4064)
			(end -0.7874 -0.4064)
			(stroke
				(width 0.1524)
				(type default)
			)
			(layer "F.SilkS")
		)
		(fp_line
			(start -0.7874 -0.4064)
			(end 0.7874 -0.4064)
			(stroke
				(width 0.1524)
				(type default)
			)
			(layer "F.SilkS")
		)
		(fp_line
			(start 0.67945 0.3048)
			(end 0.120396 0.3048)
			(stroke
				(width 0.1)
				(type default)
			)
			(layer "F.Fab")
		)
		(fp_line
			(start 0.67945 -0.3048)
			(end 0.67945 0.3048)
			(stroke
				(width 0.1)
				(type default)
			)
			(layer "F.Fab")
		)
		(fp_line
			(start 0.12065 -0.2794)
			(end 0.12065 -0.3048)
			(stroke
				(width 0.1)
				(type default)
			)
			(layer "F.Fab")
		)
		(fp_line
			(start 0.12065 -0.3048)
			(end 0.67945 -0.3048)
			(stroke
				(width 0.1)
				(type default)
			)
			(layer "F.Fab")
		)
		(fp_line
			(start 0.120396 0.3048)
			(end 0.120396 0.2794)
			(stroke
				(width 0.1)
				(type default)
			)
			(layer "F.Fab")
		)
		(fp_line
			(start 0.120396 0.2794)
			(end -0.12065 0.2794)
			(stroke
				(width 0.1)
				(type default)
			)
			(layer "F.Fab")
		)
		(fp_line
			(start -0.12065 0.3048)
			(end -0.67945 0.3048)
			(stroke
				(width 0.1)
				(type default)
			)
			(layer "F.Fab")
		)
		(fp_line
			(start -0.12065 0.2794)
			(end -0.12065 0.3048)
			(stroke
				(width 0.1)
				(type default)
			)
			(layer "F.Fab")
		)
		(fp_line
			(start -0.12065 -0.2794)
			(end 0.12065 -0.2794)
			(stroke
				(width 0.1)
				(type default)
			)
			(layer "F.Fab")
		)
		(fp_line
			(start -0.12065 -0.305054)
			(end -0.12065 -0.2794)
			(stroke
				(width 0.1)
				(type default)
			)
			(layer "F.Fab")
		)
		(fp_line
			(start -0.67945 0.3048)
			(end -0.67945 -0.305054)
			(stroke
				(width 0.1)
				(type default)
			)
			(layer "F.Fab")
		)
		(fp_line
			(start -0.67945 -0.305054)
			(end -0.12065 -0.305054)
			(stroke
				(width 0.1)
				(type default)
			)
			(layer "F.Fab")
		)
		(pad "1" smd circle
			(at -0.40005 0 180)
			(size 0 0)
			(layers "F.Cu" "F.Mask" "F.Paste")
			(net "HS1_TMR1")
		)
		(pad "2" smd circle
			(at 0.40005 0 180)
			(size 0 0)
			(layers "F.Cu" "F.Mask" "F.Paste")
			(net "GND_FIELD_SIGNAL")
		)
	)
	(footprint ""
		(layer "F.Cu")
		(at 280.543 -35.687 -90)
		(property "Reference" "PR35"
			(at 0 0 270)
			(layer "F.SilkS")
			(hide yes)
			(effects
				(font
					(size 1.27 1.27)
				)
			)
		)
		(property "Value" ""
			(at 0 0 270)
			(layer "F.Fab")
			(effects
				(font
					(size 1.27 1.27)
				)
			)
		)
		(duplicate_pad_numbers_are_jumpers no)
		(fp_line
			(start -0.7874 0.4064)
			(end -0.7874 -0.4064)
			(stroke
				(width 0.1524)
				(type default)
			)
			(layer "F.SilkS")
		)
		(fp_line
			(start 0.7874 0.4064)
			(end -0.7874 0.4064)
			(stroke
				(width 0.1524)
				(type default)
			)
			(layer "F.SilkS")
		)
		(fp_line
			(start -0.7874 -0.4064)
			(end 0.7874 -0.4064)
			(stroke
				(width 0.1524)
				(type default)
			)
			(layer "F.SilkS")
		)
		(fp_line
			(start 0.7874 -0.4064)
			(end 0.7874 0.4064)
			(stroke
				(width 0.1524)
				(type default)
			)
			(layer "F.SilkS")
		)
		(fp_line
			(start -0.67945 0.3048)
			(end -0.67945 -0.305054)
			(stroke
				(width 0.1)
				(type default)
			)
			(layer "F.Fab")
		)
		(fp_line
			(start -0.12065 0.3048)
			(end -0.67945 0.3048)
			(stroke
				(width 0.1)
				(type default)
			)
			(layer "F.Fab")
		)
		(fp_line
			(start 0.120396 0.3048)
			(end 0.120396 0.2794)
			(stroke
				(width 0.1)
				(type default)
			)
			(layer "F.Fab")
		)
		(fp_line
			(start 0.67945 0.3048)
			(end 0.120396 0.3048)
			(stroke
				(width 0.1)
				(type default)
			)
			(layer "F.Fab")
		)
		(fp_line
			(start -0.12065 0.2794)
			(end -0.12065 0.3048)
			(stroke
				(width 0.1)
				(type default)
			)
			(layer "F.Fab")
		)
		(fp_line
			(start 0.120396 0.2794)
			(end -0.12065 0.2794)
			(stroke
				(width 0.1)
				(type default)
			)
			(layer "F.Fab")
		)
		(fp_line
			(start -0.12065 -0.2794)
			(end 0.12065 -0.2794)
			(stroke
				(width 0.1)
				(type default)
			)
			(layer "F.Fab")
		)
		(fp_line
			(start 0.12065 -0.2794)
			(end 0.12065 -0.3048)
			(stroke
				(width 0.1)
				(type default)
			)
			(layer "F.Fab")
		)
		(fp_line
			(start 0.12065 -0.3048)
			(end 0.67945 -0.3048)
			(stroke
				(width 0.1)
				(type default)
			)
			(layer "F.Fab")
		)
		(fp_line
			(start 0.67945 -0.3048)
			(end 0.67945 0.3048)
			(stroke
				(width 0.1)
				(type default)
			)
			(layer "F.Fab")
		)
		(fp_line
			(start -0.67945 -0.305054)
			(end -0.12065 -0.305054)
			(stroke
				(width 0.1)
				(type default)
			)
			(layer "F.Fab")
		)
		(fp_line
			(start -0.12065 -0.305054)
			(end -0.12065 -0.2794)
			(stroke
				(width 0.1)
				(type default)
			)
			(layer "F.Fab")
		)
		(pad "1" smd circle
			(at -0.40005 0 270)
			(size 0 0)
			(layers "F.Cu" "F.Mask" "F.Paste")
			(net "P52V_HS1_MCB")
		)
		(pad "2" smd circle
			(at 0.40005 0 270)
			(size 0 0)
			(layers "F.Cu" "F.Mask" "F.Paste")
			(net "GND_FIELD_SIGNAL")
		)
	)
	(footprint ""
		(layer "F.Cu")
		(at 282.760674 -58.862214 180)
		(property "Reference" "PR6967"
			(at 0 0 180)
			(layer "F.SilkS")
			(hide yes)
			(effects
				(font
					(size 1.27 1.27)
				)
			)
		)
		(property "Value" ""
			(at 0 0 180)
			(layer "F.Fab")
			(effects
				(font
					(size 1.27 1.27)
				)
			)
		)
		(duplicate_pad_numbers_are_jumpers no)
		(fp_line
			(start 0.7874 0.4064)
			(end -0.7874 0.4064)
			(stroke
				(width 0.1524)
				(type default)
			)
			(layer "F.SilkS")
		)
		(fp_line
			(start 0.7874 -0.4064)
			(end 0.7874 0.4064)
			(stroke
				(width 0.1524)
				(type default)
			)
			(layer "F.SilkS")
		)
		(fp_line
			(start -0.7874 0.4064)
			(end -0.7874 -0.4064)
			(stroke
				(width 0.1524)
				(type default)
			)
			(layer "F.SilkS")
		)
		(fp_line
			(start -0.7874 -0.4064)
			(end 0.7874 -0.4064)
			(stroke
				(width 0.1524)
				(type default)
			)
			(layer "F.SilkS")
		)
		(fp_line
			(start 0.67945 0.3048)
			(end 0.120396 0.3048)
			(stroke
				(width 0.1)
				(type default)
			)
			(layer "F.Fab")
		)
		(fp_line
			(start 0.67945 -0.3048)
			(end 0.67945 0.3048)
			(stroke
				(width 0.1)
				(type default)
			)
			(layer "F.Fab")
		)
		(fp_line
			(start 0.12065 -0.2794)
			(end 0.12065 -0.3048)
			(stroke
				(width 0.1)
				(type default)
			)
			(layer "F.Fab")
		)
		(fp_line
			(start 0.12065 -0.3048)
			(end 0.67945 -0.3048)
			(stroke
				(width 0.1)
				(type default)
			)
			(layer "F.Fab")
		)
		(fp_line
			(start 0.120396 0.3048)
			(end 0.120396 0.2794)
			(stroke
				(width 0.1)
				(type default)
			)
			(layer "F.Fab")
		)
		(fp_line
			(start 0.120396 0.2794)
			(end -0.12065 0.2794)
			(stroke
				(width 0.1)
				(type default)
			)
			(layer "F.Fab")
		)
		(fp_line
			(start -0.12065 0.3048)
			(end -0.67945 0.3048)
			(stroke
				(width 0.1)
				(type default)
			)
			(layer "F.Fab")
		)
		(fp_line
			(start -0.12065 0.2794)
			(end -0.12065 0.3048)
			(stroke
				(width 0.1)
				(type default)
			)
			(layer "F.Fab")
		)
		(fp_line
			(start -0.12065 -0.2794)
			(end 0.12065 -0.2794)
			(stroke
				(width 0.1)
				(type default)
			)
			(layer "F.Fab")
		)
		(fp_line
			(start -0.12065 -0.305054)
			(end -0.12065 -0.2794)
			(stroke
				(width 0.1)
				(type default)
			)
			(layer "F.Fab")
		)
		(fp_line
			(start -0.67945 0.3048)
			(end -0.67945 -0.305054)
			(stroke
				(width 0.1)
				(type default)
			)
			(layer "F.Fab")
		)
		(fp_line
			(start -0.67945 -0.305054)
			(end -0.12065 -0.305054)
			(stroke
				(width 0.1)
				(type default)
			)
			(layer "F.Fab")
		)
		(pad "1" smd rect
			(at -0.40005 0)
			(size 0.4572 0.508)
			(layers "F.Cu" "F.Mask" "F.Paste")
			(net "P52V_HS1_TEMPP")
		)
		(pad "2" smd rect
			(at 0.40005 0)
			(size 0.4572 0.508)
			(layers "F.Cu" "F.Mask" "F.Paste")
			(net "P52V_HS1_TEMP_R")
		)
	)
	(footprint ""
		(layer "F.Cu")
		(at 185.293 -12.954)
		(property "Reference" "PL2"
			(at -3.81 -4.16433 0)
			(unlocked yes)
			(layer "F.SilkS")
			(effects
				(font
					(size 0.7874 0.5842)
					(thickness 0.1524)
				)
				(justify left)
			)
		)
		(property "Value" ""
			(at 0 0 0)
			(layer "F.Fab")
			(effects
				(font
					(size 1.27 1.27)
				)
			)
		)
		(duplicate_pad_numbers_are_jumpers no)
		(fp_line
			(start -3.6576 -3.350006)
			(end 3.64998 -3.350006)
			(stroke
				(width 0.1524)
				(type default)
			)
			(layer "F.SilkS")
		)
		(fp_line
			(start -3.64998 -1.8034)
			(end -3.64998 -3.350006)
			(stroke
				(width 0.1524)
				(type default)
			)
			(layer "F.SilkS")
		)
		(fp_line
			(start -3.64998 3.350006)
			(end -3.64998 1.8288)
			(stroke
				(width 0.1524)
				(type default)
			)
			(layer "F.SilkS")
		)
		(fp_line
			(start 3.64998 -3.350006)
			(end 3.64998 -1.8034)
			(stroke
				(width 0.1524)
				(type default)
			)
			(layer "F.SilkS")
		)
		(fp_line
			(start 3.64998 1.8034)
			(end 3.64998 3.350006)
			(stroke
				(width 0.1524)
				(type default)
			)
			(layer "F.SilkS")
		)
		(fp_line
			(start 3.64998 3.350006)
			(end -3.64998 3.350006)
			(stroke
				(width 0.1524)
				(type default)
			)
			(layer "F.SilkS")
		)
		(fp_line
			(start -3.64998 -3.350006)
			(end 3.64998 -3.350006)
			(stroke
				(width 0.1)
				(type default)
			)
			(layer "F.Fab")
		)
		(fp_line
			(start -3.64998 3.350006)
			(end -3.64998 -3.350006)
			(stroke
				(width 0.1)
				(type default)
			)
			(layer "F.Fab")
		)
		(fp_line
			(start 3.64998 -3.350006)
			(end 3.64998 3.350006)
			(stroke
				(width 0.1)
				(type default)
			)
			(layer "F.Fab")
		)
		(fp_line
			(start 3.64998 3.350006)
			(end -3.64998 3.350006)
			(stroke
				(width 0.1)
				(type default)
			)
			(layer "F.Fab")
		)
		(pad "1" smd rect
			(at -2.92481 0)
			(size 2.15392 3.302)
			(layers "F.Cu" "F.Mask" "F.Paste")
			(net "SW_P3V3_AUX_PH")
		)
		(pad "2" smd rect
			(at 2.92481 0)
			(size 2.15392 3.302)
			(layers "F.Cu" "F.Mask" "F.Paste")
			(net "P3V3_AUX")
		)
	)
	(footprint ""
		(layer "F.Cu")
		(at 191.643 -15.24)
		(property "Reference" "PC108"
			(at 0 0 0)
			(layer "F.SilkS")
			(hide yes)
			(effects
				(font
					(size 1.27 1.27)
				)
			)
		)
		(property "Value" ""
			(at 0 0 0)
			(layer "F.Fab")
			(effects
				(font
					(size 1.27 1.27)
				)
			)
		)
		(duplicate_pad_numbers_are_jumpers no)
		(fp_line
			(start -1.524 -0.762)
			(end 1.524 -0.762)
			(stroke
				(width 0.1524)
				(type default)
			)
			(layer "F.SilkS")
		)
		(fp_line
			(start -1.524 0.762)
			(end -1.524 -0.762)
			(stroke
				(width 0.1524)
				(type default)
			)
			(layer "F.SilkS")
		)
		(fp_line
			(start 1.524 -0.762)
			(end 1.524 0.762)
			(stroke
				(width 0.1524)
				(type default)
			)
			(layer "F.SilkS")
		)
		(fp_line
			(start 1.524 0.762)
			(end -1.524 0.762)
			(stroke
				(width 0.1524)
				(type default)
			)
			(layer "F.SilkS")
		)
		(fp_line
			(start -1.1049 -0.724916)
			(end -1.1049 0.724916)
			(stroke
				(width 0.1)
				(type default)
			)
			(layer "F.Fab")
		)
		(fp_line
			(start -1.1049 0.724916)
			(end 1.1049 0.724916)
			(stroke
				(width 0.1)
				(type default)
			)
			(layer "F.Fab")
		)
		(fp_line
			(start 1.1049 -0.724916)
			(end -1.1049 -0.724916)
			(stroke
				(width 0.1)
				(type default)
			)
			(layer "F.Fab")
		)
		(fp_line
			(start 1.1049 0.724916)
			(end 1.1049 -0.724916)
			(stroke
				(width 0.1)
				(type default)
			)
			(layer "F.Fab")
		)
		(pad "1" smd rect
			(at -0.889 0 180)
			(size 1.016 1.27)
			(layers "F.Cu" "F.Mask" "F.Paste")
			(net "P3V3_AUX")
		)
		(pad "2" smd rect
			(at 0.889 0 180)
			(size 1.016 1.27)
			(layers "F.Cu" "F.Mask" "F.Paste")
			(net "GND")
		)
	)
	(footprint ""
		(layer "F.Cu")
		(at 260.236716 -50.613818)
		(property "Reference" "PR23"
			(at 0 0 0)
			(layer "F.SilkS")
			(hide yes)
			(effects
				(font
					(size 1.27 1.27)
				)
			)
		)
		(property "Value" ""
			(at 0 0 0)
			(layer "F.Fab")
			(effects
				(font
					(size 1.27 1.27)
				)
			)
		)
		(duplicate_pad_numbers_are_jumpers no)
		(fp_line
			(start -1.651 -0.8382)
			(end 1.651 -0.8382)
			(stroke
				(width 0.1524)
				(type default)
			)
			(layer "F.SilkS")
		)
		(fp_line
			(start -1.651 0.8382)
			(end -1.651 -0.8382)
			(stroke
				(width 0.1524)
				(type default)
			)
			(layer "F.SilkS")
		)
		(fp_line
			(start 1.651 -0.8382)
			(end 1.651 0.8382)
			(stroke
				(width 0.1524)
				(type default)
			)
			(layer "F.SilkS")
		)
		(fp_line
			(start 1.651 0.8382)
			(end -1.651 0.8382)
			(stroke
				(width 0.1524)
				(type default)
			)
			(layer "F.SilkS")
		)
		(fp_line
			(start -1.559814 -0.7366)
			(end -1.559814 0.7366)
			(stroke
				(width 0.1)
				(type default)
			)
			(layer "F.Fab")
		)
		(fp_line
			(start -1.559814 0.7366)
			(end -1.524 0.7366)
			(stroke
				(width 0.1)
				(type default)
			)
			(layer "F.Fab")
		)
		(fp_line
			(start -1.524 -0.7366)
			(end -1.559814 -0.7366)
			(stroke
				(width 0.1)
				(type default)
			)
			(layer "F.Fab")
		)
		(fp_line
			(start -1.524 0.7366)
			(end 1.524 0.7366)
			(stroke
				(width 0.1)
				(type default)
			)
			(layer "F.Fab")
		)
		(fp_line
			(start 1.524 -0.7366)
			(end -1.524 -0.7366)
			(stroke
				(width 0.1)
				(type default)
			)
			(layer "F.Fab")
		)
		(fp_line
			(start 1.524 0.7366)
			(end 1.560576 0.7366)
			(stroke
				(width 0.1)
				(type default)
			)
			(layer "F.Fab")
		)
		(fp_line
			(start 1.560576 -0.7366)
			(end 1.524 -0.7366)
			(stroke
				(width 0.1)
				(type default)
			)
			(layer "F.Fab")
		)
		(fp_line
			(start 1.560576 0.7366)
			(end 1.560576 -0.7366)
			(stroke
				(width 0.1)
				(type default)
			)
			(layer "F.Fab")
		)
		(pad "1" smd rect
			(at -0.94996 0 180)
			(size 1.1176 1.3716)
			(layers "F.Cu" "F.Mask" "F.Paste")
			(net "P52V_HS")
		)
		(pad "2" smd rect
			(at 0.94996 0 180)
			(size 1.1176 1.3716)
			(layers "F.Cu" "F.Mask" "F.Paste")
			(net "P52V_HS1_FB")
		)
	)
	(footprint ""
		(layer "F.Cu")
		(at 280.39568 -102.347268)
		(property "Reference" "PQ3"
			(at -7.723886 -5.895848 0)
			(unlocked yes)
			(layer "F.SilkS")
			(effects
				(font
					(size 0.7874 0.5842)
					(thickness 0.1524)
				)
				(justify left)
			)
		)
		(property "Value" ""
			(at 0 0 0)
			(layer "F.Fab")
			(effects
				(font
					(size 1.27 1.27)
				)
			)
		)
		(duplicate_pad_numbers_are_jumpers no)
		(fp_line
			(start -7.649972 -4.99999)
			(end -7.649972 -3.3274)
			(stroke
				(width 0.1524)
				(type default)
			)
			(layer "F.SilkS")
		)
		(fp_line
			(start -7.649972 -1.7526)
			(end -7.649972 1.7526)
			(stroke
				(width 0.1524)
				(type default)
			)
			(layer "F.SilkS")
		)
		(fp_line
			(start -7.649972 3.3274)
			(end -7.649972 4.99999)
			(stroke
				(width 0.1524)
				(type default)
			)
			(layer "F.SilkS")
		)
		(fp_line
			(start -7.649972 4.99999)
			(end 5.115814 4.99999)
			(stroke
				(width 0.1524)
				(type default)
			)
			(layer "F.SilkS")
		)
		(fp_line
			(start 5.115814 -4.99999)
			(end -7.649972 -4.99999)
			(stroke
				(width 0.1524)
				(type default)
			)
			(layer "F.SilkS")
		)
		(fp_line
			(start 7.630414 4.99999)
			(end 7.649972 4.99999)
			(stroke
				(width 0.1524)
				(type default)
			)
			(layer "F.SilkS")
		)
		(fp_line
			(start 7.649972 -4.99999)
			(end 7.630414 -4.99999)
			(stroke
				(width 0.1524)
				(type default)
			)
			(layer "F.SilkS")
		)
		(fp_line
			(start 7.649972 4.99999)
			(end 7.649972 -4.99999)
			(stroke
				(width 0.1524)
				(type default)
			)
			(layer "F.SilkS")
		)
		(fp_line
			(start -7.649972 -4.99999)
			(end -7.649972 4.99999)
			(stroke
				(width 0.1)
				(type default)
			)
			(layer "F.Fab")
		)
		(fp_line
			(start -7.649972 4.99999)
			(end 7.649972 4.99999)
			(stroke
				(width 0.1)
				(type default)
			)
			(layer "F.Fab")
		)
		(fp_line
			(start 7.649972 -4.99999)
			(end -7.649972 -4.99999)
			(stroke
				(width 0.1)
				(type default)
			)
			(layer "F.Fab")
		)
		(fp_line
			(start 7.649972 4.99999)
			(end 7.649972 -4.99999)
			(stroke
				(width 0.1)
				(type default)
			)
			(layer "F.Fab")
		)
		(pad "D" smd circle
			(at 2.15011 0)
			(size 0 0)
			(layers "F.Cu" "F.Mask" "F.Paste")
			(net "P52V_HS1_DRAIN_1")
		)
		(pad "G" smd rect
			(at -7.050024 -2.54 270)
			(size 1.3208 3.0988)
			(layers "F.Cu" "F.Mask" "F.Paste")
			(net "P52V_HS1_GATE3")
		)
		(pad "S" smd rect
			(at -7.050024 2.54 270)
			(size 1.3208 3.0988)
			(layers "F.Cu" "F.Mask" "F.Paste")
			(net "P52V_HS")
		)
		(zone
			(layer "F.Cu")
			(hatch none 0.5)
			(connect_pads
				(clearance 0)
			)
			(min_thickness 0.25)
			(keepout
				(tracks not_allowed)
				(vias allowed)
				(pads allowed)
				(copperpour not_allowed)
				(footprints allowed)
			)
			(placement
				(enabled no)
				(sheetname "")
			)
			(fill
				(thermal_gap 0.5)
				(thermal_bridge_width 0.5)
				(island_removal_mode 0)
			)
			(polygon
				(pts
					(xy 285.57728 -107.325668) (xy 272.75028 -107.325668) (xy 272.75028 -105.598468) (xy 274.96008 -105.598468)
					(xy 274.96008 -104.176068) (xy 272.75028 -104.176068) (xy 272.75028 -100.518468) (xy 274.96008 -100.518468)
					(xy 274.96008 -99.096068) (xy 272.75028 -99.096068) (xy 272.75028 -97.368868) (xy 285.57728 -97.368868)
					(xy 285.57728 -98.537268) (xy 279.37968 -98.537268) (xy 279.37968 -106.157268) (xy 285.57728 -106.157268)
				)
			)
		)
	)
	(footprint ""
		(layer "F.Cu")
		(at 260.35 -34.798 -90)
		(property "Reference" "PC3"
			(at 0 0 270)
			(layer "F.SilkS")
			(hide yes)
			(effects
				(font
					(size 1.27 1.27)
				)
			)
		)
		(property "Value" ""
			(at 0 0 270)
			(layer "F.Fab")
			(effects
				(font
					(size 1.27 1.27)
				)
			)
		)
		(duplicate_pad_numbers_are_jumpers no)
		(fp_line
			(start -2.2098 0.9398)
			(end -2.2098 -0.9398)
			(stroke
				(width 0.1524)
				(type default)
			)
			(layer "F.SilkS")
		)
		(fp_line
			(start 2.2098 0.9398)
			(end -2.2098 0.9398)
			(stroke
				(width 0.1524)
				(type default)
			)
			(layer "F.SilkS")
		)
		(fp_line
			(start -2.2098 -0.9398)
			(end 2.2098 -0.9398)
			(stroke
				(width 0.1524)
				(type default)
			)
			(layer "F.SilkS")
		)
		(fp_line
			(start 2.2098 -0.9398)
			(end 2.2098 0.9398)
			(stroke
				(width 0.1524)
				(type default)
			)
			(layer "F.SilkS")
		)
		(fp_line
			(start -1.6764 0.9398)
			(end -1.6764 0.889)
			(stroke
				(width 0.1)
				(type default)
			)
			(layer "F.Fab")
		)
		(fp_line
			(start 1.6764 0.9398)
			(end -1.6764 0.9398)
			(stroke
				(width 0.1)
				(type default)
			)
			(layer "F.Fab")
		)
		(fp_line
			(start -1.6764 0.889)
			(end -1.6764 0.8382)
			(stroke
				(width 0.1)
				(type default)
			)
			(layer "F.Fab")
		)
		(fp_line
			(start 1.6764 0.889)
			(end 1.6764 0.9398)
			(stroke
				(width 0.1)
				(type default)
			)
			(layer "F.Fab")
		)
		(fp_line
			(start -2.1082 0.8382)
			(end -2.1082 -0.8382)
			(stroke
				(width 0.1)
				(type default)
			)
			(layer "F.Fab")
		)
		(fp_line
			(start -1.6764 0.8382)
			(end -2.1082 0.8382)
			(stroke
				(width 0.1)
				(type default)
			)
			(layer "F.Fab")
		)
		(fp_line
			(start 1.6764 0.8382)
			(end 1.6764 0.889)
			(stroke
				(width 0.1)
				(type default)
			)
			(layer "F.Fab")
		)
		(fp_line
			(start 2.1082 0.8382)
			(end 1.6764 0.8382)
			(stroke
				(width 0.1)
				(type default)
			)
			(layer "F.Fab")
		)
		(fp_line
			(start -2.1082 -0.8382)
			(end -1.6764 -0.8382)
			(stroke
				(width 0.1)
				(type default)
			)
			(layer "F.Fab")
		)
		(fp_line
			(start -1.6764 -0.8382)
			(end -1.6764 -0.889)
			(stroke
				(width 0.1)
				(type default)
			)
			(layer "F.Fab")
		)
		(fp_line
			(start 1.6764 -0.8382)
			(end 2.1082 -0.8382)
			(stroke
				(width 0.1)
				(type default)
			)
			(layer "F.Fab")
		)
		(fp_line
			(start 2.1082 -0.8382)
			(end 2.1082 0.8382)
			(stroke
				(width 0.1)
				(type default)
			)
			(layer "F.Fab")
		)
		(fp_line
			(start -1.6764 -0.889)
			(end -1.6764 -0.9398)
			(stroke
				(width 0.1)
				(type default)
			)
			(layer "F.Fab")
		)
		(fp_line
			(start 1.6764 -0.889)
			(end 1.6764 -0.8382)
			(stroke
				(width 0.1)
				(type default)
			)
			(layer "F.Fab")
		)
		(fp_line
			(start -1.6764 -0.9398)
			(end 1.6764 -0.9398)
			(stroke
				(width 0.1)
				(type default)
			)
			(layer "F.Fab")
		)
		(fp_line
			(start 1.6764 -0.9398)
			(end 1.6764 -0.889)
			(stroke
				(width 0.1)
				(type default)
			)
			(layer "F.Fab")
		)
		(pad "1" smd rect
			(at -1.4732 0 90)
			(size 1.1684 1.5748)
			(layers "F.Cu" "F.Mask" "F.Paste")
			(net "P52V_1_R")
		)
		(pad "2" smd rect
			(at 1.4732 0 90)
			(size 1.1684 1.5748)
			(layers "F.Cu" "F.Mask" "F.Paste")
			(net "GND_FIELD_SIGNAL")
		)
	)
	(footprint ""
		(layer "F.Cu")
		(at 90.043 -51.943)
		(property "Reference" "PC88"
			(at 0 0 0)
			(layer "F.SilkS")
			(hide yes)
			(effects
				(font
					(size 1.27 1.27)
				)
			)
		)
		(property "Value" ""
			(at 0 0 0)
			(layer "F.Fab")
			(effects
				(font
					(size 1.27 1.27)
				)
			)
		)
		(duplicate_pad_numbers_are_jumpers no)
		(fp_line
			(start -1.524 -0.762)
			(end 1.524 -0.762)
			(stroke
				(width 0.1524)
				(type default)
			)
			(layer "F.SilkS")
		)
		(fp_line
			(start -1.524 0.762)
			(end -1.524 -0.762)
			(stroke
				(width 0.1524)
				(type default)
			)
			(layer "F.SilkS")
		)
		(fp_line
			(start 1.524 -0.762)
			(end 1.524 0.762)
			(stroke
				(width 0.1524)
				(type default)
			)
			(layer "F.SilkS")
		)
		(fp_line
			(start 1.524 0.762)
			(end -1.524 0.762)
			(stroke
				(width 0.1524)
				(type default)
			)
			(layer "F.SilkS")
		)
		(fp_line
			(start -1.1049 -0.724916)
			(end -1.1049 0.724916)
			(stroke
				(width 0.1)
				(type default)
			)
			(layer "F.Fab")
		)
		(fp_line
			(start -1.1049 0.724916)
			(end 1.1049 0.724916)
			(stroke
				(width 0.1)
				(type default)
			)
			(layer "F.Fab")
		)
		(fp_line
			(start 1.1049 -0.724916)
			(end -1.1049 -0.724916)
			(stroke
				(width 0.1)
				(type default)
			)
			(layer "F.Fab")
		)
		(fp_line
			(start 1.1049 0.724916)
			(end 1.1049 -0.724916)
			(stroke
				(width 0.1)
				(type default)
			)
			(layer "F.Fab")
		)
		(pad "1" smd rect
			(at -0.889 0 180)
			(size 1.016 1.27)
			(layers "F.Cu" "F.Mask" "F.Paste")
			(net "P12V_BRICK")
		)
		(pad "2" smd rect
			(at 0.889 0 180)
			(size 1.016 1.27)
			(layers "F.Cu" "F.Mask" "F.Paste")
			(net "GND")
		)
	)
	(footprint ""
		(layer "F.Cu")
		(at 282.956 -49.276 90)
		(property "Reference" "PC1"
			(at 0 0 90)
			(layer "F.SilkS")
			(hide yes)
			(effects
				(font
					(size 1.27 1.27)
				)
			)
		)
		(property "Value" ""
			(at 0 0 90)
			(layer "F.Fab")
			(effects
				(font
					(size 1.27 1.27)
				)
			)
		)
		(duplicate_pad_numbers_are_jumpers no)
		(fp_line
			(start 0.7874 -0.4064)
			(end 0.7874 0.4064)
			(stroke
				(width 0.1524)
				(type default)
			)
			(layer "F.SilkS")
		)
		(fp_line
			(start -0.7874 -0.4064)
			(end 0.7874 -0.4064)
			(stroke
				(width 0.1524)
				(type default)
			)
			(layer "F.SilkS")
		)
		(fp_line
			(start 0.7874 0.4064)
			(end -0.7874 0.4064)
			(stroke
				(width 0.1524)
				(type default)
			)
			(layer "F.SilkS")
		)
		(fp_line
			(start -0.7874 0.4064)
			(end -0.7874 -0.4064)
			(stroke
				(width 0.1524)
				(type default)
			)
			(layer "F.SilkS")
		)
		(fp_line
			(start -0.12065 -0.305054)
			(end -0.12065 -0.2794)
			(stroke
				(width 0.1)
				(type default)
			)
			(layer "F.Fab")
		)
		(fp_line
			(start -0.67945 -0.305054)
			(end -0.12065 -0.305054)
			(stroke
				(width 0.1)
				(type default)
			)
			(layer "F.Fab")
		)
		(fp_line
			(start 0.67945 -0.3048)
			(end 0.67945 0.3048)
			(stroke
				(width 0.1)
				(type default)
			)
			(layer "F.Fab")
		)
		(fp_line
			(start 0.12065 -0.3048)
			(end 0.67945 -0.3048)
			(stroke
				(width 0.1)
				(type default)
			)
			(layer "F.Fab")
		)
		(fp_line
			(start 0.12065 -0.2794)
			(end 0.12065 -0.3048)
			(stroke
				(width 0.1)
				(type default)
			)
			(layer "F.Fab")
		)
		(fp_line
			(start -0.12065 -0.2794)
			(end 0.12065 -0.2794)
			(stroke
				(width 0.1)
				(type default)
			)
			(layer "F.Fab")
		)
		(fp_line
			(start 0.120396 0.2794)
			(end -0.12065 0.2794)
			(stroke
				(width 0.1)
				(type default)
			)
			(layer "F.Fab")
		)
		(fp_line
			(start -0.12065 0.2794)
			(end -0.12065 0.3048)
			(stroke
				(width 0.1)
				(type default)
			)
			(layer "F.Fab")
		)
		(fp_line
			(start 0.67945 0.3048)
			(end 0.120396 0.3048)
			(stroke
				(width 0.1)
				(type default)
			)
			(layer "F.Fab")
		)
		(fp_line
			(start 0.120396 0.3048)
			(end 0.120396 0.2794)
			(stroke
				(width 0.1)
				(type default)
			)
			(layer "F.Fab")
		)
		(fp_line
			(start -0.12065 0.3048)
			(end -0.67945 0.3048)
			(stroke
				(width 0.1)
				(type default)
			)
			(layer "F.Fab")
		)
		(fp_line
			(start -0.67945 0.3048)
			(end -0.67945 -0.305054)
			(stroke
				(width 0.1)
				(type default)
			)
			(layer "F.Fab")
		)
		(pad "1" smd circle
			(at -0.40005 0 90)
			(size 0 0)
			(layers "F.Cu" "F.Mask" "F.Paste")
			(net "P52V_HS1_OV")
		)
		(pad "2" smd circle
			(at 0.40005 0 90)
			(size 0 0)
			(layers "F.Cu" "F.Mask" "F.Paste")
			(net "GND_FIELD_SIGNAL")
		)
	)
	(footprint ""
		(layer "F.Cu")
		(at 279.010872 -40.744902)
		(property "Reference" "R81"
			(at 0 0 0)
			(layer "F.SilkS")
			(hide yes)
			(effects
				(font
					(size 1.27 1.27)
				)
			)
		)
		(property "Value" ""
			(at 0 0 0)
			(layer "F.Fab")
			(effects
				(font
					(size 1.27 1.27)
				)
			)
		)
		(duplicate_pad_numbers_are_jumpers no)
		(fp_line
			(start -0.7874 -0.4064)
			(end 0.7874 -0.4064)
			(stroke
				(width 0.1524)
				(type default)
			)
			(layer "F.SilkS")
		)
		(fp_line
			(start -0.7874 0.4064)
			(end -0.7874 -0.4064)
			(stroke
				(width 0.1524)
				(type default)
			)
			(layer "F.SilkS")
		)
		(fp_line
			(start 0.7874 -0.4064)
			(end 0.7874 0.4064)
			(stroke
				(width 0.1524)
				(type default)
			)
			(layer "F.SilkS")
		)
		(fp_line
			(start 0.7874 0.4064)
			(end -0.7874 0.4064)
			(stroke
				(width 0.1524)
				(type default)
			)
			(layer "F.SilkS")
		)
		(fp_line
			(start -0.67945 -0.305054)
			(end -0.12065 -0.305054)
			(stroke
				(width 0.1)
				(type default)
			)
			(layer "F.Fab")
		)
		(fp_line
			(start -0.67945 0.3048)
			(end -0.67945 -0.305054)
			(stroke
				(width 0.1)
				(type default)
			)
			(layer "F.Fab")
		)
		(fp_line
			(start -0.12065 -0.305054)
			(end -0.12065 -0.2794)
			(stroke
				(width 0.1)
				(type default)
			)
			(layer "F.Fab")
		)
		(fp_line
			(start -0.12065 -0.2794)
			(end 0.12065 -0.2794)
			(stroke
				(width 0.1)
				(type default)
			)
			(layer "F.Fab")
		)
		(fp_line
			(start -0.12065 0.2794)
			(end -0.12065 0.3048)
			(stroke
				(width 0.1)
				(type default)
			)
			(layer "F.Fab")
		)
		(fp_line
			(start -0.12065 0.3048)
			(end -0.67945 0.3048)
			(stroke
				(width 0.1)
				(type default)
			)
			(layer "F.Fab")
		)
		(fp_line
			(start 0.120396 0.2794)
			(end -0.12065 0.2794)
			(stroke
				(width 0.1)
				(type default)
			)
			(layer "F.Fab")
		)
		(fp_line
			(start 0.120396 0.3048)
			(end 0.120396 0.2794)
			(stroke
				(width 0.1)
				(type default)
			)
			(layer "F.Fab")
		)
		(fp_line
			(start 0.12065 -0.3048)
			(end 0.67945 -0.3048)
			(stroke
				(width 0.1)
				(type default)
			)
			(layer "F.Fab")
		)
		(fp_line
			(start 0.12065 -0.2794)
			(end 0.12065 -0.3048)
			(stroke
				(width 0.1)
				(type default)
			)
			(layer "F.Fab")
		)
		(fp_line
			(start 0.67945 -0.3048)
			(end 0.67945 0.3048)
			(stroke
				(width 0.1)
				(type default)
			)
			(layer "F.Fab")
		)
		(fp_line
			(start 0.67945 0.3048)
			(end 0.120396 0.3048)
			(stroke
				(width 0.1)
				(type default)
			)
			(layer "F.Fab")
		)
		(pad "1" smd circle
			(at -0.40005 0)
			(size 0 0)
			(layers "F.Cu" "F.Mask" "F.Paste")
			(net "SMB_P52V_HSC_SCL")
		)
		(pad "2" smd circle
			(at 0.40005 0)
			(size 0 0)
			(layers "F.Cu" "F.Mask" "F.Paste")
			(net "SMB_P52V_VPDB_SCL_R2")
		)
	)
	(footprint ""
		(layer "F.Cu")
		(at 298.069 -26.797)
		(property "Reference" "C69"
			(at 0 0 0)
			(layer "F.SilkS")
			(hide yes)
			(effects
				(font
					(size 1.27 1.27)
				)
			)
		)
		(property "Value" ""
			(at 0 0 0)
			(layer "F.Fab")
			(effects
				(font
					(size 1.27 1.27)
				)
			)
		)
		(duplicate_pad_numbers_are_jumpers no)
		(fp_line
			(start -1.2954 -0.5842)
			(end 1.2954 -0.5842)
			(stroke
				(width 0.1524)
				(type default)
			)
			(layer "F.SilkS")
		)
		(fp_line
			(start -1.2954 0.5842)
			(end -1.2954 -0.5842)
			(stroke
				(width 0.1524)
				(type default)
			)
			(layer "F.SilkS")
		)
		(fp_line
			(start 1.2954 -0.5842)
			(end 1.2954 0.5842)
			(stroke
				(width 0.1524)
				(type default)
			)
			(layer "F.SilkS")
		)
		(fp_line
			(start 1.2954 0.5842)
			(end -1.2954 0.5842)
			(stroke
				(width 0.1524)
				(type default)
			)
			(layer "F.SilkS")
		)
		(fp_line
			(start -1.1938 -0.4064)
			(end -0.8636 -0.4064)
			(stroke
				(width 0.1)
				(type default)
			)
			(layer "F.Fab")
		)
		(fp_line
			(start -1.1938 0.4064)
			(end -1.1938 -0.4064)
			(stroke
				(width 0.1)
				(type default)
			)
			(layer "F.Fab")
		)
		(fp_line
			(start -0.8636 -0.4572)
			(end 0.8636 -0.4572)
			(stroke
				(width 0.1)
				(type default)
			)
			(layer "F.Fab")
		)
		(fp_line
			(start -0.8636 -0.4064)
			(end -0.8636 -0.4572)
			(stroke
				(width 0.1)
				(type default)
			)
			(layer "F.Fab")
		)
		(fp_line
			(start -0.8636 0.4064)
			(end -1.1938 0.4064)
			(stroke
				(width 0.1)
				(type default)
			)
			(layer "F.Fab")
		)
		(fp_line
			(start -0.8636 0.4572)
			(end -0.8636 0.4064)
			(stroke
				(width 0.1)
				(type default)
			)
			(layer "F.Fab")
		)
		(fp_line
			(start 0.8636 -0.4572)
			(end 0.8636 -0.4064)
			(stroke
				(width 0.1)
				(type default)
			)
			(layer "F.Fab")
		)
		(fp_line
			(start 0.8636 -0.4064)
			(end 1.1938 -0.4064)
			(stroke
				(width 0.1)
				(type default)
			)
			(layer "F.Fab")
		)
		(fp_line
			(start 0.8636 0.4064)
			(end 0.8636 0.4572)
			(stroke
				(width 0.1)
				(type default)
			)
			(layer "F.Fab")
		)
		(fp_line
			(start 0.8636 0.4572)
			(end -0.8636 0.4572)
			(stroke
				(width 0.1)
				(type default)
			)
			(layer "F.Fab")
		)
		(fp_line
			(start 1.1938 -0.4064)
			(end 1.1938 0.4064)
			(stroke
				(width 0.1)
				(type default)
			)
			(layer "F.Fab")
		)
		(fp_line
			(start 1.1938 0.4064)
			(end 0.8636 0.4064)
			(stroke
				(width 0.1)
				(type default)
			)
			(layer "F.Fab")
		)
		(pad "1" smd rect
			(at -0.7366 0 270)
			(size 0.7112 0.8128)
			(layers "F.Cu" "F.Mask" "F.Paste")
			(net "FM_HSC_EN_FUSE")
		)
		(pad "2" smd rect
			(at 0.7366 0 270)
			(size 0.7112 0.8128)
			(layers "F.Cu" "F.Mask" "F.Paste")
			(net "GND")
		)
	)
	(footprint ""
		(layer "F.Cu")
		(at 36.02736 -59.26582 90)
		(property "Reference" "R5893"
			(at 0 0 90)
			(layer "F.SilkS")
			(hide yes)
			(effects
				(font
					(size 1.27 1.27)
				)
			)
		)
		(property "Value" ""
			(at 0 0 90)
			(layer "F.Fab")
			(effects
				(font
					(size 1.27 1.27)
				)
			)
		)
		(duplicate_pad_numbers_are_jumpers no)
		(fp_line
			(start 0.7874 -0.4064)
			(end 0.7874 0.4064)
			(stroke
				(width 0.1524)
				(type default)
			)
			(layer "F.SilkS")
		)
		(fp_line
			(start -0.7874 -0.4064)
			(end 0.7874 -0.4064)
			(stroke
				(width 0.1524)
				(type default)
			)
			(layer "F.SilkS")
		)
		(fp_line
			(start 0.7874 0.4064)
			(end -0.7874 0.4064)
			(stroke
				(width 0.1524)
				(type default)
			)
			(layer "F.SilkS")
		)
		(fp_line
			(start -0.7874 0.4064)
			(end -0.7874 -0.4064)
			(stroke
				(width 0.1524)
				(type default)
			)
			(layer "F.SilkS")
		)
		(fp_line
			(start -0.12065 -0.305054)
			(end -0.12065 -0.2794)
			(stroke
				(width 0.1)
				(type default)
			)
			(layer "F.Fab")
		)
		(fp_line
			(start -0.67945 -0.305054)
			(end -0.12065 -0.305054)
			(stroke
				(width 0.1)
				(type default)
			)
			(layer "F.Fab")
		)
		(fp_line
			(start 0.67945 -0.3048)
			(end 0.67945 0.3048)
			(stroke
				(width 0.1)
				(type default)
			)
			(layer "F.Fab")
		)
		(fp_line
			(start 0.12065 -0.3048)
			(end 0.67945 -0.3048)
			(stroke
				(width 0.1)
				(type default)
			)
			(layer "F.Fab")
		)
		(fp_line
			(start 0.12065 -0.2794)
			(end 0.12065 -0.3048)
			(stroke
				(width 0.1)
				(type default)
			)
			(layer "F.Fab")
		)
		(fp_line
			(start -0.12065 -0.2794)
			(end 0.12065 -0.2794)
			(stroke
				(width 0.1)
				(type default)
			)
			(layer "F.Fab")
		)
		(fp_line
			(start 0.120396 0.2794)
			(end -0.12065 0.2794)
			(stroke
				(width 0.1)
				(type default)
			)
			(layer "F.Fab")
		)
		(fp_line
			(start -0.12065 0.2794)
			(end -0.12065 0.3048)
			(stroke
				(width 0.1)
				(type default)
			)
			(layer "F.Fab")
		)
		(fp_line
			(start 0.67945 0.3048)
			(end 0.120396 0.3048)
			(stroke
				(width 0.1)
				(type default)
			)
			(layer "F.Fab")
		)
		(fp_line
			(start 0.120396 0.3048)
			(end 0.120396 0.2794)
			(stroke
				(width 0.1)
				(type default)
			)
			(layer "F.Fab")
		)
		(fp_line
			(start -0.12065 0.3048)
			(end -0.67945 0.3048)
			(stroke
				(width 0.1)
				(type default)
			)
			(layer "F.Fab")
		)
		(fp_line
			(start -0.67945 0.3048)
			(end -0.67945 -0.305054)
			(stroke
				(width 0.1)
				(type default)
			)
			(layer "F.Fab")
		)
		(pad "1" smd rect
			(at -0.40005 0 270)
			(size 0.4572 0.508)
			(layers "F.Cu" "F.Mask" "F.Paste")
			(net "P12V_HPDB")
		)
		(pad "2" smd rect
			(at 0.40005 0 270)
			(size 0.4572 0.508)
			(layers "F.Cu" "F.Mask" "F.Paste")
			(net "P12V_HPDB_0_PD")
		)
	)
	(footprint ""
		(layer "F.Cu")
		(at 84.582 -49.911)
		(property "Reference" "PC91"
			(at 0 0 0)
			(layer "F.SilkS")
			(hide yes)
			(effects
				(font
					(size 1.27 1.27)
				)
			)
		)
		(property "Value" ""
			(at 0 0 0)
			(layer "F.Fab")
			(effects
				(font
					(size 1.27 1.27)
				)
			)
		)
		(duplicate_pad_numbers_are_jumpers no)
		(fp_line
			(start -1.524 -0.762)
			(end 1.524 -0.762)
			(stroke
				(width 0.1524)
				(type default)
			)
			(layer "F.SilkS")
		)
		(fp_line
			(start -1.524 0.762)
			(end -1.524 -0.762)
			(stroke
				(width 0.1524)
				(type default)
			)
			(layer "F.SilkS")
		)
		(fp_line
			(start 1.524 -0.762)
			(end 1.524 0.762)
			(stroke
				(width 0.1524)
				(type default)
			)
			(layer "F.SilkS")
		)
		(fp_line
			(start 1.524 0.762)
			(end -1.524 0.762)
			(stroke
				(width 0.1524)
				(type default)
			)
			(layer "F.SilkS")
		)
		(fp_line
			(start -1.1049 -0.724916)
			(end -1.1049 0.724916)
			(stroke
				(width 0.1)
				(type default)
			)
			(layer "F.Fab")
		)
		(fp_line
			(start -1.1049 0.724916)
			(end 1.1049 0.724916)
			(stroke
				(width 0.1)
				(type default)
			)
			(layer "F.Fab")
		)
		(fp_line
			(start 1.1049 -0.724916)
			(end -1.1049 -0.724916)
			(stroke
				(width 0.1)
				(type default)
			)
			(layer "F.Fab")
		)
		(fp_line
			(start 1.1049 0.724916)
			(end 1.1049 -0.724916)
			(stroke
				(width 0.1)
				(type default)
			)
			(layer "F.Fab")
		)
		(pad "1" smd rect
			(at -0.889 0 180)
			(size 1.016 1.27)
			(layers "F.Cu" "F.Mask" "F.Paste")
			(net "P12V_BRICK")
		)
		(pad "2" smd rect
			(at 0.889 0 180)
			(size 1.016 1.27)
			(layers "F.Cu" "F.Mask" "F.Paste")
			(net "GND")
		)
	)
	(footprint ""
		(layer "F.Cu")
		(at 297.561 -122.9995 180)
		(property "Reference" "PR6957"
			(at 0 0 180)
			(layer "F.SilkS")
			(hide yes)
			(effects
				(font
					(size 1.27 1.27)
				)
			)
		)
		(property "Value" ""
			(at 0 0 180)
			(layer "F.Fab")
			(effects
				(font
					(size 1.27 1.27)
				)
			)
		)
		(duplicate_pad_numbers_are_jumpers no)
		(fp_line
			(start 1.2954 0.5842)
			(end -1.2954 0.5842)
			(stroke
				(width 0.1524)
				(type default)
			)
			(layer "F.SilkS")
		)
		(fp_line
			(start 1.2954 -0.5842)
			(end 1.2954 0.5842)
			(stroke
				(width 0.1524)
				(type default)
			)
			(layer "F.SilkS")
		)
		(fp_line
			(start -1.2954 0.5842)
			(end -1.2954 -0.5842)
			(stroke
				(width 0.1524)
				(type default)
			)
			(layer "F.SilkS")
		)
		(fp_line
			(start -1.2954 -0.5842)
			(end 1.2954 -0.5842)
			(stroke
				(width 0.1524)
				(type default)
			)
			(layer "F.SilkS")
		)
		(fp_line
			(start 1.1938 0.4064)
			(end 0.8636 0.4064)
			(stroke
				(width 0.1)
				(type default)
			)
			(layer "F.Fab")
		)
		(fp_line
			(start 1.1938 -0.406654)
			(end 1.1938 0.4064)
			(stroke
				(width 0.1)
				(type default)
			)
			(layer "F.Fab")
		)
		(fp_line
			(start 0.8636 0.4572)
			(end -0.8636 0.4572)
			(stroke
				(width 0.1)
				(type default)
			)
			(layer "F.Fab")
		)
		(fp_line
			(start 0.8636 0.4064)
			(end 0.8636 0.4572)
			(stroke
				(width 0.1)
				(type default)
			)
			(layer "F.Fab")
		)
		(fp_line
			(start 0.8636 -0.406654)
			(end 1.1938 -0.406654)
			(stroke
				(width 0.1)
				(type default)
			)
			(layer "F.Fab")
		)
		(fp_line
			(start 0.8636 -0.4572)
			(end 0.8636 -0.406654)
			(stroke
				(width 0.1)
				(type default)
			)
			(layer "F.Fab")
		)
		(fp_line
			(start -0.8636 0.4572)
			(end -0.8636 0.4318)
			(stroke
				(width 0.1)
				(type default)
			)
			(layer "F.Fab")
		)
		(fp_line
			(start -0.8636 0.4318)
			(end -0.8636 0.4064)
			(stroke
				(width 0.1)
				(type default)
			)
			(layer "F.Fab")
		)
		(fp_line
			(start -0.8636 0.4064)
			(end -1.1938 0.4064)
			(stroke
				(width 0.1)
				(type default)
			)
			(layer "F.Fab")
		)
		(fp_line
			(start -0.8636 -0.406654)
			(end -0.8636 -0.4572)
			(stroke
				(width 0.1)
				(type default)
			)
			(layer "F.Fab")
		)
		(fp_line
			(start -0.8636 -0.4572)
			(end 0.8636 -0.4572)
			(stroke
				(width 0.1)
				(type default)
			)
			(layer "F.Fab")
		)
		(fp_line
			(start -1.1938 0.4064)
			(end -1.1938 -0.406654)
			(stroke
				(width 0.1)
				(type default)
			)
			(layer "F.Fab")
		)
		(fp_line
			(start -1.1938 -0.406654)
			(end -0.8636 -0.406654)
			(stroke
				(width 0.1)
				(type default)
			)
			(layer "F.Fab")
		)
		(pad "1" smd rect
			(at -0.7366 0 90)
			(size 0.7112 0.8128)
			(layers "F.Cu" "F.Mask" "F.Paste")
			(net "P52V_HS_4287_S1N")
		)
		(pad "2" smd rect
			(at 0.7366 0 90)
			(size 0.7112 0.8128)
			(layers "F.Cu" "F.Mask" "F.Paste")
			(net "P52V_HS1_SENSE_N_R1")
		)
	)
	(footprint ""
		(layer "F.Cu")
		(at 180.34 -10.287 90)
		(property "Reference" "PR314"
			(at 0 0 90)
			(layer "F.SilkS")
			(hide yes)
			(effects
				(font
					(size 1.27 1.27)
				)
			)
		)
		(property "Value" ""
			(at 0 0 90)
			(layer "F.Fab")
			(effects
				(font
					(size 1.27 1.27)
				)
			)
		)
		(duplicate_pad_numbers_are_jumpers no)
		(fp_line
			(start 0.7874 -0.4064)
			(end 0.7874 0.4064)
			(stroke
				(width 0.1524)
				(type default)
			)
			(layer "F.SilkS")
		)
		(fp_line
			(start -0.7874 -0.4064)
			(end 0.7874 -0.4064)
			(stroke
				(width 0.1524)
				(type default)
			)
			(layer "F.SilkS")
		)
		(fp_line
			(start 0.7874 0.4064)
			(end -0.7874 0.4064)
			(stroke
				(width 0.1524)
				(type default)
			)
			(layer "F.SilkS")
		)
		(fp_line
			(start -0.7874 0.4064)
			(end -0.7874 -0.4064)
			(stroke
				(width 0.1524)
				(type default)
			)
			(layer "F.SilkS")
		)
		(fp_line
			(start -0.12065 -0.305054)
			(end -0.12065 -0.2794)
			(stroke
				(width 0.1)
				(type default)
			)
			(layer "F.Fab")
		)
		(fp_line
			(start -0.67945 -0.305054)
			(end -0.12065 -0.305054)
			(stroke
				(width 0.1)
				(type default)
			)
			(layer "F.Fab")
		)
		(fp_line
			(start 0.67945 -0.3048)
			(end 0.67945 0.3048)
			(stroke
				(width 0.1)
				(type default)
			)
			(layer "F.Fab")
		)
		(fp_line
			(start 0.12065 -0.3048)
			(end 0.67945 -0.3048)
			(stroke
				(width 0.1)
				(type default)
			)
			(layer "F.Fab")
		)
		(fp_line
			(start 0.12065 -0.2794)
			(end 0.12065 -0.3048)
			(stroke
				(width 0.1)
				(type default)
			)
			(layer "F.Fab")
		)
		(fp_line
			(start -0.12065 -0.2794)
			(end 0.12065 -0.2794)
			(stroke
				(width 0.1)
				(type default)
			)
			(layer "F.Fab")
		)
		(fp_line
			(start 0.120396 0.2794)
			(end -0.12065 0.2794)
			(stroke
				(width 0.1)
				(type default)
			)
			(layer "F.Fab")
		)
		(fp_line
			(start -0.12065 0.2794)
			(end -0.12065 0.3048)
			(stroke
				(width 0.1)
				(type default)
			)
			(layer "F.Fab")
		)
		(fp_line
			(start 0.67945 0.3048)
			(end 0.120396 0.3048)
			(stroke
				(width 0.1)
				(type default)
			)
			(layer "F.Fab")
		)
		(fp_line
			(start 0.120396 0.3048)
			(end 0.120396 0.2794)
			(stroke
				(width 0.1)
				(type default)
			)
			(layer "F.Fab")
		)
		(fp_line
			(start -0.12065 0.3048)
			(end -0.67945 0.3048)
			(stroke
				(width 0.1)
				(type default)
			)
			(layer "F.Fab")
		)
		(fp_line
			(start -0.67945 0.3048)
			(end -0.67945 -0.305054)
			(stroke
				(width 0.1)
				(type default)
			)
			(layer "F.Fab")
		)
		(pad "1" smd circle
			(at -0.40005 0 90)
			(size 0 0)
			(layers "F.Cu" "F.Mask" "F.Paste")
			(net "SW_P3V3_AUX_BT")
		)
		(pad "2" smd circle
			(at 0.40005 0 90)
			(size 0 0)
			(layers "F.Cu" "F.Mask" "F.Paste")
			(net "SW_P3V3_AUX_BT_R")
		)
	)
	(footprint ""
		(layer "F.Cu")
		(at 8.58012 -79.939896)
		(property "Reference" "J7"
			(at 4.50088 -18.077434 0)
			(unlocked yes)
			(layer "F.SilkS")
			(effects
				(font
					(size 0.7874 0.5842)
					(thickness 0.1524)
				)
				(justify left)
			)
		)
		(property "Value" ""
			(at 0 0 0)
			(layer "F.Fab")
			(effects
				(font
					(size 1.27 1.27)
				)
			)
		)
		(duplicate_pad_numbers_are_jumpers no)
		(fp_line
			(start -14.51991 -17.210024)
			(end 5.679948 -17.210024)
			(stroke
				(width 0.1524)
				(type default)
			)
			(layer "F.SilkS")
		)
		(fp_line
			(start -14.51991 29.29001)
			(end -14.51991 -17.210024)
			(stroke
				(width 0.1524)
				(type default)
			)
			(layer "F.SilkS")
		)
		(fp_line
			(start 5.679948 -17.210024)
			(end 5.679948 29.29001)
			(stroke
				(width 0.1524)
				(type default)
			)
			(layer "F.SilkS")
		)
		(fp_line
			(start 5.679948 29.29001)
			(end -14.51991 29.29001)
			(stroke
				(width 0.1524)
				(type default)
			)
			(layer "F.SilkS")
		)
		(fp_poly
			(pts
				(xy 6.93928 0.564896) (xy 6.93928 -0.451104) (xy 5.92328 0.056896)
			)
			(stroke
				(width 0)
				(type default)
			)
			(fill yes)
			(layer "F.SilkS")
		)
		(fp_line
			(start -14.51991 -17.210024)
			(end 5.679948 -17.210024)
			(stroke
				(width 0.1)
				(type default)
			)
			(layer "F.Fab")
		)
		(fp_line
			(start -14.51991 29.29001)
			(end -14.51991 -17.210024)
			(stroke
				(width 0.1)
				(type default)
			)
			(layer "F.Fab")
		)
		(fp_line
			(start 5.679948 -17.210024)
			(end 5.679948 29.29001)
			(stroke
				(width 0.1)
				(type default)
			)
			(layer "F.Fab")
		)
		(fp_line
			(start 5.679948 29.29001)
			(end -14.51991 29.29001)
			(stroke
				(width 0.1)
				(type default)
			)
			(layer "F.Fab")
		)
		(fp_poly
			(pts
				(xy -15.693898 -0.508) (xy -15.693898 0.508) (xy -14.677898 0)
			)
			(stroke
				(width 0)
				(type default)
			)
			(fill yes)
			(layer "F.Fab")
		)
		(pad "" np_thru_hole circle
			(at -3.519932 -13.459968 270)
			(size 2.2098 2.2098)
			(drill 2.2098)
			(layers "*.Cu" "*.Mask")
			(clearance 0.381)
			(thermal_gap 0.381)
		)
		(pad "" np_thru_hole circle
			(at -3.519932 25.539954 270)
			(size 2.2098 2.2098)
			(drill 2.2098)
			(layers "*.Cu" "*.Mask")
			(clearance 0.381)
			(thermal_gap 0.381)
		)
		(pad "P1" thru_hole circle
			(at 1.27 20.860004 270)
			(size 1.4732 1.4732)
			(drill 1.0414)
			(layers "*.Cu" "*.Mask")
			(remove_unused_layers no)
			(net "GND")
			(clearance 0.0381)
			(thermal_gap 0.0381)
		)
		(pad "P2" thru_hole circle
			(at 1.27 19.159982 270)
			(size 1.4732 1.4732)
			(drill 1.0414)
			(layers "*.Cu" "*.Mask")
			(remove_unused_layers no)
			(net "GND")
			(clearance 0.0381)
			(thermal_gap 0.0381)
		)
		(pad "P3" thru_hole circle
			(at 1.27 15.780004 270)
			(size 1.4732 1.4732)
			(drill 1.0414)
			(layers "*.Cu" "*.Mask")
			(remove_unused_layers no)
			(net "GND")
			(clearance 0.0381)
			(thermal_gap 0.0381)
		)
		(pad "P4" thru_hole circle
			(at 1.27 14.079982 270)
			(size 1.4732 1.4732)
			(drill 1.0414)
			(layers "*.Cu" "*.Mask")
			(remove_unused_layers no)
			(net "GND")
			(clearance 0.0381)
			(thermal_gap 0.0381)
		)
		(pad "P5" thru_hole circle
			(at 1.27 10.700004 270)
			(size 1.4732 1.4732)
			(drill 1.0414)
			(layers "*.Cu" "*.Mask")
			(remove_unused_layers no)
			(net "P52V_FAN")
			(clearance 0.0381)
			(thermal_gap 0.0381)
		)
		(pad "P6" thru_hole circle
			(at 1.27 8.999982 270)
			(size 1.4732 1.4732)
			(drill 1.0414)
			(layers "*.Cu" "*.Mask")
			(remove_unused_layers no)
			(net "P52V_FAN")
			(clearance 0.0381)
			(thermal_gap 0.0381)
		)
		(pad "P7" thru_hole circle
			(at 1.27 5.620004 270)
			(size 1.4732 1.4732)
			(drill 1.0414)
			(layers "*.Cu" "*.Mask")
			(remove_unused_layers no)
			(net "P52V_FAN")
			(clearance 0.0381)
			(thermal_gap 0.0381)
		)
		(pad "P8" thru_hole circle
			(at 1.27 3.919982 270)
			(size 1.4732 1.4732)
			(drill 1.0414)
			(layers "*.Cu" "*.Mask")
			(remove_unused_layers no)
			(net "P52V_FAN")
			(clearance 0.0381)
			(thermal_gap 0.0381)
		)
		(pad "P9" thru_hole circle
			(at 3.81 3.919982 270)
			(size 1.4732 1.4732)
			(drill 1.0414)
			(layers "*.Cu" "*.Mask")
			(remove_unused_layers no)
			(net "P52V_FAN")
			(clearance 0.0381)
			(thermal_gap 0.0381)
		)
		(pad "P10" thru_hole circle
			(at 3.81 5.620004 270)
			(size 1.4732 1.4732)
			(drill 1.0414)
			(layers "*.Cu" "*.Mask")
			(remove_unused_layers no)
			(net "P52V_FAN")
			(clearance 0.0381)
			(thermal_gap 0.0381)
		)
		(pad "P11" thru_hole circle
			(at 3.81 8.999982 270)
			(size 1.4732 1.4732)
			(drill 1.0414)
			(layers "*.Cu" "*.Mask")
			(remove_unused_layers no)
			(net "P52V_FAN")
			(clearance 0.0381)
			(thermal_gap 0.0381)
		)
		(pad "P12" thru_hole circle
			(at 3.81 10.700004 270)
			(size 1.4732 1.4732)
			(drill 1.0414)
			(layers "*.Cu" "*.Mask")
			(remove_unused_layers no)
			(net "P52V_FAN")
			(clearance 0.0381)
			(thermal_gap 0.0381)
		)
		(pad "P13" thru_hole circle
			(at 3.81 14.079982 270)
			(size 1.4732 1.4732)
			(drill 1.0414)
			(layers "*.Cu" "*.Mask")
			(remove_unused_layers no)
			(net "GND")
			(clearance 0.0381)
			(thermal_gap 0.0381)
		)
		(pad "P14" thru_hole circle
			(at 3.81 15.780004 270)
			(size 1.4732 1.4732)
			(drill 1.0414)
			(layers "*.Cu" "*.Mask")
			(remove_unused_layers no)
			(net "GND")
			(clearance 0.0381)
			(thermal_gap 0.0381)
		)
		(pad "P15" thru_hole circle
			(at 3.81 19.159982 270)
			(size 1.4732 1.4732)
			(drill 1.0414)
			(layers "*.Cu" "*.Mask")
			(remove_unused_layers no)
			(net "GND")
			(clearance 0.0381)
			(thermal_gap 0.0381)
		)
		(pad "P16" thru_hole circle
			(at 3.81 20.860004 270)
			(size 1.4732 1.4732)
			(drill 1.0414)
			(layers "*.Cu" "*.Mask")
			(remove_unused_layers no)
			(net "GND")
			(clearance 0.0381)
			(thermal_gap 0.0381)
		)
		(pad "S1" thru_hole rect
			(at 0 0 270)
			(size 1.27 1.27)
			(drill 0.8636)
			(layers "*.Cu" "*.Mask")
			(remove_unused_layers no)
			(net "PRSNT_HPDB_N")
			(clearance 0.0508)
			(thermal_gap 0.0508)
			(padstack
				(mode front_inner_back)
				(layer "Inner"
					(shape circle)
					(size 1.27 1.27)
					(clearance 0.0508)
				)
				(layer "B.Cu"
					(shape rect)
					(size 1.27 1.27)
					(clearance 0.0508)
				)
			)
		)
		(pad "S2" thru_hole circle
			(at 1.27 -1.27 270)
			(size 1.27 1.27)
			(drill 0.8636)
			(layers "*.Cu" "*.Mask")
			(remove_unused_layers no)
			(net "PWRGD_P3V3_HPDB")
			(clearance 0.0508)
			(thermal_gap 0.0508)
		)
		(pad "S3" thru_hole circle
			(at 0 -2.54 270)
			(size 1.27 1.27)
			(drill 0.8636)
			(layers "*.Cu" "*.Mask")
			(remove_unused_layers no)
			(net "GND")
			(clearance 0.0508)
			(thermal_gap 0.0508)
		)
		(pad "S4" thru_hole circle
			(at 1.27 -3.81 270)
			(size 1.27 1.27)
			(drill 0.8636)
			(layers "*.Cu" "*.Mask")
			(remove_unused_layers no)
			(net "PWRGD_GPU_HSC")
			(clearance 0.0508)
			(thermal_gap 0.0508)
		)
		(pad "S5" thru_hole circle
			(at 0 -5.08 270)
			(size 1.27 1.27)
			(drill 0.8636)
			(layers "*.Cu" "*.Mask")
			(remove_unused_layers no)
			(net "SMB_P52V_HPDB_R_SDA")
			(clearance 0.0508)
			(thermal_gap 0.0508)
		)
		(pad "S6" thru_hole circle
			(at 1.27 -6.35 270)
			(size 1.27 1.27)
			(drill 0.8636)
			(layers "*.Cu" "*.Mask")
			(remove_unused_layers no)
			(net "SMB_P52V_HPDB_R_SCL")
			(clearance 0.0508)
			(thermal_gap 0.0508)
		)
		(pad "S7" thru_hole circle
			(at 0 -7.62 270)
			(size 1.27 1.27)
			(drill 0.8636)
			(layers "*.Cu" "*.Mask")
			(remove_unused_layers no)
			(net "SMB_HPDB_MISC_R_SDA")
			(clearance 0.0508)
			(thermal_gap 0.0508)
		)
		(pad "S8" thru_hole circle
			(at 1.27 -8.89 270)
			(size 1.27 1.27)
			(drill 0.8636)
			(layers "*.Cu" "*.Mask")
			(remove_unused_layers no)
			(net "SMB_HPDB_MISC_R_SCL")
			(clearance 0.0508)
			(thermal_gap 0.0508)
		)
		(pad "S9" thru_hole circle
			(at 3.81 -8.89 270)
			(size 1.27 1.27)
			(drill 0.8636)
			(layers "*.Cu" "*.Mask")
			(remove_unused_layers no)
			(net "P12V_HPDB")
			(clearance 0.0508)
			(thermal_gap 0.0508)
		)
		(pad "S10" thru_hole circle
			(at 2.54 -7.62 270)
			(size 1.27 1.27)
			(drill 0.8636)
			(layers "*.Cu" "*.Mask")
			(remove_unused_layers no)
			(net "P12V_HPDB")
			(clearance 0.0508)
			(thermal_gap 0.0508)
		)
		(pad "S11" thru_hole circle
			(at 3.81 -6.35 270)
			(size 1.27 1.27)
			(drill 0.8636)
			(layers "*.Cu" "*.Mask")
			(remove_unused_layers no)
			(net "PWRGD_P3V3_AUX_MB_BUF")
			(clearance 0.0508)
			(thermal_gap 0.0508)
		)
		(pad "S12" thru_hole circle
			(at 2.54 -5.08 270)
			(size 1.27 1.27)
			(drill 0.8636)
			(layers "*.Cu" "*.Mask")
			(remove_unused_layers no)
			(net "FAN_PWR_EN_BUF")
			(clearance 0.0508)
			(thermal_gap 0.0508)
		)
		(pad "S13" thru_hole circle
			(at 3.81 -3.81 270)
			(size 1.27 1.27)
			(drill 0.8636)
			(layers "*.Cu" "*.Mask")
			(remove_unused_layers no)
			(net "P12V_HPDB")
			(clearance 0.0508)
			(thermal_gap 0.0508)
		)
		(pad "S14" thru_hole circle
			(at 2.54 -2.54 270)
			(size 1.27 1.27)
			(drill 0.8636)
			(layers "*.Cu" "*.Mask")
			(remove_unused_layers no)
			(net "GPU_HSC_EN")
			(clearance 0.0508)
			(thermal_gap 0.0508)
		)
		(pad "S15" thru_hole circle
			(at 3.81 -1.27 270)
			(size 1.27 1.27)
			(drill 0.8636)
			(layers "*.Cu" "*.Mask")
			(remove_unused_layers no)
			(net "RST_SMB_PDB_BUF_N")
			(clearance 0.0508)
			(thermal_gap 0.0508)
		)
		(pad "S16" thru_hole circle
			(at 2.54 0 270)
			(size 1.27 1.27)
			(drill 0.8636)
			(layers "*.Cu" "*.Mask")
			(remove_unused_layers no)
			(net "P12V_HPDB_PWRGD")
			(clearance 0.0508)
			(thermal_gap 0.0508)
		)
		(zone
			(layers "F.Cu" "B.Cu" "In1.Cu" "In2.Cu" "In3.Cu" "In4.Cu" "In5.Cu" "In6.Cu"
				"In7.Cu" "In8.Cu"
			)
			(hatch none 0.5)
			(connect_pads
				(clearance 0)
			)
			(min_thickness 0.25)
			(keepout
				(tracks not_allowed)
				(vias allowed)
				(pads allowed)
				(copperpour not_allowed)
				(footprints allowed)
			)
			(placement
				(enabled no)
				(sheetname "")
			)
			(fill
				(thermal_gap 0.5)
				(thermal_bridge_width 0.5)
				(island_removal_mode 0)
			)
			(polygon
				(pts
					(arc
						(start 6.673088 -93.399864)
						(mid 3.447288 -93.399864)
						(end 6.673088 -93.399864)
					)
				)
			)
		)
		(zone
			(layers "F.Cu" "B.Cu" "In1.Cu" "In2.Cu" "In3.Cu" "In4.Cu" "In5.Cu" "In6.Cu"
				"In7.Cu" "In8.Cu"
			)
			(hatch none 0.5)
			(connect_pads
				(clearance 0)
			)
			(min_thickness 0.25)
			(keepout
				(tracks not_allowed)
				(vias allowed)
				(pads allowed)
				(copperpour not_allowed)
				(footprints allowed)
			)
			(placement
				(enabled no)
				(sheetname "")
			)
			(fill
				(thermal_gap 0.5)
				(thermal_bridge_width 0.5)
				(island_removal_mode 0)
			)
			(polygon
				(pts
					(arc
						(start 6.673088 -54.399942)
						(mid 3.447288 -54.399942)
						(end 6.673088 -54.399942)
					)
				)
			)
		)
	)
	(footprint ""
		(layer "F.Cu")
		(at 282.321 -22.352)
		(property "Reference" "R5885"
			(at 0 0 0)
			(layer "F.SilkS")
			(hide yes)
			(effects
				(font
					(size 1.27 1.27)
				)
			)
		)
		(property "Value" ""
			(at 0 0 0)
			(layer "F.Fab")
			(effects
				(font
					(size 1.27 1.27)
				)
			)
		)
		(duplicate_pad_numbers_are_jumpers no)
		(fp_line
			(start -0.7874 -0.4064)
			(end 0.7874 -0.4064)
			(stroke
				(width 0.1524)
				(type default)
			)
			(layer "F.SilkS")
		)
		(fp_line
			(start -0.7874 0.4064)
			(end -0.7874 -0.4064)
			(stroke
				(width 0.1524)
				(type default)
			)
			(layer "F.SilkS")
		)
		(fp_line
			(start 0.7874 -0.4064)
			(end 0.7874 0.4064)
			(stroke
				(width 0.1524)
				(type default)
			)
			(layer "F.SilkS")
		)
		(fp_line
			(start 0.7874 0.4064)
			(end -0.7874 0.4064)
			(stroke
				(width 0.1524)
				(type default)
			)
			(layer "F.SilkS")
		)
		(fp_line
			(start -0.67945 -0.305054)
			(end -0.12065 -0.305054)
			(stroke
				(width 0.1)
				(type default)
			)
			(layer "F.Fab")
		)
		(fp_line
			(start -0.67945 0.3048)
			(end -0.67945 -0.305054)
			(stroke
				(width 0.1)
				(type default)
			)
			(layer "F.Fab")
		)
		(fp_line
			(start -0.12065 -0.305054)
			(end -0.12065 -0.2794)
			(stroke
				(width 0.1)
				(type default)
			)
			(layer "F.Fab")
		)
		(fp_line
			(start -0.12065 -0.2794)
			(end 0.12065 -0.2794)
			(stroke
				(width 0.1)
				(type default)
			)
			(layer "F.Fab")
		)
		(fp_line
			(start -0.12065 0.2794)
			(end -0.12065 0.3048)
			(stroke
				(width 0.1)
				(type default)
			)
			(layer "F.Fab")
		)
		(fp_line
			(start -0.12065 0.3048)
			(end -0.67945 0.3048)
			(stroke
				(width 0.1)
				(type default)
			)
			(layer "F.Fab")
		)
		(fp_line
			(start 0.120396 0.2794)
			(end -0.12065 0.2794)
			(stroke
				(width 0.1)
				(type default)
			)
			(layer "F.Fab")
		)
		(fp_line
			(start 0.120396 0.3048)
			(end 0.120396 0.2794)
			(stroke
				(width 0.1)
				(type default)
			)
			(layer "F.Fab")
		)
		(fp_line
			(start 0.12065 -0.3048)
			(end 0.67945 -0.3048)
			(stroke
				(width 0.1)
				(type default)
			)
			(layer "F.Fab")
		)
		(fp_line
			(start 0.12065 -0.2794)
			(end 0.12065 -0.3048)
			(stroke
				(width 0.1)
				(type default)
			)
			(layer "F.Fab")
		)
		(fp_line
			(start 0.67945 -0.3048)
			(end 0.67945 0.3048)
			(stroke
				(width 0.1)
				(type default)
			)
			(layer "F.Fab")
		)
		(fp_line
			(start 0.67945 0.3048)
			(end 0.120396 0.3048)
			(stroke
				(width 0.1)
				(type default)
			)
			(layer "F.Fab")
		)
		(pad "1" smd circle
			(at -0.40005 0)
			(size 0 0)
			(layers "F.Cu" "F.Mask" "F.Paste")
			(net "FM_HSC_EN_BUSBAR")
		)
		(pad "2" smd circle
			(at 0.40005 0)
			(size 0 0)
			(layers "F.Cu" "F.Mask" "F.Paste")
			(net "GND")
		)
	)
	(footprint ""
		(layer "F.Cu")
		(at 45.6946 -57.10428)
		(property "Reference" "R5901"
			(at 0 0 0)
			(layer "F.SilkS")
			(hide yes)
			(effects
				(font
					(size 1.27 1.27)
				)
			)
		)
		(property "Value" ""
			(at 0 0 0)
			(layer "F.Fab")
			(effects
				(font
					(size 1.27 1.27)
				)
			)
		)
		(duplicate_pad_numbers_are_jumpers no)
		(fp_line
			(start -0.7874 -0.4064)
			(end 0.7874 -0.4064)
			(stroke
				(width 0.1524)
				(type default)
			)
			(layer "F.SilkS")
		)
		(fp_line
			(start -0.7874 0.4064)
			(end -0.7874 -0.4064)
			(stroke
				(width 0.1524)
				(type default)
			)
			(layer "F.SilkS")
		)
		(fp_line
			(start 0.7874 -0.4064)
			(end 0.7874 0.4064)
			(stroke
				(width 0.1524)
				(type default)
			)
			(layer "F.SilkS")
		)
		(fp_line
			(start 0.7874 0.4064)
			(end -0.7874 0.4064)
			(stroke
				(width 0.1524)
				(type default)
			)
			(layer "F.SilkS")
		)
		(fp_line
			(start -0.67945 -0.305054)
			(end -0.12065 -0.305054)
			(stroke
				(width 0.1)
				(type default)
			)
			(layer "F.Fab")
		)
		(fp_line
			(start -0.67945 0.3048)
			(end -0.67945 -0.305054)
			(stroke
				(width 0.1)
				(type default)
			)
			(layer "F.Fab")
		)
		(fp_line
			(start -0.12065 -0.305054)
			(end -0.12065 -0.2794)
			(stroke
				(width 0.1)
				(type default)
			)
			(layer "F.Fab")
		)
		(fp_line
			(start -0.12065 -0.2794)
			(end 0.12065 -0.2794)
			(stroke
				(width 0.1)
				(type default)
			)
			(layer "F.Fab")
		)
		(fp_line
			(start -0.12065 0.2794)
			(end -0.12065 0.3048)
			(stroke
				(width 0.1)
				(type default)
			)
			(layer "F.Fab")
		)
		(fp_line
			(start -0.12065 0.3048)
			(end -0.67945 0.3048)
			(stroke
				(width 0.1)
				(type default)
			)
			(layer "F.Fab")
		)
		(fp_line
			(start 0.120396 0.2794)
			(end -0.12065 0.2794)
			(stroke
				(width 0.1)
				(type default)
			)
			(layer "F.Fab")
		)
		(fp_line
			(start 0.120396 0.3048)
			(end 0.120396 0.2794)
			(stroke
				(width 0.1)
				(type default)
			)
			(layer "F.Fab")
		)
		(fp_line
			(start 0.12065 -0.3048)
			(end 0.67945 -0.3048)
			(stroke
				(width 0.1)
				(type default)
			)
			(layer "F.Fab")
		)
		(fp_line
			(start 0.12065 -0.2794)
			(end 0.12065 -0.3048)
			(stroke
				(width 0.1)
				(type default)
			)
			(layer "F.Fab")
		)
		(fp_line
			(start 0.67945 -0.3048)
			(end 0.67945 0.3048)
			(stroke
				(width 0.1)
				(type default)
			)
			(layer "F.Fab")
		)
		(fp_line
			(start 0.67945 0.3048)
			(end 0.120396 0.3048)
			(stroke
				(width 0.1)
				(type default)
			)
			(layer "F.Fab")
		)
		(pad "1" smd circle
			(at -0.40005 0)
			(size 0 0)
			(layers "F.Cu" "F.Mask" "F.Paste")
			(net "P12V_HPDB_0_ISET")
		)
		(pad "2" smd circle
			(at 0.40005 0)
			(size 0 0)
			(layers "F.Cu" "F.Mask" "F.Paste")
			(net "GND")
		)
	)
	(footprint ""
		(layer "F.Cu")
		(at 229.743 -95.504 -90)
		(property "Reference" "C35"
			(at 0 0 270)
			(layer "F.SilkS")
			(hide yes)
			(effects
				(font
					(size 1.27 1.27)
				)
			)
		)
		(property "Value" ""
			(at 0 0 270)
			(layer "F.Fab")
			(effects
				(font
					(size 1.27 1.27)
				)
			)
		)
		(duplicate_pad_numbers_are_jumpers no)
		(fp_line
			(start -2.2098 0.9398)
			(end -2.2098 -0.9398)
			(stroke
				(width 0.1524)
				(type default)
			)
			(layer "F.SilkS")
		)
		(fp_line
			(start 2.2098 0.9398)
			(end -2.2098 0.9398)
			(stroke
				(width 0.1524)
				(type default)
			)
			(layer "F.SilkS")
		)
		(fp_line
			(start -2.2098 -0.9398)
			(end 2.2098 -0.9398)
			(stroke
				(width 0.1524)
				(type default)
			)
			(layer "F.SilkS")
		)
		(fp_line
			(start 2.2098 -0.9398)
			(end 2.2098 0.9398)
			(stroke
				(width 0.1524)
				(type default)
			)
			(layer "F.SilkS")
		)
		(fp_line
			(start -1.700022 0.899922)
			(end -1.700022 -0.899922)
			(stroke
				(width 0.1)
				(type default)
			)
			(layer "F.Fab")
		)
		(fp_line
			(start 1.700022 0.899922)
			(end -1.700022 0.899922)
			(stroke
				(width 0.1)
				(type default)
			)
			(layer "F.Fab")
		)
		(fp_line
			(start -1.700022 -0.899922)
			(end 1.700022 -0.899922)
			(stroke
				(width 0.1)
				(type default)
			)
			(layer "F.Fab")
		)
		(fp_line
			(start 1.700022 -0.899922)
			(end 1.700022 0.899922)
			(stroke
				(width 0.1)
				(type default)
			)
			(layer "F.Fab")
		)
		(pad "1" smd rect
			(at -1.4732 0 90)
			(size 1.1684 1.5748)
			(layers "F.Cu" "F.Mask" "F.Paste")
			(net "P52V_HS")
		)
		(pad "2" smd rect
			(at 1.4732 0 90)
			(size 1.1684 1.5748)
			(layers "F.Cu" "F.Mask" "F.Paste")
			(net "GND")
		)
	)
	(footprint ""
		(layer "F.Cu")
		(at 100.076 -61.595)
		(property "Reference" "PC57"
			(at 0 0 0)
			(layer "F.SilkS")
			(hide yes)
			(effects
				(font
					(size 1.27 1.27)
				)
			)
		)
		(property "Value" ""
			(at 0 0 0)
			(layer "F.Fab")
			(effects
				(font
					(size 1.27 1.27)
				)
			)
		)
		(duplicate_pad_numbers_are_jumpers no)
		(fp_line
			(start -0.7874 -0.4064)
			(end 0.7874 -0.4064)
			(stroke
				(width 0.1524)
				(type default)
			)
			(layer "F.SilkS")
		)
		(fp_line
			(start -0.7874 0.4064)
			(end -0.7874 -0.4064)
			(stroke
				(width 0.1524)
				(type default)
			)
			(layer "F.SilkS")
		)
		(fp_line
			(start 0.7874 -0.4064)
			(end 0.7874 0.4064)
			(stroke
				(width 0.1524)
				(type default)
			)
			(layer "F.SilkS")
		)
		(fp_line
			(start 0.7874 0.4064)
			(end -0.7874 0.4064)
			(stroke
				(width 0.1524)
				(type default)
			)
			(layer "F.SilkS")
		)
		(fp_line
			(start -0.6858 -0.3048)
			(end -0.1016 -0.3048)
			(stroke
				(width 0.1)
				(type default)
			)
			(layer "F.Fab")
		)
		(fp_line
			(start -0.6858 0.3048)
			(end -0.6858 -0.3048)
			(stroke
				(width 0.1)
				(type default)
			)
			(layer "F.Fab")
		)
		(fp_line
			(start -0.1016 -0.3048)
			(end -0.1016 -0.2794)
			(stroke
				(width 0.1)
				(type default)
			)
			(layer "F.Fab")
		)
		(fp_line
			(start -0.1016 -0.2794)
			(end 0.1016 -0.2794)
			(stroke
				(width 0.1)
				(type default)
			)
			(layer "F.Fab")
		)
		(fp_line
			(start -0.1016 0.2794)
			(end -0.1016 0.3048)
			(stroke
				(width 0.1)
				(type default)
			)
			(layer "F.Fab")
		)
		(fp_line
			(start -0.1016 0.3048)
			(end -0.6858 0.3048)
			(stroke
				(width 0.1)
				(type default)
			)
			(layer "F.Fab")
		)
		(fp_line
			(start 0.1016 -0.3048)
			(end 0.6858 -0.3048)
			(stroke
				(width 0.1)
				(type default)
			)
			(layer "F.Fab")
		)
		(fp_line
			(start 0.1016 -0.2794)
			(end 0.1016 -0.3048)
			(stroke
				(width 0.1)
				(type default)
			)
			(layer "F.Fab")
		)
		(fp_line
			(start 0.1016 0.2794)
			(end -0.1016 0.2794)
			(stroke
				(width 0.1)
				(type default)
			)
			(layer "F.Fab")
		)
		(fp_line
			(start 0.1016 0.3048)
			(end 0.1016 0.2794)
			(stroke
				(width 0.1)
				(type default)
			)
			(layer "F.Fab")
		)
		(fp_line
			(start 0.6858 -0.3048)
			(end 0.6858 0.3048)
			(stroke
				(width 0.1)
				(type default)
			)
			(layer "F.Fab")
		)
		(fp_line
			(start 0.6858 0.3048)
			(end 0.1016 0.3048)
			(stroke
				(width 0.1)
				(type default)
			)
			(layer "F.Fab")
		)
		(pad "1" smd rect
			(at -0.40005 0 180)
			(size 0.4572 0.508)
			(layers "F.Cu" "F.Mask" "F.Paste")
			(net "P12V_BRICK")
		)
		(pad "2" smd rect
			(at 0.40005 0 180)
			(size 0.4572 0.508)
			(layers "F.Cu" "F.Mask" "F.Paste")
			(net "GND")
		)
	)
	(footprint ""
		(layer "F.Cu")
		(at 270.383 -81.493868 -90)
		(property "Reference" "PR15"
			(at 0 0 270)
			(layer "F.SilkS")
			(hide yes)
			(effects
				(font
					(size 1.27 1.27)
				)
			)
		)
		(property "Value" ""
			(at 0 0 270)
			(layer "F.Fab")
			(effects
				(font
					(size 1.27 1.27)
				)
			)
		)
		(duplicate_pad_numbers_are_jumpers no)
		(fp_line
			(start -1.2954 0.5842)
			(end -1.2954 -0.5842)
			(stroke
				(width 0.1524)
				(type default)
			)
			(layer "F.SilkS")
		)
		(fp_line
			(start 1.2954 0.5842)
			(end -1.2954 0.5842)
			(stroke
				(width 0.1524)
				(type default)
			)
			(layer "F.SilkS")
		)
		(fp_line
			(start -1.2954 -0.5842)
			(end 1.2954 -0.5842)
			(stroke
				(width 0.1524)
				(type default)
			)
			(layer "F.SilkS")
		)
		(fp_line
			(start 1.2954 -0.5842)
			(end 1.2954 0.5842)
			(stroke
				(width 0.1524)
				(type default)
			)
			(layer "F.SilkS")
		)
		(fp_line
			(start -0.8636 0.4572)
			(end -0.8636 0.4318)
			(stroke
				(width 0.1)
				(type default)
			)
			(layer "F.Fab")
		)
		(fp_line
			(start 0.8636 0.4572)
			(end -0.8636 0.4572)
			(stroke
				(width 0.1)
				(type default)
			)
			(layer "F.Fab")
		)
		(fp_line
			(start -0.8636 0.4318)
			(end -0.8636 0.4064)
			(stroke
				(width 0.1)
				(type default)
			)
			(layer "F.Fab")
		)
		(fp_line
			(start -1.1938 0.4064)
			(end -1.1938 -0.406654)
			(stroke
				(width 0.1)
				(type default)
			)
			(layer "F.Fab")
		)
		(fp_line
			(start -0.8636 0.4064)
			(end -1.1938 0.4064)
			(stroke
				(width 0.1)
				(type default)
			)
			(layer "F.Fab")
		)
		(fp_line
			(start 0.8636 0.4064)
			(end 0.8636 0.4572)
			(stroke
				(width 0.1)
				(type default)
			)
			(layer "F.Fab")
		)
		(fp_line
			(start 1.1938 0.4064)
			(end 0.8636 0.4064)
			(stroke
				(width 0.1)
				(type default)
			)
			(layer "F.Fab")
		)
		(fp_line
			(start -1.1938 -0.406654)
			(end -0.8636 -0.406654)
			(stroke
				(width 0.1)
				(type default)
			)
			(layer "F.Fab")
		)
		(fp_line
			(start -0.8636 -0.406654)
			(end -0.8636 -0.4572)
			(stroke
				(width 0.1)
				(type default)
			)
			(layer "F.Fab")
		)
		(fp_line
			(start 0.8636 -0.406654)
			(end 1.1938 -0.406654)
			(stroke
				(width 0.1)
				(type default)
			)
			(layer "F.Fab")
		)
		(fp_line
			(start 1.1938 -0.406654)
			(end 1.1938 0.4064)
			(stroke
				(width 0.1)
				(type default)
			)
			(layer "F.Fab")
		)
		(fp_line
			(start -0.8636 -0.4572)
			(end 0.8636 -0.4572)
			(stroke
				(width 0.1)
				(type default)
			)
			(layer "F.Fab")
		)
		(fp_line
			(start 0.8636 -0.4572)
			(end 0.8636 -0.406654)
			(stroke
				(width 0.1)
				(type default)
			)
			(layer "F.Fab")
		)
		(pad "1" smd rect
			(at -0.7366 0 180)
			(size 0.7112 0.8128)
			(layers "F.Cu" "F.Mask" "F.Paste")
			(net "P52V_HS1_GATE2_R")
		)
		(pad "2" smd rect
			(at 0.7366 0 180)
			(size 0.7112 0.8128)
			(layers "F.Cu" "F.Mask" "F.Paste")
			(net "P52V_HS1_GATE5")
		)
	)
	(footprint ""
		(layer "F.Cu")
		(at 260.236716 -47.946818)
		(property "Reference" "PR25"
			(at 0 0 0)
			(layer "F.SilkS")
			(hide yes)
			(effects
				(font
					(size 1.27 1.27)
				)
			)
		)
		(property "Value" ""
			(at 0 0 0)
			(layer "F.Fab")
			(effects
				(font
					(size 1.27 1.27)
				)
			)
		)
		(duplicate_pad_numbers_are_jumpers no)
		(fp_line
			(start -1.651 -0.8382)
			(end 1.651 -0.8382)
			(stroke
				(width 0.1524)
				(type default)
			)
			(layer "F.SilkS")
		)
		(fp_line
			(start -1.651 0.8382)
			(end -1.651 -0.8382)
			(stroke
				(width 0.1524)
				(type default)
			)
			(layer "F.SilkS")
		)
		(fp_line
			(start 1.651 -0.8382)
			(end 1.651 0.8382)
			(stroke
				(width 0.1524)
				(type default)
			)
			(layer "F.SilkS")
		)
		(fp_line
			(start 1.651 0.8382)
			(end -1.651 0.8382)
			(stroke
				(width 0.1524)
				(type default)
			)
			(layer "F.SilkS")
		)
		(fp_line
			(start -1.559814 -0.7366)
			(end -1.559814 0.7366)
			(stroke
				(width 0.1)
				(type default)
			)
			(layer "F.Fab")
		)
		(fp_line
			(start -1.559814 0.7366)
			(end -1.524 0.7366)
			(stroke
				(width 0.1)
				(type default)
			)
			(layer "F.Fab")
		)
		(fp_line
			(start -1.524 -0.7366)
			(end -1.559814 -0.7366)
			(stroke
				(width 0.1)
				(type default)
			)
			(layer "F.Fab")
		)
		(fp_line
			(start -1.524 0.7366)
			(end 1.524 0.7366)
			(stroke
				(width 0.1)
				(type default)
			)
			(layer "F.Fab")
		)
		(fp_line
			(start 1.524 -0.7366)
			(end -1.524 -0.7366)
			(stroke
				(width 0.1)
				(type default)
			)
			(layer "F.Fab")
		)
		(fp_line
			(start 1.524 0.7366)
			(end 1.560576 0.7366)
			(stroke
				(width 0.1)
				(type default)
			)
			(layer "F.Fab")
		)
		(fp_line
			(start 1.560576 -0.7366)
			(end 1.524 -0.7366)
			(stroke
				(width 0.1)
				(type default)
			)
			(layer "F.Fab")
		)
		(fp_line
			(start 1.560576 0.7366)
			(end 1.560576 -0.7366)
			(stroke
				(width 0.1)
				(type default)
			)
			(layer "F.Fab")
		)
		(pad "1" smd rect
			(at -0.94996 0 180)
			(size 1.1176 1.3716)
			(layers "F.Cu" "F.Mask" "F.Paste")
			(net "P52V_HS")
		)
		(pad "2" smd rect
			(at 0.94996 0 180)
			(size 1.1176 1.3716)
			(layers "F.Cu" "F.Mask" "F.Paste")
			(net "P52V_HS1_VDSFB")
		)
	)
	(footprint ""
		(layer "F.Cu")
		(at 198.115174 -60.96)
		(property "Reference" "PC135"
			(at -2.027174 -3.65633 0)
			(unlocked yes)
			(layer "F.SilkS")
			(effects
				(font
					(size 0.7874 0.5842)
					(thickness 0.1524)
				)
				(justify left)
			)
		)
		(property "Value" ""
			(at 0 0 0)
			(layer "F.Fab")
			(effects
				(font
					(size 1.27 1.27)
				)
			)
		)
		(duplicate_pad_numbers_are_jumpers no)
		(fp_line
			(start 5.2578 2.499868)
			(end -5.2578 2.499868)
			(stroke
				(width 0.1524)
				(type default)
			)
			(layer "F.SilkS")
		)
		(fp_circle
			(center 0 2.499868)
			(end 5.2578 2.499868)
			(stroke
				(width 0.1524)
				(type default)
			)
			(fill no)
			(layer "F.SilkS")
		)
		(fp_poly
			(pts
				(arc
					(start 5.2578 2.499868)
					(mid 0 7.757922)
					(end -5.2578 2.499868)
				)
			)
			(stroke
				(width 0)
				(type default)
			)
			(fill yes)
			(layer "F.SilkS")
		)
		(fp_circle
			(center 0 2.499868)
			(end 5.2578 2.499868)
			(stroke
				(width 0.1)
				(type default)
			)
			(fill no)
			(layer "F.Fab")
		)
		(pad "1" thru_hole rect
			(at 0 0 270)
			(size 1.524 1.524)
			(drill 1.016)
			(layers "*.Cu" "*.Mask")
			(remove_unused_layers no)
			(net "P12V_BRICK")
			(clearance 0)
			(padstack
				(mode front_inner_back)
				(layer "Inner"
					(shape circle)
					(size 1.524 1.524)
					(clearance 0)
				)
				(layer "B.Cu"
					(shape rect)
					(size 1.524 1.524)
					(clearance 0)
				)
			)
		)
		(pad "2" thru_hole circle
			(at 0 4.99999 270)
			(size 1.524 1.524)
			(drill 1.016)
			(layers "*.Cu" "*.Mask")
			(remove_unused_layers no)
			(net "GND")
			(clearance 0)
		)
	)
	(footprint ""
		(layer "F.Cu")
		(at 158.115 -60.96)
		(property "Reference" "PC42"
			(at -1.397 -3.52933 0)
			(unlocked yes)
			(layer "F.SilkS")
			(effects
				(font
					(size 0.7874 0.5842)
					(thickness 0.1524)
				)
				(justify left)
			)
		)
		(property "Value" ""
			(at 0 0 0)
			(layer "F.Fab")
			(effects
				(font
					(size 1.27 1.27)
				)
			)
		)
		(duplicate_pad_numbers_are_jumpers no)
		(fp_line
			(start 5.2578 2.499868)
			(end -5.2578 2.499868)
			(stroke
				(width 0.1524)
				(type default)
			)
			(layer "F.SilkS")
		)
		(fp_circle
			(center 0 2.499868)
			(end 5.2578 2.499868)
			(stroke
				(width 0.1524)
				(type default)
			)
			(fill no)
			(layer "F.SilkS")
		)
		(fp_poly
			(pts
				(arc
					(start 5.2578 2.499868)
					(mid 0 7.757922)
					(end -5.2578 2.499868)
				)
			)
			(stroke
				(width 0)
				(type default)
			)
			(fill yes)
			(layer "F.SilkS")
		)
		(fp_circle
			(center 0 2.499868)
			(end 5.2578 2.499868)
			(stroke
				(width 0.1)
				(type default)
			)
			(fill no)
			(layer "F.Fab")
		)
		(pad "1" thru_hole rect
			(at 0 0 270)
			(size 1.524 1.524)
			(drill 1.016)
			(layers "*.Cu" "*.Mask")
			(remove_unused_layers no)
			(net "P12V_BRICK")
			(clearance 0)
			(padstack
				(mode front_inner_back)
				(layer "Inner"
					(shape circle)
					(size 1.524 1.524)
					(clearance 0)
				)
				(layer "B.Cu"
					(shape rect)
					(size 1.524 1.524)
					(clearance 0)
				)
			)
		)
		(pad "2" thru_hole circle
			(at 0 4.99999 270)
			(size 1.524 1.524)
			(drill 1.016)
			(layers "*.Cu" "*.Mask")
			(remove_unused_layers no)
			(net "GND")
			(clearance 0)
		)
	)
	(footprint ""
		(layer "F.Cu")
		(at 94.238826 -136.906 90)
		(property "Reference" "PC44"
			(at 6.06933 1.011174 0)
			(unlocked yes)
			(layer "F.SilkS")
			(effects
				(font
					(size 0.7874 0.5842)
					(thickness 0.1524)
				)
				(justify left)
			)
		)
		(property "Value" ""
			(at 0 0 90)
			(layer "F.Fab")
			(effects
				(font
					(size 1.27 1.27)
				)
			)
		)
		(duplicate_pad_numbers_are_jumpers no)
		(fp_line
			(start 5.2578 2.499868)
			(end -5.2578 2.499868)
			(stroke
				(width 0.1524)
				(type default)
			)
			(layer "F.SilkS")
		)
		(fp_circle
			(center 0 2.500122)
			(end 0 7.758176)
			(stroke
				(width 0.1524)
				(type default)
			)
			(fill no)
			(layer "F.SilkS")
		)
		(fp_poly
			(pts
				(arc
					(start 5.2578 2.499868)
					(mid 0 7.757922)
					(end -5.2578 2.499868)
				)
			)
			(stroke
				(width 0)
				(type default)
			)
			(fill yes)
			(layer "F.SilkS")
		)
		(fp_circle
			(center 0 2.500122)
			(end 0 7.758176)
			(stroke
				(width 0.1)
				(type default)
			)
			(fill no)
			(layer "F.Fab")
		)
		(pad "1" thru_hole rect
			(at 0 0)
			(size 1.5748 1.5748)
			(drill 1.0668)
			(layers "*.Cu" "*.Mask")
			(remove_unused_layers no)
			(net "P52V_HS_FILTER")
			(clearance 0)
			(padstack
				(mode front_inner_back)
				(layer "Inner"
					(shape circle)
					(size 1.5748 1.5748)
					(clearance 0)
				)
				(layer "B.Cu"
					(shape rect)
					(size 1.5748 1.5748)
					(clearance 0)
				)
			)
		)
		(pad "2" thru_hole circle
			(at 0 4.99999)
			(size 1.5748 1.5748)
			(drill 1.0668)
			(layers "*.Cu" "*.Mask")
			(remove_unused_layers no)
			(net "GND")
			(clearance 0)
		)
	)
	(footprint ""
		(layer "F.Cu")
		(at 234.569 -95.504 -90)
		(property "Reference" "C39"
			(at 0 0 270)
			(layer "F.SilkS")
			(hide yes)
			(effects
				(font
					(size 1.27 1.27)
				)
			)
		)
		(property "Value" ""
			(at 0 0 270)
			(layer "F.Fab")
			(effects
				(font
					(size 1.27 1.27)
				)
			)
		)
		(duplicate_pad_numbers_are_jumpers no)
		(fp_line
			(start -2.2098 0.9398)
			(end -2.2098 -0.9398)
			(stroke
				(width 0.1524)
				(type default)
			)
			(layer "F.SilkS")
		)
		(fp_line
			(start 2.2098 0.9398)
			(end -2.2098 0.9398)
			(stroke
				(width 0.1524)
				(type default)
			)
			(layer "F.SilkS")
		)
		(fp_line
			(start -2.2098 -0.9398)
			(end 2.2098 -0.9398)
			(stroke
				(width 0.1524)
				(type default)
			)
			(layer "F.SilkS")
		)
		(fp_line
			(start 2.2098 -0.9398)
			(end 2.2098 0.9398)
			(stroke
				(width 0.1524)
				(type default)
			)
			(layer "F.SilkS")
		)
		(fp_line
			(start -1.700022 0.899922)
			(end -1.700022 -0.899922)
			(stroke
				(width 0.1)
				(type default)
			)
			(layer "F.Fab")
		)
		(fp_line
			(start 1.700022 0.899922)
			(end -1.700022 0.899922)
			(stroke
				(width 0.1)
				(type default)
			)
			(layer "F.Fab")
		)
		(fp_line
			(start -1.700022 -0.899922)
			(end 1.700022 -0.899922)
			(stroke
				(width 0.1)
				(type default)
			)
			(layer "F.Fab")
		)
		(fp_line
			(start 1.700022 -0.899922)
			(end 1.700022 0.899922)
			(stroke
				(width 0.1)
				(type default)
			)
			(layer "F.Fab")
		)
		(pad "1" smd rect
			(at -1.4732 0 90)
			(size 1.1684 1.5748)
			(layers "F.Cu" "F.Mask" "F.Paste")
			(net "P52V_HS")
		)
		(pad "2" smd rect
			(at 1.4732 0 90)
			(size 1.1684 1.5748)
			(layers "F.Cu" "F.Mask" "F.Paste")
			(net "GND")
		)
	)
	(footprint ""
		(layer "F.Cu")
		(at 146.939 -60.96)
		(property "Reference" "PC40"
			(at -1.27 -3.65633 0)
			(unlocked yes)
			(layer "F.SilkS")
			(effects
				(font
					(size 0.7874 0.5842)
					(thickness 0.1524)
				)
				(justify left)
			)
		)
		(property "Value" ""
			(at 0 0 0)
			(layer "F.Fab")
			(effects
				(font
					(size 1.27 1.27)
				)
			)
		)
		(duplicate_pad_numbers_are_jumpers no)
		(fp_line
			(start 5.2578 2.499868)
			(end -5.2578 2.499868)
			(stroke
				(width 0.1524)
				(type default)
			)
			(layer "F.SilkS")
		)
		(fp_circle
			(center 0 2.499868)
			(end 5.2578 2.499868)
			(stroke
				(width 0.1524)
				(type default)
			)
			(fill no)
			(layer "F.SilkS")
		)
		(fp_poly
			(pts
				(arc
					(start 5.2578 2.499868)
					(mid 0 7.757922)
					(end -5.2578 2.499868)
				)
			)
			(stroke
				(width 0)
				(type default)
			)
			(fill yes)
			(layer "F.SilkS")
		)
		(fp_circle
			(center 0 2.499868)
			(end 5.2578 2.499868)
			(stroke
				(width 0.1)
				(type default)
			)
			(fill no)
			(layer "F.Fab")
		)
		(pad "1" thru_hole rect
			(at 0 0 270)
			(size 1.524 1.524)
			(drill 1.016)
			(layers "*.Cu" "*.Mask")
			(remove_unused_layers no)
			(net "P12V_BRICK")
			(clearance 0)
			(padstack
				(mode front_inner_back)
				(layer "Inner"
					(shape circle)
					(size 1.524 1.524)
					(clearance 0)
				)
				(layer "B.Cu"
					(shape rect)
					(size 1.524 1.524)
					(clearance 0)
				)
			)
		)
		(pad "2" thru_hole circle
			(at 0 4.99999 270)
			(size 1.524 1.524)
			(drill 1.016)
			(layers "*.Cu" "*.Mask")
			(remove_unused_layers no)
			(net "GND")
			(clearance 0)
		)
	)
	(footprint ""
		(layer "F.Cu")
		(at 280.67 -24.765 180)
		(property "Reference" "U19"
			(at 0.3175 2.24663 0)
			(unlocked yes)
			(layer "F.SilkS")
			(effects
				(font
					(size 0.7874 0.5842)
					(thickness 0.1524)
				)
				(justify left)
			)
		)
		(property "Value" ""
			(at 0 0 180)
			(layer "F.Fab")
			(effects
				(font
					(size 1.27 1.27)
				)
			)
		)
		(duplicate_pad_numbers_are_jumpers no)
		(fp_line
			(start 1.733296 1.549908)
			(end 1.733296 -1.549908)
			(stroke
				(width 0.1524)
				(type default)
			)
			(layer "F.SilkS")
		)
		(fp_line
			(start 1.733296 -1.549908)
			(end 0.660908 -1.549908)
			(stroke
				(width 0.1524)
				(type default)
			)
			(layer "F.SilkS")
		)
		(fp_line
			(start 0.660908 -1.549908)
			(end 0 -0.889)
			(stroke
				(width 0.1524)
				(type default)
			)
			(layer "F.SilkS")
		)
		(fp_line
			(start 0 -0.889)
			(end -0.660908 -1.549908)
			(stroke
				(width 0.1524)
				(type default)
			)
			(layer "F.SilkS")
		)
		(fp_line
			(start -0.660908 -1.549908)
			(end -1.733296 -1.549908)
			(stroke
				(width 0.1524)
				(type default)
			)
			(layer "F.SilkS")
		)
		(fp_line
			(start -1.733296 1.549908)
			(end 1.733296 1.549908)
			(stroke
				(width 0.1524)
				(type default)
			)
			(layer "F.SilkS")
		)
		(fp_line
			(start -1.733296 -1.549908)
			(end -1.733296 1.549908)
			(stroke
				(width 0.1524)
				(type default)
			)
			(layer "F.SilkS")
		)
		(fp_poly
			(pts
				(xy -2.4384 -1.20396) (xy -2.4384 -0.69596) (xy -1.9304 -0.94996)
			)
			(stroke
				(width 0)
				(type default)
			)
			(fill yes)
			(layer "F.SilkS")
		)
		(fp_line
			(start 0.849884 1.549908)
			(end 0.849884 -1.549908)
			(stroke
				(width 0.1)
				(type default)
			)
			(layer "F.Fab")
		)
		(fp_line
			(start 0.849884 -1.549908)
			(end -0.849884 -1.549908)
			(stroke
				(width 0.1)
				(type default)
			)
			(layer "F.Fab")
		)
		(fp_line
			(start -0.849884 1.549908)
			(end 0.849884 1.549908)
			(stroke
				(width 0.1)
				(type default)
			)
			(layer "F.Fab")
		)
		(fp_line
			(start -0.849884 -1.549908)
			(end -0.849884 1.549908)
			(stroke
				(width 0.1)
				(type default)
			)
			(layer "F.Fab")
		)
		(fp_poly
			(pts
				(xy -2.4384 -1.20396) (xy -2.4384 -0.69596) (xy -1.9304 -0.94996)
			)
			(stroke
				(width 0)
				(type default)
			)
			(fill yes)
			(layer "F.Fab")
		)
		(pad "1" smd rect
			(at -1.199896 -0.94996 90)
			(size 0.5588 0.8128)
			(layers "F.Cu" "F.Mask" "F.Paste")
			(net "FM_HSC_EN_BUSBAR")
		)
		(pad "2" smd rect
			(at -1.199896 0 90)
			(size 0.5588 0.8128)
			(layers "F.Cu" "F.Mask" "F.Paste")
			(net "FM_HSC_EN_FUSE")
		)
		(pad "3" smd rect
			(at -1.199896 0.94996 90)
			(size 0.5588 0.8128)
			(layers "F.Cu" "F.Mask" "F.Paste")
			(net "GND")
		)
		(pad "4" smd rect
			(at 1.199896 0.94996 90)
			(size 0.5588 0.8128)
			(layers "F.Cu" "F.Mask" "F.Paste")
			(net "P52V_HS1_R_EN")
		)
		(pad "5" smd rect
			(at 1.199896 -0.94996 90)
			(size 0.5588 0.8128)
			(layers "F.Cu" "F.Mask" "F.Paste")
			(net "P3V3_AND")
		)
	)
	(footprint ""
		(layer "F.Cu")
		(at 266.192 -34.798 -90)
		(property "Reference" "PR210"
			(at 0 0 270)
			(layer "F.SilkS")
			(hide yes)
			(effects
				(font
					(size 1.27 1.27)
				)
			)
		)
		(property "Value" ""
			(at 0 0 270)
			(layer "F.Fab")
			(effects
				(font
					(size 1.27 1.27)
				)
			)
		)
		(duplicate_pad_numbers_are_jumpers no)
		(fp_line
			(start -0.7874 0.4064)
			(end -0.7874 -0.4064)
			(stroke
				(width 0.1524)
				(type default)
			)
			(layer "F.SilkS")
		)
		(fp_line
			(start 0.7874 0.4064)
			(end -0.7874 0.4064)
			(stroke
				(width 0.1524)
				(type default)
			)
			(layer "F.SilkS")
		)
		(fp_line
			(start -0.7874 -0.4064)
			(end 0.7874 -0.4064)
			(stroke
				(width 0.1524)
				(type default)
			)
			(layer "F.SilkS")
		)
		(fp_line
			(start 0.7874 -0.4064)
			(end 0.7874 0.4064)
			(stroke
				(width 0.1524)
				(type default)
			)
			(layer "F.SilkS")
		)
		(fp_line
			(start -0.67945 0.3048)
			(end -0.67945 -0.305054)
			(stroke
				(width 0.1)
				(type default)
			)
			(layer "F.Fab")
		)
		(fp_line
			(start -0.12065 0.3048)
			(end -0.67945 0.3048)
			(stroke
				(width 0.1)
				(type default)
			)
			(layer "F.Fab")
		)
		(fp_line
			(start 0.120396 0.3048)
			(end 0.120396 0.2794)
			(stroke
				(width 0.1)
				(type default)
			)
			(layer "F.Fab")
		)
		(fp_line
			(start 0.67945 0.3048)
			(end 0.120396 0.3048)
			(stroke
				(width 0.1)
				(type default)
			)
			(layer "F.Fab")
		)
		(fp_line
			(start -0.12065 0.2794)
			(end -0.12065 0.3048)
			(stroke
				(width 0.1)
				(type default)
			)
			(layer "F.Fab")
		)
		(fp_line
			(start 0.120396 0.2794)
			(end -0.12065 0.2794)
			(stroke
				(width 0.1)
				(type default)
			)
			(layer "F.Fab")
		)
		(fp_line
			(start -0.12065 -0.2794)
			(end 0.12065 -0.2794)
			(stroke
				(width 0.1)
				(type default)
			)
			(layer "F.Fab")
		)
		(fp_line
			(start 0.12065 -0.2794)
			(end 0.12065 -0.3048)
			(stroke
				(width 0.1)
				(type default)
			)
			(layer "F.Fab")
		)
		(fp_line
			(start 0.12065 -0.3048)
			(end 0.67945 -0.3048)
			(stroke
				(width 0.1)
				(type default)
			)
			(layer "F.Fab")
		)
		(fp_line
			(start 0.67945 -0.3048)
			(end 0.67945 0.3048)
			(stroke
				(width 0.1)
				(type default)
			)
			(layer "F.Fab")
		)
		(fp_line
			(start -0.67945 -0.305054)
			(end -0.12065 -0.305054)
			(stroke
				(width 0.1)
				(type default)
			)
			(layer "F.Fab")
		)
		(fp_line
			(start -0.12065 -0.305054)
			(end -0.12065 -0.2794)
			(stroke
				(width 0.1)
				(type default)
			)
			(layer "F.Fab")
		)
		(pad "1" smd circle
			(at -0.40005 0 270)
			(size 0 0)
			(layers "F.Cu" "F.Mask" "F.Paste")
			(net "P52V_HS1_TMR")
		)
		(pad "2" smd circle
			(at 0.40005 0 270)
			(size 0 0)
			(layers "F.Cu" "F.Mask" "F.Paste")
			(net "HS1_TMR1")
		)
	)
	(footprint ""
		(layer "F.Cu")
		(at 279.010872 -39.649146)
		(property "Reference" "R146"
			(at 0 0 0)
			(layer "F.SilkS")
			(hide yes)
			(effects
				(font
					(size 1.27 1.27)
				)
			)
		)
		(property "Value" ""
			(at 0 0 0)
			(layer "F.Fab")
			(effects
				(font
					(size 1.27 1.27)
				)
			)
		)
		(duplicate_pad_numbers_are_jumpers no)
		(fp_line
			(start -0.7874 -0.4064)
			(end 0.7874 -0.4064)
			(stroke
				(width 0.1524)
				(type default)
			)
			(layer "F.SilkS")
		)
		(fp_line
			(start -0.7874 0.4064)
			(end -0.7874 -0.4064)
			(stroke
				(width 0.1524)
				(type default)
			)
			(layer "F.SilkS")
		)
		(fp_line
			(start 0.7874 -0.4064)
			(end 0.7874 0.4064)
			(stroke
				(width 0.1524)
				(type default)
			)
			(layer "F.SilkS")
		)
		(fp_line
			(start 0.7874 0.4064)
			(end -0.7874 0.4064)
			(stroke
				(width 0.1524)
				(type default)
			)
			(layer "F.SilkS")
		)
		(fp_line
			(start -0.67945 -0.305054)
			(end -0.12065 -0.305054)
			(stroke
				(width 0.1)
				(type default)
			)
			(layer "F.Fab")
		)
		(fp_line
			(start -0.67945 0.3048)
			(end -0.67945 -0.305054)
			(stroke
				(width 0.1)
				(type default)
			)
			(layer "F.Fab")
		)
		(fp_line
			(start -0.12065 -0.305054)
			(end -0.12065 -0.2794)
			(stroke
				(width 0.1)
				(type default)
			)
			(layer "F.Fab")
		)
		(fp_line
			(start -0.12065 -0.2794)
			(end 0.12065 -0.2794)
			(stroke
				(width 0.1)
				(type default)
			)
			(layer "F.Fab")
		)
		(fp_line
			(start -0.12065 0.2794)
			(end -0.12065 0.3048)
			(stroke
				(width 0.1)
				(type default)
			)
			(layer "F.Fab")
		)
		(fp_line
			(start -0.12065 0.3048)
			(end -0.67945 0.3048)
			(stroke
				(width 0.1)
				(type default)
			)
			(layer "F.Fab")
		)
		(fp_line
			(start 0.120396 0.2794)
			(end -0.12065 0.2794)
			(stroke
				(width 0.1)
				(type default)
			)
			(layer "F.Fab")
		)
		(fp_line
			(start 0.120396 0.3048)
			(end 0.120396 0.2794)
			(stroke
				(width 0.1)
				(type default)
			)
			(layer "F.Fab")
		)
		(fp_line
			(start 0.12065 -0.3048)
			(end 0.67945 -0.3048)
			(stroke
				(width 0.1)
				(type default)
			)
			(layer "F.Fab")
		)
		(fp_line
			(start 0.12065 -0.2794)
			(end 0.12065 -0.3048)
			(stroke
				(width 0.1)
				(type default)
			)
			(layer "F.Fab")
		)
		(fp_line
			(start 0.67945 -0.3048)
			(end 0.67945 0.3048)
			(stroke
				(width 0.1)
				(type default)
			)
			(layer "F.Fab")
		)
		(fp_line
			(start 0.67945 0.3048)
			(end 0.120396 0.3048)
			(stroke
				(width 0.1)
				(type default)
			)
			(layer "F.Fab")
		)
		(pad "1" smd circle
			(at -0.40005 0)
			(size 0 0)
			(layers "F.Cu" "F.Mask" "F.Paste")
			(net "P3V3_AUX")
		)
		(pad "2" smd circle
			(at 0.40005 0)
			(size 0 0)
			(layers "F.Cu" "F.Mask" "F.Paste")
			(net "SMB_P52V_VPDB_SCL_R2")
		)
	)
	(footprint ""
		(layer "F.Cu")
		(at 30.000194 -135.999982 -90)
		(property "Reference" "H11"
			(at -6.340348 12.093194 0)
			(unlocked yes)
			(layer "F.SilkS")
			(effects
				(font
					(size 0.7874 0.5842)
					(thickness 0.1524)
				)
				(justify left)
			)
		)
		(property "Value" ""
			(at 0 0 270)
			(layer "F.Fab")
			(effects
				(font
					(size 1.27 1.27)
				)
			)
		)
		(duplicate_pad_numbers_are_jumpers no)
		(pad "1" thru_hole oval
			(at 0 0 270)
			(size 10.0076 32.004)
			(drill 3.0226
				(offset 0 10.999978)
			)
			(layers "*.Cu" "*.Mask")
			(remove_unused_layers no)
			(net "GND")
			(clearance -1.995678)
			(padstack
				(mode front_inner_back)
				(layer "Inner"
					(shape circle)
					(size 0 0)
					(clearance 0)
				)
				(layer "B.Cu"
					(shape oval)
					(size 10.0076 32.004)
					(offset 0 10.999978)
					(clearance -1.995678)
				)
			)
		)
	)
	(footprint ""
		(layer "F.Cu")
		(at 278.892 -45.593 180)
		(property "Reference" "PR6933"
			(at 0 0 180)
			(layer "F.SilkS")
			(hide yes)
			(effects
				(font
					(size 1.27 1.27)
				)
			)
		)
		(property "Value" ""
			(at 0 0 180)
			(layer "F.Fab")
			(effects
				(font
					(size 1.27 1.27)
				)
			)
		)
		(duplicate_pad_numbers_are_jumpers no)
		(fp_line
			(start 0.7874 0.4064)
			(end -0.7874 0.4064)
			(stroke
				(width 0.1524)
				(type default)
			)
			(layer "F.SilkS")
		)
		(fp_line
			(start 0.7874 -0.4064)
			(end 0.7874 0.4064)
			(stroke
				(width 0.1524)
				(type default)
			)
			(layer "F.SilkS")
		)
		(fp_line
			(start -0.7874 0.4064)
			(end -0.7874 -0.4064)
			(stroke
				(width 0.1524)
				(type default)
			)
			(layer "F.SilkS")
		)
		(fp_line
			(start -0.7874 -0.4064)
			(end 0.7874 -0.4064)
			(stroke
				(width 0.1524)
				(type default)
			)
			(layer "F.SilkS")
		)
		(fp_line
			(start 0.67945 0.3048)
			(end 0.120396 0.3048)
			(stroke
				(width 0.1)
				(type default)
			)
			(layer "F.Fab")
		)
		(fp_line
			(start 0.67945 -0.3048)
			(end 0.67945 0.3048)
			(stroke
				(width 0.1)
				(type default)
			)
			(layer "F.Fab")
		)
		(fp_line
			(start 0.12065 -0.2794)
			(end 0.12065 -0.3048)
			(stroke
				(width 0.1)
				(type default)
			)
			(layer "F.Fab")
		)
		(fp_line
			(start 0.12065 -0.3048)
			(end 0.67945 -0.3048)
			(stroke
				(width 0.1)
				(type default)
			)
			(layer "F.Fab")
		)
		(fp_line
			(start 0.120396 0.3048)
			(end 0.120396 0.2794)
			(stroke
				(width 0.1)
				(type default)
			)
			(layer "F.Fab")
		)
		(fp_line
			(start 0.120396 0.2794)
			(end -0.12065 0.2794)
			(stroke
				(width 0.1)
				(type default)
			)
			(layer "F.Fab")
		)
		(fp_line
			(start -0.12065 0.3048)
			(end -0.67945 0.3048)
			(stroke
				(width 0.1)
				(type default)
			)
			(layer "F.Fab")
		)
		(fp_line
			(start -0.12065 0.2794)
			(end -0.12065 0.3048)
			(stroke
				(width 0.1)
				(type default)
			)
			(layer "F.Fab")
		)
		(fp_line
			(start -0.12065 -0.2794)
			(end 0.12065 -0.2794)
			(stroke
				(width 0.1)
				(type default)
			)
			(layer "F.Fab")
		)
		(fp_line
			(start -0.12065 -0.305054)
			(end -0.12065 -0.2794)
			(stroke
				(width 0.1)
				(type default)
			)
			(layer "F.Fab")
		)
		(fp_line
			(start -0.67945 0.3048)
			(end -0.67945 -0.305054)
			(stroke
				(width 0.1)
				(type default)
			)
			(layer "F.Fab")
		)
		(fp_line
			(start -0.67945 -0.305054)
			(end -0.12065 -0.305054)
			(stroke
				(width 0.1)
				(type default)
			)
			(layer "F.Fab")
		)
		(pad "1" smd circle
			(at -0.40005 0 180)
			(size 0 0)
			(layers "F.Cu" "F.Mask" "F.Paste")
			(net "P52V_HS1_ISET")
		)
		(pad "2" smd circle
			(at 0.40005 0 180)
			(size 0 0)
			(layers "F.Cu" "F.Mask" "F.Paste")
			(net "P52V_HS1_VCAP")
		)
	)
	(footprint ""
		(layer "F.Cu")
		(at 278.1554 -24.257 90)
		(property "Reference" "C90"
			(at 0 0 90)
			(layer "F.SilkS")
			(hide yes)
			(effects
				(font
					(size 1.27 1.27)
				)
			)
		)
		(property "Value" ""
			(at 0 0 90)
			(layer "F.Fab")
			(effects
				(font
					(size 1.27 1.27)
				)
			)
		)
		(duplicate_pad_numbers_are_jumpers no)
		(fp_line
			(start 0.7874 -0.4064)
			(end 0.7874 0.4064)
			(stroke
				(width 0.1524)
				(type default)
			)
			(layer "F.SilkS")
		)
		(fp_line
			(start -0.7874 -0.4064)
			(end 0.7874 -0.4064)
			(stroke
				(width 0.1524)
				(type default)
			)
			(layer "F.SilkS")
		)
		(fp_line
			(start 0.7874 0.4064)
			(end -0.7874 0.4064)
			(stroke
				(width 0.1524)
				(type default)
			)
			(layer "F.SilkS")
		)
		(fp_line
			(start -0.7874 0.4064)
			(end -0.7874 -0.4064)
			(stroke
				(width 0.1524)
				(type default)
			)
			(layer "F.SilkS")
		)
		(fp_line
			(start -0.12065 -0.305054)
			(end -0.12065 -0.2794)
			(stroke
				(width 0.1)
				(type default)
			)
			(layer "F.Fab")
		)
		(fp_line
			(start -0.67945 -0.305054)
			(end -0.12065 -0.305054)
			(stroke
				(width 0.1)
				(type default)
			)
			(layer "F.Fab")
		)
		(fp_line
			(start 0.67945 -0.3048)
			(end 0.67945 0.3048)
			(stroke
				(width 0.1)
				(type default)
			)
			(layer "F.Fab")
		)
		(fp_line
			(start 0.12065 -0.3048)
			(end 0.67945 -0.3048)
			(stroke
				(width 0.1)
				(type default)
			)
			(layer "F.Fab")
		)
		(fp_line
			(start 0.12065 -0.2794)
			(end 0.12065 -0.3048)
			(stroke
				(width 0.1)
				(type default)
			)
			(layer "F.Fab")
		)
		(fp_line
			(start -0.12065 -0.2794)
			(end 0.12065 -0.2794)
			(stroke
				(width 0.1)
				(type default)
			)
			(layer "F.Fab")
		)
		(fp_line
			(start 0.120396 0.2794)
			(end -0.12065 0.2794)
			(stroke
				(width 0.1)
				(type default)
			)
			(layer "F.Fab")
		)
		(fp_line
			(start -0.12065 0.2794)
			(end -0.12065 0.3048)
			(stroke
				(width 0.1)
				(type default)
			)
			(layer "F.Fab")
		)
		(fp_line
			(start 0.67945 0.3048)
			(end 0.120396 0.3048)
			(stroke
				(width 0.1)
				(type default)
			)
			(layer "F.Fab")
		)
		(fp_line
			(start 0.120396 0.3048)
			(end 0.120396 0.2794)
			(stroke
				(width 0.1)
				(type default)
			)
			(layer "F.Fab")
		)
		(fp_line
			(start -0.12065 0.3048)
			(end -0.67945 0.3048)
			(stroke
				(width 0.1)
				(type default)
			)
			(layer "F.Fab")
		)
		(fp_line
			(start -0.67945 0.3048)
			(end -0.67945 -0.305054)
			(stroke
				(width 0.1)
				(type default)
			)
			(layer "F.Fab")
		)
		(pad "1" smd circle
			(at -0.40005 0 90)
			(size 0 0)
			(layers "F.Cu" "F.Mask" "F.Paste")
			(net "P3V3_AND")
		)
		(pad "2" smd circle
			(at 0.40005 0 90)
			(size 0 0)
			(layers "F.Cu" "F.Mask" "F.Paste")
			(net "GND")
		)
	)
	(footprint ""
		(layer "F.Cu")
		(at 282.575 -35.687 -90)
		(property "Reference" "R151"
			(at 0 0 270)
			(layer "F.SilkS")
			(hide yes)
			(effects
				(font
					(size 1.27 1.27)
				)
			)
		)
		(property "Value" ""
			(at 0 0 270)
			(layer "F.Fab")
			(effects
				(font
					(size 1.27 1.27)
				)
			)
		)
		(duplicate_pad_numbers_are_jumpers no)
		(fp_line
			(start -0.7874 0.4064)
			(end -0.7874 -0.4064)
			(stroke
				(width 0.1524)
				(type default)
			)
			(layer "F.SilkS")
		)
		(fp_line
			(start 0.7874 0.4064)
			(end -0.7874 0.4064)
			(stroke
				(width 0.1524)
				(type default)
			)
			(layer "F.SilkS")
		)
		(fp_line
			(start -0.7874 -0.4064)
			(end 0.7874 -0.4064)
			(stroke
				(width 0.1524)
				(type default)
			)
			(layer "F.SilkS")
		)
		(fp_line
			(start 0.7874 -0.4064)
			(end 0.7874 0.4064)
			(stroke
				(width 0.1524)
				(type default)
			)
			(layer "F.SilkS")
		)
		(fp_line
			(start -0.67945 0.3048)
			(end -0.67945 -0.305054)
			(stroke
				(width 0.1)
				(type default)
			)
			(layer "F.Fab")
		)
		(fp_line
			(start -0.12065 0.3048)
			(end -0.67945 0.3048)
			(stroke
				(width 0.1)
				(type default)
			)
			(layer "F.Fab")
		)
		(fp_line
			(start 0.120396 0.3048)
			(end 0.120396 0.2794)
			(stroke
				(width 0.1)
				(type default)
			)
			(layer "F.Fab")
		)
		(fp_line
			(start 0.67945 0.3048)
			(end 0.120396 0.3048)
			(stroke
				(width 0.1)
				(type default)
			)
			(layer "F.Fab")
		)
		(fp_line
			(start -0.12065 0.2794)
			(end -0.12065 0.3048)
			(stroke
				(width 0.1)
				(type default)
			)
			(layer "F.Fab")
		)
		(fp_line
			(start 0.120396 0.2794)
			(end -0.12065 0.2794)
			(stroke
				(width 0.1)
				(type default)
			)
			(layer "F.Fab")
		)
		(fp_line
			(start -0.12065 -0.2794)
			(end 0.12065 -0.2794)
			(stroke
				(width 0.1)
				(type default)
			)
			(layer "F.Fab")
		)
		(fp_line
			(start 0.12065 -0.2794)
			(end 0.12065 -0.3048)
			(stroke
				(width 0.1)
				(type default)
			)
			(layer "F.Fab")
		)
		(fp_line
			(start 0.12065 -0.3048)
			(end 0.67945 -0.3048)
			(stroke
				(width 0.1)
				(type default)
			)
			(layer "F.Fab")
		)
		(fp_line
			(start 0.67945 -0.3048)
			(end 0.67945 0.3048)
			(stroke
				(width 0.1)
				(type default)
			)
			(layer "F.Fab")
		)
		(fp_line
			(start -0.67945 -0.305054)
			(end -0.12065 -0.305054)
			(stroke
				(width 0.1)
				(type default)
			)
			(layer "F.Fab")
		)
		(fp_line
			(start -0.12065 -0.305054)
			(end -0.12065 -0.2794)
			(stroke
				(width 0.1)
				(type default)
			)
			(layer "F.Fab")
		)
		(pad "1" smd circle
			(at -0.40005 0 270)
			(size 0 0)
			(layers "F.Cu" "F.Mask" "F.Paste")
			(net "P52V_HS1_GPO2")
		)
		(pad "2" smd circle
			(at 0.40005 0 270)
			(size 0 0)
			(layers "F.Cu" "F.Mask" "F.Paste")
			(net "P52V_HS1_FLT")
		)
	)
	(footprint ""
		(layer "F.Cu")
		(at 64.470026 -121.209816)
		(property "Reference" "PU4"
			(at -26.563066 -5.12953 0)
			(unlocked yes)
			(layer "F.SilkS")
			(effects
				(font
					(size 0.7874 0.5842)
					(thickness 0.1524)
				)
				(justify left)
			)
		)
		(property "Value" ""
			(at 0 0 0)
			(layer "F.Fab")
			(effects
				(font
					(size 1.27 1.27)
				)
			)
		)
		(duplicate_pad_numbers_are_jumpers no)
		(fp_line
			(start -26.519886 -4.299966)
			(end -26.519886 55.099966)
			(stroke
				(width 0.1524)
				(type default)
			)
			(layer "F.SilkS")
		)
		(fp_line
			(start -26.519886 55.099966)
			(end 11.279886 55.099966)
			(stroke
				(width 0.1524)
				(type default)
			)
			(layer "F.SilkS")
		)
		(fp_line
			(start -26.020014 -3.800094)
			(end -26.020014 54.59984)
			(stroke
				(width 0.1524)
				(type default)
			)
			(layer "F.SilkS")
		)
		(fp_line
			(start -26.020014 54.59984)
			(end 10.780014 54.59984)
			(stroke
				(width 0.1524)
				(type default)
			)
			(layer "F.SilkS")
		)
		(fp_line
			(start 10.780014 -3.800094)
			(end -26.020014 -3.800094)
			(stroke
				(width 0.1524)
				(type default)
			)
			(layer "F.SilkS")
		)
		(fp_line
			(start 10.780014 54.59984)
			(end 10.780014 -3.800094)
			(stroke
				(width 0.1524)
				(type default)
			)
			(layer "F.SilkS")
		)
		(fp_line
			(start 11.279886 -4.299966)
			(end -26.519886 -4.299966)
			(stroke
				(width 0.1524)
				(type default)
			)
			(layer "F.SilkS")
		)
		(fp_line
			(start 11.279886 55.099966)
			(end 11.279886 -4.299966)
			(stroke
				(width 0.1524)
				(type default)
			)
			(layer "F.SilkS")
		)
		(fp_poly
			(pts
				(xy 1.27 -7.44728) (xy -1.27 -7.44728) (xy 0 -4.90728)
			)
			(stroke
				(width 0)
				(type default)
			)
			(fill yes)
			(layer "F.SilkS")
		)
		(fp_line
			(start -26.020014 -3.800094)
			(end -26.020014 54.59984)
			(stroke
				(width 0.1)
				(type default)
			)
			(layer "F.Fab")
		)
		(fp_line
			(start -26.020014 54.59984)
			(end 10.780014 54.59984)
			(stroke
				(width 0.1)
				(type default)
			)
			(layer "F.Fab")
		)
		(fp_line
			(start 10.780014 -3.800094)
			(end -26.020014 -3.800094)
			(stroke
				(width 0.1)
				(type default)
			)
			(layer "F.Fab")
		)
		(fp_line
			(start 10.780014 54.59984)
			(end 10.780014 -3.800094)
			(stroke
				(width 0.1)
				(type default)
			)
			(layer "F.Fab")
		)
		(fp_poly
			(pts
				(xy 1.27 -7.44728) (xy -1.27 -7.44728) (xy 0 -4.90728)
			)
			(stroke
				(width 0)
				(type default)
			)
			(fill yes)
			(layer "F.Fab")
		)
		(pad "1" thru_hole rect
			(at 0 0 270)
			(size 2.3622 2.3622)
			(drill 1.6002)
			(layers "*.Cu" "*.Mask")
			(remove_unused_layers no)
			(net "P52V_HS_FILTER")
			(clearance -0.127)
			(padstack
				(mode front_inner_back)
				(layer "Inner"
					(shape circle)
					(size 2.3622 2.3622)
					(clearance -0.127)
				)
				(layer "B.Cu"
					(shape rect)
					(size 2.3622 2.3622)
					(clearance -0.127)
				)
			)
		)
		(pad "2" thru_hole circle
			(at -7.62 0 270)
			(size 2.3622 2.3622)
			(drill 1.6002)
			(layers "*.Cu" "*.Mask")
			(remove_unused_layers no)
			(net "BRICK_P12V3_ON_OFF_R")
			(clearance -0.127)
		)
		(pad "3" thru_hole circle
			(at -15.24 0 270)
			(size 2.3622 2.3622)
			(drill 1.6002)
			(layers "*.Cu" "*.Mask")
			(remove_unused_layers no)
			(net "GND")
			(clearance -0.127)
		)
		(pad "4" thru_hole circle
			(at -19.05 50.8 270)
			(size 3.1242 3.1242)
			(drill 2.1082)
			(layers "*.Cu" "*.Mask")
			(remove_unused_layers no)
			(net "GND")
			(clearance -0.254)
		)
		(pad "5" thru_hole circle
			(at -15.24 50.8 270)
			(size 3.1242 3.1242)
			(drill 2.1082)
			(layers "*.Cu" "*.Mask")
			(remove_unused_layers no)
			(net "GND")
			(clearance -0.254)
		)
		(pad "6" thru_hole circle
			(at 0 50.8 270)
			(size 3.1242 3.1242)
			(drill 2.1082)
			(layers "*.Cu" "*.Mask")
			(remove_unused_layers no)
			(net "P12V_BRICK")
			(clearance -0.254)
		)
		(pad "7" thru_hole circle
			(at 3.81 50.8 270)
			(size 3.1242 3.1242)
			(drill 2.1082)
			(layers "*.Cu" "*.Mask")
			(remove_unused_layers no)
			(net "P12V_BRICK")
			(clearance -0.254)
		)
		(pad "8" thru_hole circle
			(at -13.619988 53.34 270)
			(size 1.3208 1.3208)
			(drill 0.9144)
			(layers "*.Cu" "*.Mask")
			(remove_unused_layers no)
			(net "P12V_BRICK_PWRGD")
			(clearance 0.0508)
			(thermal_gap 0.0508)
		)
		(pad "9" thru_hole circle
			(at -11.619992 53.34 270)
			(size 1.3208 1.3208)
			(drill 0.9144)
			(layers "*.Cu" "*.Mask")
			(remove_unused_layers no)
			(net "P12V_MB3_SENSE-")
			(clearance 0.0508)
			(thermal_gap 0.0508)
		)
		(pad "10" thru_hole circle
			(at -9.619996 53.34 270)
			(size 1.3208 1.3208)
			(drill 0.9144)
			(layers "*.Cu" "*.Mask")
			(remove_unused_layers no)
			(net "SMB_BRICK3_SDA")
			(clearance 0.0508)
			(thermal_gap 0.0508)
		)
		(pad "11" thru_hole circle
			(at -7.62 53.34 270)
			(size 1.3208 1.3208)
			(drill 0.9144)
			(layers "*.Cu" "*.Mask")
			(remove_unused_layers no)
			(net "SMB_BRICK3_ALERT")
			(clearance 0.0508)
			(thermal_gap 0.0508)
		)
		(pad "12" thru_hole circle
			(at -5.620004 53.34 270)
			(size 1.3208 1.3208)
			(drill 0.9144)
			(layers "*.Cu" "*.Mask")
			(remove_unused_layers no)
			(net "SMB_BRICK3_SCL")
			(clearance 0.0508)
			(thermal_gap 0.0508)
		)
		(pad "13" thru_hole circle
			(at -3.620008 53.34 270)
			(size 1.3208 1.3208)
			(drill 0.9144)
			(layers "*.Cu" "*.Mask")
			(remove_unused_layers no)
			(net "BRICK3_PMBADD")
			(clearance 0.0508)
			(thermal_gap 0.0508)
		)
		(pad "14" thru_hole circle
			(at -1.620012 53.34 270)
			(size 1.3208 1.3208)
			(drill 0.9144)
			(layers "*.Cu" "*.Mask")
			(remove_unused_layers no)
			(net "P12V_MB3_SENSE+")
			(clearance 0.0508)
			(thermal_gap 0.0508)
		)
	)
	(footprint ""
		(layer "F.Cu")
		(at 79.121 -51.943)
		(property "Reference" "PC92"
			(at 0 0 0)
			(layer "F.SilkS")
			(hide yes)
			(effects
				(font
					(size 1.27 1.27)
				)
			)
		)
		(property "Value" ""
			(at 0 0 0)
			(layer "F.Fab")
			(effects
				(font
					(size 1.27 1.27)
				)
			)
		)
		(duplicate_pad_numbers_are_jumpers no)
		(fp_line
			(start -1.524 -0.762)
			(end 1.524 -0.762)
			(stroke
				(width 0.1524)
				(type default)
			)
			(layer "F.SilkS")
		)
		(fp_line
			(start -1.524 0.762)
			(end -1.524 -0.762)
			(stroke
				(width 0.1524)
				(type default)
			)
			(layer "F.SilkS")
		)
		(fp_line
			(start 1.524 -0.762)
			(end 1.524 0.762)
			(stroke
				(width 0.1524)
				(type default)
			)
			(layer "F.SilkS")
		)
		(fp_line
			(start 1.524 0.762)
			(end -1.524 0.762)
			(stroke
				(width 0.1524)
				(type default)
			)
			(layer "F.SilkS")
		)
		(fp_line
			(start -1.1049 -0.724916)
			(end -1.1049 0.724916)
			(stroke
				(width 0.1)
				(type default)
			)
			(layer "F.Fab")
		)
		(fp_line
			(start -1.1049 0.724916)
			(end 1.1049 0.724916)
			(stroke
				(width 0.1)
				(type default)
			)
			(layer "F.Fab")
		)
		(fp_line
			(start 1.1049 -0.724916)
			(end -1.1049 -0.724916)
			(stroke
				(width 0.1)
				(type default)
			)
			(layer "F.Fab")
		)
		(fp_line
			(start 1.1049 0.724916)
			(end 1.1049 -0.724916)
			(stroke
				(width 0.1)
				(type default)
			)
			(layer "F.Fab")
		)
		(pad "1" smd rect
			(at -0.889 0 180)
			(size 1.016 1.27)
			(layers "F.Cu" "F.Mask" "F.Paste")
			(net "P12V_BRICK")
		)
		(pad "2" smd rect
			(at 0.889 0 180)
			(size 1.016 1.27)
			(layers "F.Cu" "F.Mask" "F.Paste")
			(net "GND")
		)
	)
	(footprint ""
		(layer "F.Cu")
		(at 301.602394 -83.5025)
		(property "Reference" "PR6961"
			(at 0 0 0)
			(layer "F.SilkS")
			(hide yes)
			(effects
				(font
					(size 1.27 1.27)
				)
			)
		)
		(property "Value" ""
			(at 0 0 0)
			(layer "F.Fab")
			(effects
				(font
					(size 1.27 1.27)
				)
			)
		)
		(duplicate_pad_numbers_are_jumpers no)
		(fp_line
			(start -1.2954 -0.5842)
			(end 1.2954 -0.5842)
			(stroke
				(width 0.1524)
				(type default)
			)
			(layer "F.SilkS")
		)
		(fp_line
			(start -1.2954 0.5842)
			(end -1.2954 -0.5842)
			(stroke
				(width 0.1524)
				(type default)
			)
			(layer "F.SilkS")
		)
		(fp_line
			(start 1.2954 -0.5842)
			(end 1.2954 0.5842)
			(stroke
				(width 0.1524)
				(type default)
			)
			(layer "F.SilkS")
		)
		(fp_line
			(start 1.2954 0.5842)
			(end -1.2954 0.5842)
			(stroke
				(width 0.1524)
				(type default)
			)
			(layer "F.SilkS")
		)
		(fp_line
			(start -1.1938 -0.406654)
			(end -0.8636 -0.406654)
			(stroke
				(width 0.1)
				(type default)
			)
			(layer "F.Fab")
		)
		(fp_line
			(start -1.1938 0.4064)
			(end -1.1938 -0.406654)
			(stroke
				(width 0.1)
				(type default)
			)
			(layer "F.Fab")
		)
		(fp_line
			(start -0.8636 -0.4572)
			(end 0.8636 -0.4572)
			(stroke
				(width 0.1)
				(type default)
			)
			(layer "F.Fab")
		)
		(fp_line
			(start -0.8636 -0.406654)
			(end -0.8636 -0.4572)
			(stroke
				(width 0.1)
				(type default)
			)
			(layer "F.Fab")
		)
		(fp_line
			(start -0.8636 0.4064)
			(end -1.1938 0.4064)
			(stroke
				(width 0.1)
				(type default)
			)
			(layer "F.Fab")
		)
		(fp_line
			(start -0.8636 0.4318)
			(end -0.8636 0.4064)
			(stroke
				(width 0.1)
				(type default)
			)
			(layer "F.Fab")
		)
		(fp_line
			(start -0.8636 0.4572)
			(end -0.8636 0.4318)
			(stroke
				(width 0.1)
				(type default)
			)
			(layer "F.Fab")
		)
		(fp_line
			(start 0.8636 -0.4572)
			(end 0.8636 -0.406654)
			(stroke
				(width 0.1)
				(type default)
			)
			(layer "F.Fab")
		)
		(fp_line
			(start 0.8636 -0.406654)
			(end 1.1938 -0.406654)
			(stroke
				(width 0.1)
				(type default)
			)
			(layer "F.Fab")
		)
		(fp_line
			(start 0.8636 0.4064)
			(end 0.8636 0.4572)
			(stroke
				(width 0.1)
				(type default)
			)
			(layer "F.Fab")
		)
		(fp_line
			(start 0.8636 0.4572)
			(end -0.8636 0.4572)
			(stroke
				(width 0.1)
				(type default)
			)
			(layer "F.Fab")
		)
		(fp_line
			(start 1.1938 -0.406654)
			(end 1.1938 0.4064)
			(stroke
				(width 0.1)
				(type default)
			)
			(layer "F.Fab")
		)
		(fp_line
			(start 1.1938 0.4064)
			(end 0.8636 0.4064)
			(stroke
				(width 0.1)
				(type default)
			)
			(layer "F.Fab")
		)
		(pad "1" smd rect
			(at -0.7366 0 270)
			(size 0.7112 0.8128)
			(layers "F.Cu" "F.Mask" "F.Paste")
			(net "P52V_HS_1272_S_P")
		)
		(pad "2" smd rect
			(at 0.7366 0 270)
			(size 0.7112 0.8128)
			(layers "F.Cu" "F.Mask" "F.Paste")
			(net "P52V_HS1_SENSE_P_R2")
		)
	)
	(footprint ""
		(layer "F.Cu")
		(at 297.538394 -85.2805)
		(property "Reference" "PR6965"
			(at 0 0 0)
			(layer "F.SilkS")
			(hide yes)
			(effects
				(font
					(size 1.27 1.27)
				)
			)
		)
		(property "Value" ""
			(at 0 0 0)
			(layer "F.Fab")
			(effects
				(font
					(size 1.27 1.27)
				)
			)
		)
		(duplicate_pad_numbers_are_jumpers no)
		(fp_line
			(start -1.2954 -0.5842)
			(end 1.2954 -0.5842)
			(stroke
				(width 0.1524)
				(type default)
			)
			(layer "F.SilkS")
		)
		(fp_line
			(start -1.2954 0.5842)
			(end -1.2954 -0.5842)
			(stroke
				(width 0.1524)
				(type default)
			)
			(layer "F.SilkS")
		)
		(fp_line
			(start 1.2954 -0.5842)
			(end 1.2954 0.5842)
			(stroke
				(width 0.1524)
				(type default)
			)
			(layer "F.SilkS")
		)
		(fp_line
			(start 1.2954 0.5842)
			(end -1.2954 0.5842)
			(stroke
				(width 0.1524)
				(type default)
			)
			(layer "F.SilkS")
		)
		(fp_line
			(start -1.1938 -0.406654)
			(end -0.8636 -0.406654)
			(stroke
				(width 0.1)
				(type default)
			)
			(layer "F.Fab")
		)
		(fp_line
			(start -1.1938 0.4064)
			(end -1.1938 -0.406654)
			(stroke
				(width 0.1)
				(type default)
			)
			(layer "F.Fab")
		)
		(fp_line
			(start -0.8636 -0.4572)
			(end 0.8636 -0.4572)
			(stroke
				(width 0.1)
				(type default)
			)
			(layer "F.Fab")
		)
		(fp_line
			(start -0.8636 -0.406654)
			(end -0.8636 -0.4572)
			(stroke
				(width 0.1)
				(type default)
			)
			(layer "F.Fab")
		)
		(fp_line
			(start -0.8636 0.4064)
			(end -1.1938 0.4064)
			(stroke
				(width 0.1)
				(type default)
			)
			(layer "F.Fab")
		)
		(fp_line
			(start -0.8636 0.4318)
			(end -0.8636 0.4064)
			(stroke
				(width 0.1)
				(type default)
			)
			(layer "F.Fab")
		)
		(fp_line
			(start -0.8636 0.4572)
			(end -0.8636 0.4318)
			(stroke
				(width 0.1)
				(type default)
			)
			(layer "F.Fab")
		)
		(fp_line
			(start 0.8636 -0.4572)
			(end 0.8636 -0.406654)
			(stroke
				(width 0.1)
				(type default)
			)
			(layer "F.Fab")
		)
		(fp_line
			(start 0.8636 -0.406654)
			(end 1.1938 -0.406654)
			(stroke
				(width 0.1)
				(type default)
			)
			(layer "F.Fab")
		)
		(fp_line
			(start 0.8636 0.4064)
			(end 0.8636 0.4572)
			(stroke
				(width 0.1)
				(type default)
			)
			(layer "F.Fab")
		)
		(fp_line
			(start 0.8636 0.4572)
			(end -0.8636 0.4572)
			(stroke
				(width 0.1)
				(type default)
			)
			(layer "F.Fab")
		)
		(fp_line
			(start 1.1938 -0.406654)
			(end 1.1938 0.4064)
			(stroke
				(width 0.1)
				(type default)
			)
			(layer "F.Fab")
		)
		(fp_line
			(start 1.1938 0.4064)
			(end 0.8636 0.4064)
			(stroke
				(width 0.1)
				(type default)
			)
			(layer "F.Fab")
		)
		(pad "1" smd rect
			(at -0.7366 0 270)
			(size 0.7112 0.8128)
			(layers "F.Cu" "F.Mask" "F.Paste")
			(net "P52V_HS1_SENSE_N_R2")
		)
		(pad "2" smd rect
			(at 0.7366 0 270)
			(size 0.7112 0.8128)
			(layers "F.Cu" "F.Mask" "F.Paste")
			(net "P52V_HS_4287_ADC_N")
		)
	)
	(footprint ""
		(layer "F.Cu")
		(at 204.089 -66.929 90)
		(property "Reference" "R59"
			(at 0 0 90)
			(layer "F.SilkS")
			(hide yes)
			(effects
				(font
					(size 1.27 1.27)
				)
			)
		)
		(property "Value" ""
			(at 0 0 90)
			(layer "F.Fab")
			(effects
				(font
					(size 1.27 1.27)
				)
			)
		)
		(duplicate_pad_numbers_are_jumpers no)
		(fp_line
			(start 0.7874 -0.4064)
			(end 0.7874 0.4064)
			(stroke
				(width 0.1524)
				(type default)
			)
			(layer "F.SilkS")
		)
		(fp_line
			(start -0.7874 -0.4064)
			(end 0.7874 -0.4064)
			(stroke
				(width 0.1524)
				(type default)
			)
			(layer "F.SilkS")
		)
		(fp_line
			(start 0.7874 0.4064)
			(end -0.7874 0.4064)
			(stroke
				(width 0.1524)
				(type default)
			)
			(layer "F.SilkS")
		)
		(fp_line
			(start -0.7874 0.4064)
			(end -0.7874 -0.4064)
			(stroke
				(width 0.1524)
				(type default)
			)
			(layer "F.SilkS")
		)
		(fp_line
			(start -0.12065 -0.305054)
			(end -0.12065 -0.2794)
			(stroke
				(width 0.1)
				(type default)
			)
			(layer "F.Fab")
		)
		(fp_line
			(start -0.67945 -0.305054)
			(end -0.12065 -0.305054)
			(stroke
				(width 0.1)
				(type default)
			)
			(layer "F.Fab")
		)
		(fp_line
			(start 0.67945 -0.3048)
			(end 0.67945 0.3048)
			(stroke
				(width 0.1)
				(type default)
			)
			(layer "F.Fab")
		)
		(fp_line
			(start 0.12065 -0.3048)
			(end 0.67945 -0.3048)
			(stroke
				(width 0.1)
				(type default)
			)
			(layer "F.Fab")
		)
		(fp_line
			(start 0.12065 -0.2794)
			(end 0.12065 -0.3048)
			(stroke
				(width 0.1)
				(type default)
			)
			(layer "F.Fab")
		)
		(fp_line
			(start -0.12065 -0.2794)
			(end 0.12065 -0.2794)
			(stroke
				(width 0.1)
				(type default)
			)
			(layer "F.Fab")
		)
		(fp_line
			(start 0.120396 0.2794)
			(end -0.12065 0.2794)
			(stroke
				(width 0.1)
				(type default)
			)
			(layer "F.Fab")
		)
		(fp_line
			(start -0.12065 0.2794)
			(end -0.12065 0.3048)
			(stroke
				(width 0.1)
				(type default)
			)
			(layer "F.Fab")
		)
		(fp_line
			(start 0.67945 0.3048)
			(end 0.120396 0.3048)
			(stroke
				(width 0.1)
				(type default)
			)
			(layer "F.Fab")
		)
		(fp_line
			(start 0.120396 0.3048)
			(end 0.120396 0.2794)
			(stroke
				(width 0.1)
				(type default)
			)
			(layer "F.Fab")
		)
		(fp_line
			(start -0.12065 0.3048)
			(end -0.67945 0.3048)
			(stroke
				(width 0.1)
				(type default)
			)
			(layer "F.Fab")
		)
		(fp_line
			(start -0.67945 0.3048)
			(end -0.67945 -0.305054)
			(stroke
				(width 0.1)
				(type default)
			)
			(layer "F.Fab")
		)
		(pad "1" smd circle
			(at -0.40005 0 90)
			(size 0 0)
			(layers "F.Cu" "F.Mask" "F.Paste")
			(net "P3V3_AUX")
		)
		(pad "2" smd circle
			(at 0.40005 0 90)
			(size 0 0)
			(layers "F.Cu" "F.Mask" "F.Paste")
			(net "LED_D3_R")
		)
	)
	(footprint ""
		(layer "F.Cu")
		(at 184.52846 -49.911)
		(property "Reference" "PC133"
			(at 0 0 0)
			(layer "F.SilkS")
			(hide yes)
			(effects
				(font
					(size 1.27 1.27)
				)
			)
		)
		(property "Value" ""
			(at 0 0 0)
			(layer "F.Fab")
			(effects
				(font
					(size 1.27 1.27)
				)
			)
		)
		(duplicate_pad_numbers_are_jumpers no)
		(fp_line
			(start -1.524 -0.762)
			(end 1.524 -0.762)
			(stroke
				(width 0.1524)
				(type default)
			)
			(layer "F.SilkS")
		)
		(fp_line
			(start -1.524 0.762)
			(end -1.524 -0.762)
			(stroke
				(width 0.1524)
				(type default)
			)
			(layer "F.SilkS")
		)
		(fp_line
			(start 1.524 -0.762)
			(end 1.524 0.762)
			(stroke
				(width 0.1524)
				(type default)
			)
			(layer "F.SilkS")
		)
		(fp_line
			(start 1.524 0.762)
			(end -1.524 0.762)
			(stroke
				(width 0.1524)
				(type default)
			)
			(layer "F.SilkS")
		)
		(fp_line
			(start -1.1049 -0.724916)
			(end -1.1049 0.724916)
			(stroke
				(width 0.1)
				(type default)
			)
			(layer "F.Fab")
		)
		(fp_line
			(start -1.1049 0.724916)
			(end 1.1049 0.724916)
			(stroke
				(width 0.1)
				(type default)
			)
			(layer "F.Fab")
		)
		(fp_line
			(start 1.1049 -0.724916)
			(end -1.1049 -0.724916)
			(stroke
				(width 0.1)
				(type default)
			)
			(layer "F.Fab")
		)
		(fp_line
			(start 1.1049 0.724916)
			(end 1.1049 -0.724916)
			(stroke
				(width 0.1)
				(type default)
			)
			(layer "F.Fab")
		)
		(pad "1" smd rect
			(at -0.889 0 180)
			(size 1.016 1.27)
			(layers "F.Cu" "F.Mask" "F.Paste")
			(net "P12V_BRICK")
		)
		(pad "2" smd rect
			(at 0.889 0 180)
			(size 1.016 1.27)
			(layers "F.Cu" "F.Mask" "F.Paste")
			(net "GND")
		)
	)
	(footprint ""
		(layer "F.Cu")
		(at 227.33 -95.504 -90)
		(property "Reference" "C33"
			(at 0 0 270)
			(layer "F.SilkS")
			(hide yes)
			(effects
				(font
					(size 1.27 1.27)
				)
			)
		)
		(property "Value" ""
			(at 0 0 270)
			(layer "F.Fab")
			(effects
				(font
					(size 1.27 1.27)
				)
			)
		)
		(duplicate_pad_numbers_are_jumpers no)
		(fp_line
			(start -2.2098 0.9398)
			(end -2.2098 -0.9398)
			(stroke
				(width 0.1524)
				(type default)
			)
			(layer "F.SilkS")
		)
		(fp_line
			(start 2.2098 0.9398)
			(end -2.2098 0.9398)
			(stroke
				(width 0.1524)
				(type default)
			)
			(layer "F.SilkS")
		)
		(fp_line
			(start -2.2098 -0.9398)
			(end 2.2098 -0.9398)
			(stroke
				(width 0.1524)
				(type default)
			)
			(layer "F.SilkS")
		)
		(fp_line
			(start 2.2098 -0.9398)
			(end 2.2098 0.9398)
			(stroke
				(width 0.1524)
				(type default)
			)
			(layer "F.SilkS")
		)
		(fp_line
			(start -1.700022 0.899922)
			(end -1.700022 -0.899922)
			(stroke
				(width 0.1)
				(type default)
			)
			(layer "F.Fab")
		)
		(fp_line
			(start 1.700022 0.899922)
			(end -1.700022 0.899922)
			(stroke
				(width 0.1)
				(type default)
			)
			(layer "F.Fab")
		)
		(fp_line
			(start -1.700022 -0.899922)
			(end 1.700022 -0.899922)
			(stroke
				(width 0.1)
				(type default)
			)
			(layer "F.Fab")
		)
		(fp_line
			(start 1.700022 -0.899922)
			(end 1.700022 0.899922)
			(stroke
				(width 0.1)
				(type default)
			)
			(layer "F.Fab")
		)
		(pad "1" smd rect
			(at -1.4732 0 90)
			(size 1.1684 1.5748)
			(layers "F.Cu" "F.Mask" "F.Paste")
			(net "P52V_HS")
		)
		(pad "2" smd rect
			(at 1.4732 0 90)
			(size 1.1684 1.5748)
			(layers "F.Cu" "F.Mask" "F.Paste")
			(net "GND")
		)
	)
	(footprint ""
		(layer "F.Cu")
		(at 79.375 -60.96)
		(property "Reference" "PC97"
			(at -1.524 -3.52933 0)
			(unlocked yes)
			(layer "F.SilkS")
			(effects
				(font
					(size 0.7874 0.5842)
					(thickness 0.1524)
				)
				(justify left)
			)
		)
		(property "Value" ""
			(at 0 0 0)
			(layer "F.Fab")
			(effects
				(font
					(size 1.27 1.27)
				)
			)
		)
		(duplicate_pad_numbers_are_jumpers no)
		(fp_line
			(start 5.2578 2.499868)
			(end -5.2578 2.499868)
			(stroke
				(width 0.1524)
				(type default)
			)
			(layer "F.SilkS")
		)
		(fp_circle
			(center 0 2.499868)
			(end 5.2578 2.499868)
			(stroke
				(width 0.1524)
				(type default)
			)
			(fill no)
			(layer "F.SilkS")
		)
		(fp_poly
			(pts
				(arc
					(start 5.2578 2.499868)
					(mid 0 7.757922)
					(end -5.2578 2.499868)
				)
			)
			(stroke
				(width 0)
				(type default)
			)
			(fill yes)
			(layer "F.SilkS")
		)
		(fp_circle
			(center 0 2.499868)
			(end 5.2578 2.499868)
			(stroke
				(width 0.1)
				(type default)
			)
			(fill no)
			(layer "F.Fab")
		)
		(pad "1" thru_hole rect
			(at 0 0 270)
			(size 1.524 1.524)
			(drill 1.016)
			(layers "*.Cu" "*.Mask")
			(remove_unused_layers no)
			(net "P12V_BRICK")
			(clearance 0)
			(padstack
				(mode front_inner_back)
				(layer "Inner"
					(shape circle)
					(size 1.524 1.524)
					(clearance 0)
				)
				(layer "B.Cu"
					(shape rect)
					(size 1.524 1.524)
					(clearance 0)
				)
			)
		)
		(pad "2" thru_hole circle
			(at 0 4.99999 270)
			(size 1.524 1.524)
			(drill 1.016)
			(layers "*.Cu" "*.Mask")
			(remove_unused_layers no)
			(net "GND")
			(clearance 0)
		)
	)
	(footprint ""
		(layer "F.Cu")
		(at 198.717916 -66.956686 90)
		(property "Reference" "R56"
			(at 0 0 90)
			(layer "F.SilkS")
			(hide yes)
			(effects
				(font
					(size 1.27 1.27)
				)
			)
		)
		(property "Value" ""
			(at 0 0 90)
			(layer "F.Fab")
			(effects
				(font
					(size 1.27 1.27)
				)
			)
		)
		(duplicate_pad_numbers_are_jumpers no)
		(fp_line
			(start 0.7874 -0.4064)
			(end 0.7874 0.4064)
			(stroke
				(width 0.1524)
				(type default)
			)
			(layer "F.SilkS")
		)
		(fp_line
			(start -0.7874 -0.4064)
			(end 0.7874 -0.4064)
			(stroke
				(width 0.1524)
				(type default)
			)
			(layer "F.SilkS")
		)
		(fp_line
			(start 0.7874 0.4064)
			(end -0.7874 0.4064)
			(stroke
				(width 0.1524)
				(type default)
			)
			(layer "F.SilkS")
		)
		(fp_line
			(start -0.7874 0.4064)
			(end -0.7874 -0.4064)
			(stroke
				(width 0.1524)
				(type default)
			)
			(layer "F.SilkS")
		)
		(fp_line
			(start -0.12065 -0.305054)
			(end -0.12065 -0.2794)
			(stroke
				(width 0.1)
				(type default)
			)
			(layer "F.Fab")
		)
		(fp_line
			(start -0.67945 -0.305054)
			(end -0.12065 -0.305054)
			(stroke
				(width 0.1)
				(type default)
			)
			(layer "F.Fab")
		)
		(fp_line
			(start 0.67945 -0.3048)
			(end 0.67945 0.3048)
			(stroke
				(width 0.1)
				(type default)
			)
			(layer "F.Fab")
		)
		(fp_line
			(start 0.12065 -0.3048)
			(end 0.67945 -0.3048)
			(stroke
				(width 0.1)
				(type default)
			)
			(layer "F.Fab")
		)
		(fp_line
			(start 0.12065 -0.2794)
			(end 0.12065 -0.3048)
			(stroke
				(width 0.1)
				(type default)
			)
			(layer "F.Fab")
		)
		(fp_line
			(start -0.12065 -0.2794)
			(end 0.12065 -0.2794)
			(stroke
				(width 0.1)
				(type default)
			)
			(layer "F.Fab")
		)
		(fp_line
			(start 0.120396 0.2794)
			(end -0.12065 0.2794)
			(stroke
				(width 0.1)
				(type default)
			)
			(layer "F.Fab")
		)
		(fp_line
			(start -0.12065 0.2794)
			(end -0.12065 0.3048)
			(stroke
				(width 0.1)
				(type default)
			)
			(layer "F.Fab")
		)
		(fp_line
			(start 0.67945 0.3048)
			(end 0.120396 0.3048)
			(stroke
				(width 0.1)
				(type default)
			)
			(layer "F.Fab")
		)
		(fp_line
			(start 0.120396 0.3048)
			(end 0.120396 0.2794)
			(stroke
				(width 0.1)
				(type default)
			)
			(layer "F.Fab")
		)
		(fp_line
			(start -0.12065 0.3048)
			(end -0.67945 0.3048)
			(stroke
				(width 0.1)
				(type default)
			)
			(layer "F.Fab")
		)
		(fp_line
			(start -0.67945 0.3048)
			(end -0.67945 -0.305054)
			(stroke
				(width 0.1)
				(type default)
			)
			(layer "F.Fab")
		)
		(pad "1" smd circle
			(at -0.40005 0 90)
			(size 0 0)
			(layers "F.Cu" "F.Mask" "F.Paste")
			(net "P12V_BRICK")
		)
		(pad "2" smd circle
			(at 0.40005 0 90)
			(size 0 0)
			(layers "F.Cu" "F.Mask" "F.Paste")
			(net "LED_D2_R1")
		)
	)
	(footprint ""
		(layer "F.Cu")
		(at 278.892 -47.752 180)
		(property "Reference" "PR21"
			(at 0 0 180)
			(layer "F.SilkS")
			(hide yes)
			(effects
				(font
					(size 1.27 1.27)
				)
			)
		)
		(property "Value" ""
			(at 0 0 180)
			(layer "F.Fab")
			(effects
				(font
					(size 1.27 1.27)
				)
			)
		)
		(duplicate_pad_numbers_are_jumpers no)
		(fp_line
			(start 0.7874 0.4064)
			(end -0.7874 0.4064)
			(stroke
				(width 0.1524)
				(type default)
			)
			(layer "F.SilkS")
		)
		(fp_line
			(start 0.7874 -0.4064)
			(end 0.7874 0.4064)
			(stroke
				(width 0.1524)
				(type default)
			)
			(layer "F.SilkS")
		)
		(fp_line
			(start -0.7874 0.4064)
			(end -0.7874 -0.4064)
			(stroke
				(width 0.1524)
				(type default)
			)
			(layer "F.SilkS")
		)
		(fp_line
			(start -0.7874 -0.4064)
			(end 0.7874 -0.4064)
			(stroke
				(width 0.1524)
				(type default)
			)
			(layer "F.SilkS")
		)
		(fp_line
			(start 0.67945 0.3048)
			(end 0.120396 0.3048)
			(stroke
				(width 0.1)
				(type default)
			)
			(layer "F.Fab")
		)
		(fp_line
			(start 0.67945 -0.3048)
			(end 0.67945 0.3048)
			(stroke
				(width 0.1)
				(type default)
			)
			(layer "F.Fab")
		)
		(fp_line
			(start 0.12065 -0.2794)
			(end 0.12065 -0.3048)
			(stroke
				(width 0.1)
				(type default)
			)
			(layer "F.Fab")
		)
		(fp_line
			(start 0.12065 -0.3048)
			(end 0.67945 -0.3048)
			(stroke
				(width 0.1)
				(type default)
			)
			(layer "F.Fab")
		)
		(fp_line
			(start 0.120396 0.3048)
			(end 0.120396 0.2794)
			(stroke
				(width 0.1)
				(type default)
			)
			(layer "F.Fab")
		)
		(fp_line
			(start 0.120396 0.2794)
			(end -0.12065 0.2794)
			(stroke
				(width 0.1)
				(type default)
			)
			(layer "F.Fab")
		)
		(fp_line
			(start -0.12065 0.3048)
			(end -0.67945 0.3048)
			(stroke
				(width 0.1)
				(type default)
			)
			(layer "F.Fab")
		)
		(fp_line
			(start -0.12065 0.2794)
			(end -0.12065 0.3048)
			(stroke
				(width 0.1)
				(type default)
			)
			(layer "F.Fab")
		)
		(fp_line
			(start -0.12065 -0.2794)
			(end 0.12065 -0.2794)
			(stroke
				(width 0.1)
				(type default)
			)
			(layer "F.Fab")
		)
		(fp_line
			(start -0.12065 -0.305054)
			(end -0.12065 -0.2794)
			(stroke
				(width 0.1)
				(type default)
			)
			(layer "F.Fab")
		)
		(fp_line
			(start -0.67945 0.3048)
			(end -0.67945 -0.305054)
			(stroke
				(width 0.1)
				(type default)
			)
			(layer "F.Fab")
		)
		(fp_line
			(start -0.67945 -0.305054)
			(end -0.12065 -0.305054)
			(stroke
				(width 0.1)
				(type default)
			)
			(layer "F.Fab")
		)
		(pad "1" smd circle
			(at -0.40005 0 180)
			(size 0 0)
			(layers "F.Cu" "F.Mask" "F.Paste")
			(net "P52V_HS1_ISET")
		)
		(pad "2" smd circle
			(at 0.40005 0 180)
			(size 0 0)
			(layers "F.Cu" "F.Mask" "F.Paste")
			(net "GND_FIELD_SIGNAL")
		)
	)
	(footprint ""
		(layer "F.Cu")
		(at 166.0398 -12.4968 90)
		(property "Reference" "PC568"
			(at 0 0 90)
			(layer "F.SilkS")
			(hide yes)
			(effects
				(font
					(size 1.27 1.27)
				)
			)
		)
		(property "Value" ""
			(at 0 0 90)
			(layer "F.Fab")
			(effects
				(font
					(size 1.27 1.27)
				)
			)
		)
		(duplicate_pad_numbers_are_jumpers no)
		(fp_line
			(start 1.524 -0.762)
			(end 1.524 0.762)
			(stroke
				(width 0.1524)
				(type default)
			)
			(layer "F.SilkS")
		)
		(fp_line
			(start -1.524 -0.762)
			(end 1.524 -0.762)
			(stroke
				(width 0.1524)
				(type default)
			)
			(layer "F.SilkS")
		)
		(fp_line
			(start 1.524 0.762)
			(end -1.524 0.762)
			(stroke
				(width 0.1524)
				(type default)
			)
			(layer "F.SilkS")
		)
		(fp_line
			(start -1.524 0.762)
			(end -1.524 -0.762)
			(stroke
				(width 0.1524)
				(type default)
			)
			(layer "F.SilkS")
		)
		(fp_line
			(start 1.1049 -0.724916)
			(end -1.1049 -0.724916)
			(stroke
				(width 0.1)
				(type default)
			)
			(layer "F.Fab")
		)
		(fp_line
			(start -1.1049 -0.724916)
			(end -1.1049 0.724916)
			(stroke
				(width 0.1)
				(type default)
			)
			(layer "F.Fab")
		)
		(fp_line
			(start 1.1049 0.724916)
			(end 1.1049 -0.724916)
			(stroke
				(width 0.1)
				(type default)
			)
			(layer "F.Fab")
		)
		(fp_line
			(start -1.1049 0.724916)
			(end 1.1049 0.724916)
			(stroke
				(width 0.1)
				(type default)
			)
			(layer "F.Fab")
		)
		(pad "1" smd rect
			(at -0.889 0 270)
			(size 1.016 1.27)
			(layers "F.Cu" "F.Mask" "F.Paste")
			(net "SW_P12V_FILT__P3V3_AUX")
		)
		(pad "2" smd rect
			(at 0.889 0 270)
			(size 1.016 1.27)
			(layers "F.Cu" "F.Mask" "F.Paste")
			(net "GND")
		)
	)
	(footprint ""
		(layer "F.Cu")
		(at 209.931 -91.5924)
		(property "Reference" "R60"
			(at 0 0 0)
			(layer "F.SilkS")
			(hide yes)
			(effects
				(font
					(size 1.27 1.27)
				)
			)
		)
		(property "Value" ""
			(at 0 0 0)
			(layer "F.Fab")
			(effects
				(font
					(size 1.27 1.27)
				)
			)
		)
		(duplicate_pad_numbers_are_jumpers no)
		(fp_line
			(start -2.234946 -0.9271)
			(end 2.234946 -0.9271)
			(stroke
				(width 0.1524)
				(type default)
			)
			(layer "F.SilkS")
		)
		(fp_line
			(start -2.234946 0.9271)
			(end -2.234946 -0.9271)
			(stroke
				(width 0.1524)
				(type default)
			)
			(layer "F.SilkS")
		)
		(fp_line
			(start 2.234946 -0.9271)
			(end 2.234946 0.9271)
			(stroke
				(width 0.1524)
				(type default)
			)
			(layer "F.SilkS")
		)
		(fp_line
			(start 2.234946 0.9271)
			(end -2.234946 0.9271)
			(stroke
				(width 0.1524)
				(type default)
			)
			(layer "F.SilkS")
		)
		(fp_line
			(start -1.575054 -0.824992)
			(end -1.575054 0.824992)
			(stroke
				(width 0.1)
				(type default)
			)
			(layer "F.Fab")
		)
		(fp_line
			(start -1.575054 0.824992)
			(end 1.575054 0.824992)
			(stroke
				(width 0.1)
				(type default)
			)
			(layer "F.Fab")
		)
		(fp_line
			(start 1.575054 -0.824992)
			(end -1.575054 -0.824992)
			(stroke
				(width 0.1)
				(type default)
			)
			(layer "F.Fab")
		)
		(fp_line
			(start 1.575054 0.824992)
			(end 1.575054 -0.824992)
			(stroke
				(width 0.1)
				(type default)
			)
			(layer "F.Fab")
		)
		(pad "1" smd rect
			(at -1.599946 0)
			(size 1.016 1.6002)
			(layers "F.Cu" "F.Mask" "F.Paste")
			(net "LED_D1_R2")
		)
		(pad "2" smd rect
			(at 1.599946 0)
			(size 1.016 1.6002)
			(layers "F.Cu" "F.Mask" "F.Paste")
			(net "LED_D1_R3")
		)
	)
	(footprint ""
		(layer "F.Cu")
		(at 301.602394 -86.8045)
		(property "Reference" "PR6955"
			(at 0 0 0)
			(layer "F.SilkS")
			(hide yes)
			(effects
				(font
					(size 1.27 1.27)
				)
			)
		)
		(property "Value" ""
			(at 0 0 0)
			(layer "F.Fab")
			(effects
				(font
					(size 1.27 1.27)
				)
			)
		)
		(duplicate_pad_numbers_are_jumpers no)
		(fp_line
			(start -1.2954 -0.5842)
			(end 1.2954 -0.5842)
			(stroke
				(width 0.1524)
				(type default)
			)
			(layer "F.SilkS")
		)
		(fp_line
			(start -1.2954 0.5842)
			(end -1.2954 -0.5842)
			(stroke
				(width 0.1524)
				(type default)
			)
			(layer "F.SilkS")
		)
		(fp_line
			(start 1.2954 -0.5842)
			(end 1.2954 0.5842)
			(stroke
				(width 0.1524)
				(type default)
			)
			(layer "F.SilkS")
		)
		(fp_line
			(start 1.2954 0.5842)
			(end -1.2954 0.5842)
			(stroke
				(width 0.1524)
				(type default)
			)
			(layer "F.SilkS")
		)
		(fp_line
			(start -1.1938 -0.406654)
			(end -0.8636 -0.406654)
			(stroke
				(width 0.1)
				(type default)
			)
			(layer "F.Fab")
		)
		(fp_line
			(start -1.1938 0.4064)
			(end -1.1938 -0.406654)
			(stroke
				(width 0.1)
				(type default)
			)
			(layer "F.Fab")
		)
		(fp_line
			(start -0.8636 -0.4572)
			(end 0.8636 -0.4572)
			(stroke
				(width 0.1)
				(type default)
			)
			(layer "F.Fab")
		)
		(fp_line
			(start -0.8636 -0.406654)
			(end -0.8636 -0.4572)
			(stroke
				(width 0.1)
				(type default)
			)
			(layer "F.Fab")
		)
		(fp_line
			(start -0.8636 0.4064)
			(end -1.1938 0.4064)
			(stroke
				(width 0.1)
				(type default)
			)
			(layer "F.Fab")
		)
		(fp_line
			(start -0.8636 0.4318)
			(end -0.8636 0.4064)
			(stroke
				(width 0.1)
				(type default)
			)
			(layer "F.Fab")
		)
		(fp_line
			(start -0.8636 0.4572)
			(end -0.8636 0.4318)
			(stroke
				(width 0.1)
				(type default)
			)
			(layer "F.Fab")
		)
		(fp_line
			(start 0.8636 -0.4572)
			(end 0.8636 -0.406654)
			(stroke
				(width 0.1)
				(type default)
			)
			(layer "F.Fab")
		)
		(fp_line
			(start 0.8636 -0.406654)
			(end 1.1938 -0.406654)
			(stroke
				(width 0.1)
				(type default)
			)
			(layer "F.Fab")
		)
		(fp_line
			(start 0.8636 0.4064)
			(end 0.8636 0.4572)
			(stroke
				(width 0.1)
				(type default)
			)
			(layer "F.Fab")
		)
		(fp_line
			(start 0.8636 0.4572)
			(end -0.8636 0.4572)
			(stroke
				(width 0.1)
				(type default)
			)
			(layer "F.Fab")
		)
		(fp_line
			(start 1.1938 -0.406654)
			(end 1.1938 0.4064)
			(stroke
				(width 0.1)
				(type default)
			)
			(layer "F.Fab")
		)
		(fp_line
			(start 1.1938 0.4064)
			(end 0.8636 0.4064)
			(stroke
				(width 0.1)
				(type default)
			)
			(layer "F.Fab")
		)
		(pad "1" smd rect
			(at -0.7366 0 270)
			(size 0.7112 0.8128)
			(layers "F.Cu" "F.Mask" "F.Paste")
			(net "P52V_HS_4287_S2P")
		)
		(pad "2" smd rect
			(at 0.7366 0 270)
			(size 0.7112 0.8128)
			(layers "F.Cu" "F.Mask" "F.Paste")
			(net "P52V_HS1_SENSE_P_R2")
		)
	)
	(footprint ""
		(layer "F.Cu")
		(at 256.794 -24.892 180)
		(property "Reference" "JP2"
			(at -1.4859 -2.32537 0)
			(unlocked yes)
			(layer "F.SilkS")
			(effects
				(font
					(size 0.7874 0.5842)
					(thickness 0.1524)
				)
				(justify left)
			)
		)
		(property "Value" ""
			(at 0 0 180)
			(layer "F.Fab")
			(effects
				(font
					(size 1.27 1.27)
				)
			)
		)
		(duplicate_pad_numbers_are_jumpers no)
		(fp_line
			(start 1.234948 6.415024)
			(end -1.234948 6.415024)
			(stroke
				(width 0.1524)
				(type default)
			)
			(layer "F.SilkS")
		)
		(fp_line
			(start 1.234948 -1.335024)
			(end 1.234948 6.415024)
			(stroke
				(width 0.1524)
				(type default)
			)
			(layer "F.SilkS")
		)
		(fp_line
			(start -1.234948 6.415024)
			(end -1.234948 -1.335024)
			(stroke
				(width 0.1524)
				(type default)
			)
			(layer "F.SilkS")
		)
		(fp_line
			(start -1.234948 -1.335024)
			(end 1.234948 -1.335024)
			(stroke
				(width 0.1524)
				(type default)
			)
			(layer "F.SilkS")
		)
		(fp_poly
			(pts
				(xy 0.508 -2.530348) (xy -0.508 -2.530348) (xy 0 -1.514348)
			)
			(stroke
				(width 0)
				(type default)
			)
			(fill yes)
			(layer "F.SilkS")
		)
		(fp_line
			(start 1.234948 6.415024)
			(end -1.234948 6.415024)
			(stroke
				(width 0.1)
				(type default)
			)
			(layer "F.Fab")
		)
		(fp_line
			(start 1.234948 -1.335024)
			(end 1.234948 6.415024)
			(stroke
				(width 0.1)
				(type default)
			)
			(layer "F.Fab")
		)
		(fp_line
			(start -1.234948 6.415024)
			(end -1.234948 -1.335024)
			(stroke
				(width 0.1)
				(type default)
			)
			(layer "F.Fab")
		)
		(fp_line
			(start -1.234948 -1.335024)
			(end 1.234948 -1.335024)
			(stroke
				(width 0.1)
				(type default)
			)
			(layer "F.Fab")
		)
		(fp_poly
			(pts
				(xy 0.508 -2.530348) (xy -0.508 -2.530348) (xy 0 -1.514348)
			)
			(stroke
				(width 0)
				(type default)
			)
			(fill yes)
			(layer "F.Fab")
		)
		(fp_text user "3"
			(at 0.10668 7.527798 270)
			(unlocked yes)
			(layer "F.SilkS")
			(effects
				(font
					(size 0.7874 0.5842)
					(thickness 0.1524)
				)
				(justify left)
			)
		)
		(fp_text user "3"
			(at -0.00127 6.640576 90)
			(unlocked yes)
			(layer "B.SilkS")
			(effects
				(font
					(size 0.7874 0.5842)
					(thickness 0.1524)
				)
				(justify left mirror)
			)
		)
		(fp_text user "1"
			(at -0.00127 -0.954024 90)
			(unlocked yes)
			(layer "B.SilkS")
			(effects
				(font
					(size 0.7874 0.5842)
					(thickness 0.1524)
				)
				(justify left mirror)
			)
		)
		(fp_text user "3"
			(at -0.00127 6.640576 90)
			(unlocked yes)
			(layer "B.Fab")
			(effects
				(font
					(size 0.7874 0.5842)
					(thickness 0.1524)
				)
				(justify left mirror)
			)
		)
		(fp_text user "1"
			(at -0.00127 -0.954024 90)
			(unlocked yes)
			(layer "B.Fab")
			(effects
				(font
					(size 0.7874 0.5842)
					(thickness 0.1524)
				)
				(justify left mirror)
			)
		)
		(fp_text user "3"
			(at -0.009652 6.5659 90)
			(unlocked yes)
			(layer "F.Fab")
			(effects
				(font
					(size 0.7874 0.5842)
					(thickness 0.1524)
				)
				(justify left)
			)
		)
		(pad "1" thru_hole rect
			(at 0 0 90)
			(size 1.6764 1.6764)
			(drill 1.1684)
			(layers "*.Cu" "*.Mask")
			(remove_unused_layers no)
			(net "SMB_P52V_VPDB_DEBUG_SDA")
			(clearance 0)
			(padstack
				(mode front_inner_back)
				(layer "Inner"
					(shape circle)
					(size 1.6764 1.6764)
					(clearance 0)
				)
				(layer "B.Cu"
					(shape rect)
					(size 1.6764 1.6764)
					(clearance 0)
				)
			)
		)
		(pad "2" thru_hole circle
			(at 0 2.54 90)
			(size 1.6764 1.6764)
			(drill 1.1684)
			(layers "*.Cu" "*.Mask")
			(remove_unused_layers no)
			(net "GND")
			(clearance 0)
		)
		(pad "3" thru_hole circle
			(at 0 5.08 90)
			(size 1.6764 1.6764)
			(drill 1.1684)
			(layers "*.Cu" "*.Mask")
			(remove_unused_layers no)
			(net "SMB_P52V_VPDB_DEBUG_SCL")
			(clearance 0)
		)
	)
	(footprint ""
		(layer "F.Cu")
		(at 279.010872 -38.571424)
		(property "Reference" "R147"
			(at 0 0 0)
			(layer "F.SilkS")
			(hide yes)
			(effects
				(font
					(size 1.27 1.27)
				)
			)
		)
		(property "Value" ""
			(at 0 0 0)
			(layer "F.Fab")
			(effects
				(font
					(size 1.27 1.27)
				)
			)
		)
		(duplicate_pad_numbers_are_jumpers no)
		(fp_line
			(start -0.7874 -0.4064)
			(end 0.7874 -0.4064)
			(stroke
				(width 0.1524)
				(type default)
			)
			(layer "F.SilkS")
		)
		(fp_line
			(start -0.7874 0.4064)
			(end -0.7874 -0.4064)
			(stroke
				(width 0.1524)
				(type default)
			)
			(layer "F.SilkS")
		)
		(fp_line
			(start 0.7874 -0.4064)
			(end 0.7874 0.4064)
			(stroke
				(width 0.1524)
				(type default)
			)
			(layer "F.SilkS")
		)
		(fp_line
			(start 0.7874 0.4064)
			(end -0.7874 0.4064)
			(stroke
				(width 0.1524)
				(type default)
			)
			(layer "F.SilkS")
		)
		(fp_line
			(start -0.67945 -0.305054)
			(end -0.12065 -0.305054)
			(stroke
				(width 0.1)
				(type default)
			)
			(layer "F.Fab")
		)
		(fp_line
			(start -0.67945 0.3048)
			(end -0.67945 -0.305054)
			(stroke
				(width 0.1)
				(type default)
			)
			(layer "F.Fab")
		)
		(fp_line
			(start -0.12065 -0.305054)
			(end -0.12065 -0.2794)
			(stroke
				(width 0.1)
				(type default)
			)
			(layer "F.Fab")
		)
		(fp_line
			(start -0.12065 -0.2794)
			(end 0.12065 -0.2794)
			(stroke
				(width 0.1)
				(type default)
			)
			(layer "F.Fab")
		)
		(fp_line
			(start -0.12065 0.2794)
			(end -0.12065 0.3048)
			(stroke
				(width 0.1)
				(type default)
			)
			(layer "F.Fab")
		)
		(fp_line
			(start -0.12065 0.3048)
			(end -0.67945 0.3048)
			(stroke
				(width 0.1)
				(type default)
			)
			(layer "F.Fab")
		)
		(fp_line
			(start 0.120396 0.2794)
			(end -0.12065 0.2794)
			(stroke
				(width 0.1)
				(type default)
			)
			(layer "F.Fab")
		)
		(fp_line
			(start 0.120396 0.3048)
			(end 0.120396 0.2794)
			(stroke
				(width 0.1)
				(type default)
			)
			(layer "F.Fab")
		)
		(fp_line
			(start 0.12065 -0.3048)
			(end 0.67945 -0.3048)
			(stroke
				(width 0.1)
				(type default)
			)
			(layer "F.Fab")
		)
		(fp_line
			(start 0.12065 -0.2794)
			(end 0.12065 -0.3048)
			(stroke
				(width 0.1)
				(type default)
			)
			(layer "F.Fab")
		)
		(fp_line
			(start 0.67945 -0.3048)
			(end 0.67945 0.3048)
			(stroke
				(width 0.1)
				(type default)
			)
			(layer "F.Fab")
		)
		(fp_line
			(start 0.67945 0.3048)
			(end 0.120396 0.3048)
			(stroke
				(width 0.1)
				(type default)
			)
			(layer "F.Fab")
		)
		(pad "1" smd circle
			(at -0.40005 0)
			(size 0 0)
			(layers "F.Cu" "F.Mask" "F.Paste")
			(net "P3V3_AUX")
		)
		(pad "2" smd circle
			(at 0.40005 0)
			(size 0 0)
			(layers "F.Cu" "F.Mask" "F.Paste")
			(net "SMB_P52V_HSC_SDA")
		)
	)
	(footprint ""
		(layer "F.Cu")
		(at 131.191 -60.96)
		(property "Reference" "PC69"
			(at -1.651 -3.52933 0)
			(unlocked yes)
			(layer "F.SilkS")
			(effects
				(font
					(size 0.7874 0.5842)
					(thickness 0.1524)
				)
				(justify left)
			)
		)
		(property "Value" ""
			(at 0 0 0)
			(layer "F.Fab")
			(effects
				(font
					(size 1.27 1.27)
				)
			)
		)
		(duplicate_pad_numbers_are_jumpers no)
		(fp_line
			(start 5.2578 2.499868)
			(end -5.2578 2.499868)
			(stroke
				(width 0.1524)
				(type default)
			)
			(layer "F.SilkS")
		)
		(fp_circle
			(center 0 2.499868)
			(end 5.2578 2.499868)
			(stroke
				(width 0.1524)
				(type default)
			)
			(fill no)
			(layer "F.SilkS")
		)
		(fp_poly
			(pts
				(arc
					(start 5.2578 2.499868)
					(mid 0 7.757922)
					(end -5.2578 2.499868)
				)
			)
			(stroke
				(width 0)
				(type default)
			)
			(fill yes)
			(layer "F.SilkS")
		)
		(fp_circle
			(center 0 2.499868)
			(end 5.2578 2.499868)
			(stroke
				(width 0.1)
				(type default)
			)
			(fill no)
			(layer "F.Fab")
		)
		(pad "1" thru_hole rect
			(at 0 0 270)
			(size 1.524 1.524)
			(drill 1.016)
			(layers "*.Cu" "*.Mask")
			(remove_unused_layers no)
			(net "P12V_BRICK")
			(clearance 0)
			(padstack
				(mode front_inner_back)
				(layer "Inner"
					(shape circle)
					(size 1.524 1.524)
					(clearance 0)
				)
				(layer "B.Cu"
					(shape rect)
					(size 1.524 1.524)
					(clearance 0)
				)
			)
		)
		(pad "2" thru_hole circle
			(at 0 4.99999 270)
			(size 1.524 1.524)
			(drill 1.016)
			(layers "*.Cu" "*.Mask")
			(remove_unused_layers no)
			(net "GND")
			(clearance 0)
		)
	)
	(footprint ""
		(layer "F.Cu")
		(at 270.383 -92.085668 90)
		(property "Reference" "PR14"
			(at 0 0 90)
			(layer "F.SilkS")
			(hide yes)
			(effects
				(font
					(size 1.27 1.27)
				)
			)
		)
		(property "Value" ""
			(at 0 0 90)
			(layer "F.Fab")
			(effects
				(font
					(size 1.27 1.27)
				)
			)
		)
		(duplicate_pad_numbers_are_jumpers no)
		(fp_line
			(start 1.2954 -0.5842)
			(end 1.2954 0.5842)
			(stroke
				(width 0.1524)
				(type default)
			)
			(layer "F.SilkS")
		)
		(fp_line
			(start -1.2954 -0.5842)
			(end 1.2954 -0.5842)
			(stroke
				(width 0.1524)
				(type default)
			)
			(layer "F.SilkS")
		)
		(fp_line
			(start 1.2954 0.5842)
			(end -1.2954 0.5842)
			(stroke
				(width 0.1524)
				(type default)
			)
			(layer "F.SilkS")
		)
		(fp_line
			(start -1.2954 0.5842)
			(end -1.2954 -0.5842)
			(stroke
				(width 0.1524)
				(type default)
			)
			(layer "F.SilkS")
		)
		(fp_line
			(start 0.8636 -0.4572)
			(end 0.8636 -0.406654)
			(stroke
				(width 0.1)
				(type default)
			)
			(layer "F.Fab")
		)
		(fp_line
			(start -0.8636 -0.4572)
			(end 0.8636 -0.4572)
			(stroke
				(width 0.1)
				(type default)
			)
			(layer "F.Fab")
		)
		(fp_line
			(start 1.1938 -0.406654)
			(end 1.1938 0.4064)
			(stroke
				(width 0.1)
				(type default)
			)
			(layer "F.Fab")
		)
		(fp_line
			(start 0.8636 -0.406654)
			(end 1.1938 -0.406654)
			(stroke
				(width 0.1)
				(type default)
			)
			(layer "F.Fab")
		)
		(fp_line
			(start -0.8636 -0.406654)
			(end -0.8636 -0.4572)
			(stroke
				(width 0.1)
				(type default)
			)
			(layer "F.Fab")
		)
		(fp_line
			(start -1.1938 -0.406654)
			(end -0.8636 -0.406654)
			(stroke
				(width 0.1)
				(type default)
			)
			(layer "F.Fab")
		)
		(fp_line
			(start 1.1938 0.4064)
			(end 0.8636 0.4064)
			(stroke
				(width 0.1)
				(type default)
			)
			(layer "F.Fab")
		)
		(fp_line
			(start 0.8636 0.4064)
			(end 0.8636 0.4572)
			(stroke
				(width 0.1)
				(type default)
			)
			(layer "F.Fab")
		)
		(fp_line
			(start -0.8636 0.4064)
			(end -1.1938 0.4064)
			(stroke
				(width 0.1)
				(type default)
			)
			(layer "F.Fab")
		)
		(fp_line
			(start -1.1938 0.4064)
			(end -1.1938 -0.406654)
			(stroke
				(width 0.1)
				(type default)
			)
			(layer "F.Fab")
		)
		(fp_line
			(start -0.8636 0.4318)
			(end -0.8636 0.4064)
			(stroke
				(width 0.1)
				(type default)
			)
			(layer "F.Fab")
		)
		(fp_line
			(start 0.8636 0.4572)
			(end -0.8636 0.4572)
			(stroke
				(width 0.1)
				(type default)
			)
			(layer "F.Fab")
		)
		(fp_line
			(start -0.8636 0.4572)
			(end -0.8636 0.4318)
			(stroke
				(width 0.1)
				(type default)
			)
			(layer "F.Fab")
		)
		(pad "1" smd rect
			(at -0.7366 0)
			(size 0.7112 0.8128)
			(layers "F.Cu" "F.Mask" "F.Paste")
			(net "P52V_HS1_GATE2_R")
		)
		(pad "2" smd rect
			(at 0.7366 0)
			(size 0.7112 0.8128)
			(layers "F.Cu" "F.Mask" "F.Paste")
			(net "P52V_HS1_GATE4")
		)
	)
	(footprint ""
		(layer "F.Cu")
		(at 151.765 -49.911)
		(property "Reference" "PC39"
			(at 0 0 0)
			(layer "F.SilkS")
			(hide yes)
			(effects
				(font
					(size 1.27 1.27)
				)
			)
		)
		(property "Value" ""
			(at 0 0 0)
			(layer "F.Fab")
			(effects
				(font
					(size 1.27 1.27)
				)
			)
		)
		(duplicate_pad_numbers_are_jumpers no)
		(fp_line
			(start -1.524 -0.762)
			(end 1.524 -0.762)
			(stroke
				(width 0.1524)
				(type default)
			)
			(layer "F.SilkS")
		)
		(fp_line
			(start -1.524 0.762)
			(end -1.524 -0.762)
			(stroke
				(width 0.1524)
				(type default)
			)
			(layer "F.SilkS")
		)
		(fp_line
			(start 1.524 -0.762)
			(end 1.524 0.762)
			(stroke
				(width 0.1524)
				(type default)
			)
			(layer "F.SilkS")
		)
		(fp_line
			(start 1.524 0.762)
			(end -1.524 0.762)
			(stroke
				(width 0.1524)
				(type default)
			)
			(layer "F.SilkS")
		)
		(fp_line
			(start -1.1049 -0.724916)
			(end -1.1049 0.724916)
			(stroke
				(width 0.1)
				(type default)
			)
			(layer "F.Fab")
		)
		(fp_line
			(start -1.1049 0.724916)
			(end 1.1049 0.724916)
			(stroke
				(width 0.1)
				(type default)
			)
			(layer "F.Fab")
		)
		(fp_line
			(start 1.1049 -0.724916)
			(end -1.1049 -0.724916)
			(stroke
				(width 0.1)
				(type default)
			)
			(layer "F.Fab")
		)
		(fp_line
			(start 1.1049 0.724916)
			(end 1.1049 -0.724916)
			(stroke
				(width 0.1)
				(type default)
			)
			(layer "F.Fab")
		)
		(pad "1" smd rect
			(at -0.889 0 180)
			(size 1.016 1.27)
			(layers "F.Cu" "F.Mask" "F.Paste")
			(net "P12V_BRICK")
		)
		(pad "2" smd rect
			(at 0.889 0 180)
			(size 1.016 1.27)
			(layers "F.Cu" "F.Mask" "F.Paste")
			(net "GND")
		)
	)
	(footprint ""
		(layer "F.Cu")
		(at 73.66 -49.911)
		(property "Reference" "PC95"
			(at 0 0 0)
			(layer "F.SilkS")
			(hide yes)
			(effects
				(font
					(size 1.27 1.27)
				)
			)
		)
		(property "Value" ""
			(at 0 0 0)
			(layer "F.Fab")
			(effects
				(font
					(size 1.27 1.27)
				)
			)
		)
		(duplicate_pad_numbers_are_jumpers no)
		(fp_line
			(start -1.524 -0.762)
			(end 1.524 -0.762)
			(stroke
				(width 0.1524)
				(type default)
			)
			(layer "F.SilkS")
		)
		(fp_line
			(start -1.524 0.762)
			(end -1.524 -0.762)
			(stroke
				(width 0.1524)
				(type default)
			)
			(layer "F.SilkS")
		)
		(fp_line
			(start 1.524 -0.762)
			(end 1.524 0.762)
			(stroke
				(width 0.1524)
				(type default)
			)
			(layer "F.SilkS")
		)
		(fp_line
			(start 1.524 0.762)
			(end -1.524 0.762)
			(stroke
				(width 0.1524)
				(type default)
			)
			(layer "F.SilkS")
		)
		(fp_line
			(start -1.1049 -0.724916)
			(end -1.1049 0.724916)
			(stroke
				(width 0.1)
				(type default)
			)
			(layer "F.Fab")
		)
		(fp_line
			(start -1.1049 0.724916)
			(end 1.1049 0.724916)
			(stroke
				(width 0.1)
				(type default)
			)
			(layer "F.Fab")
		)
		(fp_line
			(start 1.1049 -0.724916)
			(end -1.1049 -0.724916)
			(stroke
				(width 0.1)
				(type default)
			)
			(layer "F.Fab")
		)
		(fp_line
			(start 1.1049 0.724916)
			(end 1.1049 -0.724916)
			(stroke
				(width 0.1)
				(type default)
			)
			(layer "F.Fab")
		)
		(pad "1" smd rect
			(at -0.889 0 180)
			(size 1.016 1.27)
			(layers "F.Cu" "F.Mask" "F.Paste")
			(net "P12V_BRICK")
		)
		(pad "2" smd rect
			(at 0.889 0 180)
			(size 1.016 1.27)
			(layers "F.Cu" "F.Mask" "F.Paste")
			(net "GND")
		)
	)
	(footprint ""
		(layer "F.Cu")
		(at 75.375008 -40.55999 90)
		(property "Reference" "J2"
			(at 7.41934 63.435992 0)
			(unlocked yes)
			(layer "F.SilkS")
			(effects
				(font
					(size 0.7874 0.5842)
					(thickness 0.1524)
				)
				(justify left)
			)
		)
		(property "Value" ""
			(at 0 0 90)
			(layer "F.Fab")
			(effects
				(font
					(size 1.27 1.27)
				)
			)
		)
		(duplicate_pad_numbers_are_jumpers no)
		(fp_line
			(start 6.480048 -17.85493)
			(end 6.480048 64.84493)
			(stroke
				(width 0.1524)
				(type default)
			)
			(layer "F.SilkS")
		)
		(fp_line
			(start -14.100048 -17.85493)
			(end 6.480048 -17.85493)
			(stroke
				(width 0.1524)
				(type default)
			)
			(layer "F.SilkS")
		)
		(fp_line
			(start 3.480054 -14.854936)
			(end 3.480054 61.844936)
			(stroke
				(width 0.1524)
				(type default)
			)
			(layer "F.SilkS")
		)
		(fp_line
			(start -5.6769 -14.854936)
			(end 3.480054 -14.854936)
			(stroke
				(width 0.1524)
				(type default)
			)
			(layer "F.SilkS")
		)
		(fp_line
			(start -11.100054 -14.854936)
			(end -9.5631 -14.854936)
			(stroke
				(width 0.1524)
				(type default)
			)
			(layer "F.SilkS")
		)
		(fp_line
			(start 3.480054 61.844936)
			(end -5.6769 61.844936)
			(stroke
				(width 0.1524)
				(type default)
			)
			(layer "F.SilkS")
		)
		(fp_line
			(start -9.5504 61.844936)
			(end -11.100054 61.844936)
			(stroke
				(width 0.1524)
				(type default)
			)
			(layer "F.SilkS")
		)
		(fp_line
			(start -11.100054 61.844936)
			(end -11.100054 -14.854936)
			(stroke
				(width 0.1524)
				(type default)
			)
			(layer "F.SilkS")
		)
		(fp_line
			(start 6.480048 64.84493)
			(end -14.100048 64.84493)
			(stroke
				(width 0.1524)
				(type default)
			)
			(layer "F.SilkS")
		)
		(fp_line
			(start -14.100048 64.84493)
			(end -14.100048 -17.85493)
			(stroke
				(width 0.1524)
				(type default)
			)
			(layer "F.SilkS")
		)
		(fp_poly
			(pts
				(xy 5.0038 -0.508) (xy 5.0038 0.508) (xy 3.9878 0)
			)
			(stroke
				(width 0)
				(type default)
			)
			(fill yes)
			(layer "F.SilkS")
		)
		(fp_line
			(start 6.480048 -17.85493)
			(end 6.480048 64.84493)
			(stroke
				(width 0.1524)
				(type default)
			)
			(layer "B.SilkS")
		)
		(fp_line
			(start -14.100048 -17.85493)
			(end 6.480048 -17.85493)
			(stroke
				(width 0.1524)
				(type default)
			)
			(layer "B.SilkS")
		)
		(fp_line
			(start 6.480048 64.84493)
			(end -14.100048 64.84493)
			(stroke
				(width 0.1524)
				(type default)
			)
			(layer "B.SilkS")
		)
		(fp_line
			(start -14.100048 64.84493)
			(end -14.100048 -17.85493)
			(stroke
				(width 0.1524)
				(type default)
			)
			(layer "B.SilkS")
		)
		(fp_line
			(start 6.480048 -17.85493)
			(end 6.480048 64.84493)
			(stroke
				(width 0.1)
				(type default)
			)
			(layer "B.Fab")
		)
		(fp_line
			(start -14.100048 -17.85493)
			(end 6.480048 -17.85493)
			(stroke
				(width 0.1)
				(type default)
			)
			(layer "B.Fab")
		)
		(fp_line
			(start 6.480048 64.84493)
			(end -14.100048 64.84493)
			(stroke
				(width 0.1)
				(type default)
			)
			(layer "B.Fab")
		)
		(fp_line
			(start -14.100048 64.84493)
			(end -14.100048 -17.85493)
			(stroke
				(width 0.1)
				(type default)
			)
			(layer "B.Fab")
		)
		(fp_line
			(start 3.480054 -14.854936)
			(end 3.480054 61.844936)
			(stroke
				(width 0.1)
				(type default)
			)
			(layer "F.Fab")
		)
		(fp_line
			(start -11.100054 -14.854936)
			(end 3.480054 -14.854936)
			(stroke
				(width 0.1)
				(type default)
			)
			(layer "F.Fab")
		)
		(fp_line
			(start 3.480054 61.844936)
			(end -11.100054 61.844936)
			(stroke
				(width 0.1)
				(type default)
			)
			(layer "F.Fab")
		)
		(fp_line
			(start -11.100054 61.844936)
			(end -11.100054 -14.854936)
			(stroke
				(width 0.1)
				(type default)
			)
			(layer "F.Fab")
		)
		(fp_poly
			(pts
				(xy 5.0038 -0.508) (xy 5.0038 0.508) (xy 3.9878 0)
			)
			(stroke
				(width 0)
				(type default)
			)
			(fill yes)
			(layer "F.Fab")
		)
		(fp_text user "PRESS-FIT"
			(at 4.98475 15.1257 0)
			(unlocked yes)
			(layer "F.SilkS")
			(effects
				(font
					(size 1.905 1.4224)
					(thickness 0.1524)
				)
				(justify left)
			)
		)
		(fp_text user "PRESS-FIT"
			(at 5.01015 31.7881 0)
			(unlocked yes)
			(layer "B.SilkS")
			(effects
				(font
					(size 1.905 1.4224)
					(thickness 0.1524)
				)
				(justify left mirror)
			)
		)
		(fp_text user "PRESS-FIT"
			(at 5.01015 31.7881 0)
			(unlocked yes)
			(layer "B.Fab")
			(effects
				(font
					(size 1.905 1.4224)
					(thickness 0.1524)
				)
				(justify left mirror)
			)
		)
		(fp_text user "PRESS-FIT"
			(at 4.98475 15.1257 0)
			(unlocked yes)
			(layer "F.Fab")
			(effects
				(font
					(size 1.905 1.4224)
					(thickness 0.1524)
				)
				(justify left)
			)
		)
		(pad "" np_thru_hole circle
			(at -7.62 -12.065)
			(size 0 0)
			(drill 3.2004)
			(layers "*.Cu" "*.Mask")
			(clearance 0)
		)
		(pad "" np_thru_hole circle
			(at -7.62 59.055)
			(size 0 0)
			(drill 3.2004)
			(layers "*.Cu" "*.Mask")
			(clearance 0)
		)
		(pad "P1_1" thru_hole rect
			(at 0 0)
			(size 1.52781 1.52781)
			(drill 1.01981)
			(layers "*.Cu" "*.Mask")
			(remove_unused_layers no)
			(net "GND")
			(clearance 0)
			(padstack
				(mode front_inner_back)
				(layer "Inner"
					(shape circle)
					(size 1.52781 1.52781)
					(clearance 0)
				)
				(layer "B.Cu"
					(shape rect)
					(size 1.52781 1.52781)
					(clearance 0)
				)
			)
		)
		(pad "P1_2" thru_hole circle
			(at -2.54 0)
			(size 1.52781 1.52781)
			(drill 1.01981)
			(layers "*.Cu" "*.Mask")
			(remove_unused_layers no)
			(net "GND")
			(clearance 0)
		)
		(pad "P1_3" thru_hole circle
			(at -5.08 0)
			(size 1.52781 1.52781)
			(drill 1.01981)
			(layers "*.Cu" "*.Mask")
			(remove_unused_layers no)
			(net "GND")
			(clearance 0)
		)
		(pad "P1_4" thru_hole circle
			(at -7.62 0)
			(size 1.52781 1.52781)
			(drill 1.01981)
			(layers "*.Cu" "*.Mask")
			(remove_unused_layers no)
			(net "GND")
			(clearance 0)
		)
		(pad "P1_5" thru_hole circle
			(at 0 2.54)
			(size 1.52781 1.52781)
			(drill 1.01981)
			(layers "*.Cu" "*.Mask")
			(remove_unused_layers no)
			(net "GND")
			(clearance 0)
		)
		(pad "P1_6" thru_hole circle
			(at -2.54 2.54)
			(size 1.52781 1.52781)
			(drill 1.01981)
			(layers "*.Cu" "*.Mask")
			(remove_unused_layers no)
			(net "GND")
			(clearance 0)
		)
		(pad "P1_7" thru_hole circle
			(at -5.08 2.54)
			(size 1.52781 1.52781)
			(drill 1.01981)
			(layers "*.Cu" "*.Mask")
			(remove_unused_layers no)
			(net "GND")
			(clearance 0)
		)
		(pad "P1_8" thru_hole circle
			(at -7.62 2.54)
			(size 1.52781 1.52781)
			(drill 1.01981)
			(layers "*.Cu" "*.Mask")
			(remove_unused_layers no)
			(net "GND")
			(clearance 0)
		)
		(pad "P2_1" thru_hole circle
			(at 0 8.89)
			(size 1.52781 1.52781)
			(drill 1.01981)
			(layers "*.Cu" "*.Mask")
			(remove_unused_layers no)
			(net "GND")
			(clearance 0)
		)
		(pad "P2_2" thru_hole circle
			(at -2.54 8.89)
			(size 1.52781 1.52781)
			(drill 1.01981)
			(layers "*.Cu" "*.Mask")
			(remove_unused_layers no)
			(net "GND")
			(clearance 0)
		)
		(pad "P2_3" thru_hole circle
			(at -5.08 8.89)
			(size 1.52781 1.52781)
			(drill 1.01981)
			(layers "*.Cu" "*.Mask")
			(remove_unused_layers no)
			(net "GND")
			(clearance 0)
		)
		(pad "P2_4" thru_hole circle
			(at -7.62 8.89)
			(size 1.52781 1.52781)
			(drill 1.01981)
			(layers "*.Cu" "*.Mask")
			(remove_unused_layers no)
			(net "GND")
			(clearance 0)
		)
		(pad "P2_5" thru_hole circle
			(at 0 11.43)
			(size 1.52781 1.52781)
			(drill 1.01981)
			(layers "*.Cu" "*.Mask")
			(remove_unused_layers no)
			(net "GND")
			(clearance 0)
		)
		(pad "P2_6" thru_hole circle
			(at -2.54 11.43)
			(size 1.52781 1.52781)
			(drill 1.01981)
			(layers "*.Cu" "*.Mask")
			(remove_unused_layers no)
			(net "GND")
			(clearance 0)
		)
		(pad "P2_7" thru_hole circle
			(at -5.08 11.43)
			(size 1.52781 1.52781)
			(drill 1.01981)
			(layers "*.Cu" "*.Mask")
			(remove_unused_layers no)
			(net "GND")
			(clearance 0)
		)
		(pad "P2_8" thru_hole circle
			(at -7.62 11.43)
			(size 1.52781 1.52781)
			(drill 1.01981)
			(layers "*.Cu" "*.Mask")
			(remove_unused_layers no)
			(net "GND")
			(clearance 0)
		)
		(pad "P3_1" thru_hole circle
			(at 0 17.78)
			(size 1.52781 1.52781)
			(drill 1.01981)
			(layers "*.Cu" "*.Mask")
			(remove_unused_layers no)
			(net "GND")
			(clearance 0)
		)
		(pad "P3_2" thru_hole circle
			(at -2.54 17.78)
			(size 1.52781 1.52781)
			(drill 1.01981)
			(layers "*.Cu" "*.Mask")
			(remove_unused_layers no)
			(net "GND")
			(clearance 0)
		)
		(pad "P3_3" thru_hole circle
			(at -5.08 17.78)
			(size 1.52781 1.52781)
			(drill 1.01981)
			(layers "*.Cu" "*.Mask")
			(remove_unused_layers no)
			(net "GND")
			(clearance 0)
		)
		(pad "P3_4" thru_hole circle
			(at -7.62 17.78)
			(size 1.52781 1.52781)
			(drill 1.01981)
			(layers "*.Cu" "*.Mask")
			(remove_unused_layers no)
			(net "GND")
			(clearance 0)
		)
		(pad "P3_5" thru_hole circle
			(at 0 20.32)
			(size 1.52781 1.52781)
			(drill 1.01981)
			(layers "*.Cu" "*.Mask")
			(remove_unused_layers no)
			(net "GND")
			(clearance 0)
		)
		(pad "P3_6" thru_hole circle
			(at -2.54 20.32)
			(size 1.52781 1.52781)
			(drill 1.01981)
			(layers "*.Cu" "*.Mask")
			(remove_unused_layers no)
			(net "GND")
			(clearance 0)
		)
		(pad "P3_7" thru_hole circle
			(at -5.08 20.32)
			(size 1.52781 1.52781)
			(drill 1.01981)
			(layers "*.Cu" "*.Mask")
			(remove_unused_layers no)
			(net "GND")
			(clearance 0)
		)
		(pad "P3_8" thru_hole circle
			(at -7.62 20.32)
			(size 1.52781 1.52781)
			(drill 1.01981)
			(layers "*.Cu" "*.Mask")
			(remove_unused_layers no)
			(net "GND")
			(clearance 0)
		)
		(pad "P4_1" thru_hole circle
			(at 0 26.67)
			(size 1.52781 1.52781)
			(drill 1.01981)
			(layers "*.Cu" "*.Mask")
			(remove_unused_layers no)
			(net "P12V_BRICK")
			(clearance 0)
		)
		(pad "P4_2" thru_hole circle
			(at -2.54 26.67)
			(size 1.52781 1.52781)
			(drill 1.01981)
			(layers "*.Cu" "*.Mask")
			(remove_unused_layers no)
			(net "P12V_BRICK")
			(clearance 0)
		)
		(pad "P4_3" thru_hole circle
			(at -5.08 26.67)
			(size 1.52781 1.52781)
			(drill 1.01981)
			(layers "*.Cu" "*.Mask")
			(remove_unused_layers no)
			(net "P12V_BRICK")
			(clearance 0)
		)
		(pad "P4_4" thru_hole circle
			(at -7.62 26.67)
			(size 1.52781 1.52781)
			(drill 1.01981)
			(layers "*.Cu" "*.Mask")
			(remove_unused_layers no)
			(net "P12V_BRICK")
			(clearance 0)
		)
		(pad "P4_5" thru_hole circle
			(at 0 29.21)
			(size 1.52781 1.52781)
			(drill 1.01981)
			(layers "*.Cu" "*.Mask")
			(remove_unused_layers no)
			(net "P12V_BRICK")
			(clearance 0)
		)
		(pad "P4_6" thru_hole circle
			(at -2.54 29.21)
			(size 1.52781 1.52781)
			(drill 1.01981)
			(layers "*.Cu" "*.Mask")
			(remove_unused_layers no)
			(net "P12V_BRICK")
			(clearance 0)
		)
		(pad "P4_7" thru_hole circle
			(at -5.08 29.21)
			(size 1.52781 1.52781)
			(drill 1.01981)
			(layers "*.Cu" "*.Mask")
			(remove_unused_layers no)
			(net "P12V_BRICK")
			(clearance 0)
		)
		(pad "P4_8" thru_hole circle
			(at -7.62 29.21)
			(size 1.52781 1.52781)
			(drill 1.01981)
			(layers "*.Cu" "*.Mask")
			(remove_unused_layers no)
			(net "P12V_BRICK")
			(clearance 0)
		)
		(pad "P5_1" thru_hole circle
			(at 0 35.56)
			(size 1.52781 1.52781)
			(drill 1.01981)
			(layers "*.Cu" "*.Mask")
			(remove_unused_layers no)
			(net "P12V_BRICK")
			(clearance 0)
		)
		(pad "P5_2" thru_hole circle
			(at -2.54 35.56)
			(size 1.52781 1.52781)
			(drill 1.01981)
			(layers "*.Cu" "*.Mask")
			(remove_unused_layers no)
			(net "P12V_BRICK")
			(clearance 0)
		)
		(pad "P5_3" thru_hole circle
			(at -5.08 35.56)
			(size 1.52781 1.52781)
			(drill 1.01981)
			(layers "*.Cu" "*.Mask")
			(remove_unused_layers no)
			(net "P12V_BRICK")
			(clearance 0)
		)
		(pad "P5_4" thru_hole circle
			(at -7.62 35.56)
			(size 1.52781 1.52781)
			(drill 1.01981)
			(layers "*.Cu" "*.Mask")
			(remove_unused_layers no)
			(net "P12V_BRICK")
			(clearance 0)
		)
		(pad "P5_5" thru_hole circle
			(at 0 38.1)
			(size 1.52781 1.52781)
			(drill 1.01981)
			(layers "*.Cu" "*.Mask")
			(remove_unused_layers no)
			(net "P12V_BRICK")
			(clearance 0)
		)
		(pad "P5_6" thru_hole circle
			(at -2.54 38.1)
			(size 1.52781 1.52781)
			(drill 1.01981)
			(layers "*.Cu" "*.Mask")
			(remove_unused_layers no)
			(net "P12V_BRICK")
			(clearance 0)
		)
		(pad "P5_7" thru_hole circle
			(at -5.08 38.1)
			(size 1.52781 1.52781)
			(drill 1.01981)
			(layers "*.Cu" "*.Mask")
			(remove_unused_layers no)
			(net "P12V_BRICK")
			(clearance 0)
		)
		(pad "P5_8" thru_hole circle
			(at -7.62 38.1)
			(size 1.52781 1.52781)
			(drill 1.01981)
			(layers "*.Cu" "*.Mask")
			(remove_unused_layers no)
			(net "P12V_BRICK")
			(clearance 0)
		)
		(pad "P6_1" thru_hole circle
			(at 0 44.45)
			(size 1.52781 1.52781)
			(drill 1.01981)
			(layers "*.Cu" "*.Mask")
			(remove_unused_layers no)
			(net "P12V_BRICK")
			(clearance 0)
		)
		(pad "P6_2" thru_hole circle
			(at -2.54 44.45)
			(size 1.52781 1.52781)
			(drill 1.01981)
			(layers "*.Cu" "*.Mask")
			(remove_unused_layers no)
			(net "P12V_BRICK")
			(clearance 0)
		)
		(pad "P6_3" thru_hole circle
			(at -5.08 44.45)
			(size 1.52781 1.52781)
			(drill 1.01981)
			(layers "*.Cu" "*.Mask")
			(remove_unused_layers no)
			(net "P12V_BRICK")
			(clearance 0)
		)
		(pad "P6_4" thru_hole circle
			(at -7.62 44.45)
			(size 1.52781 1.52781)
			(drill 1.01981)
			(layers "*.Cu" "*.Mask")
			(remove_unused_layers no)
			(net "P12V_BRICK")
			(clearance 0)
		)
		(pad "P6_5" thru_hole circle
			(at 0 46.99)
			(size 1.52781 1.52781)
			(drill 1.01981)
			(layers "*.Cu" "*.Mask")
			(remove_unused_layers no)
			(net "P12V_BRICK")
			(clearance 0)
		)
		(pad "P6_6" thru_hole circle
			(at -2.54 46.99)
			(size 1.52781 1.52781)
			(drill 1.01981)
			(layers "*.Cu" "*.Mask")
			(remove_unused_layers no)
			(net "P12V_BRICK")
			(clearance 0)
		)
		(pad "P6_7" thru_hole circle
			(at -5.08 46.99)
			(size 1.52781 1.52781)
			(drill 1.01981)
			(layers "*.Cu" "*.Mask")
			(remove_unused_layers no)
			(net "P12V_BRICK")
			(clearance 0)
		)
		(pad "P6_8" thru_hole circle
			(at -7.62 46.99)
			(size 1.52781 1.52781)
			(drill 1.01981)
			(layers "*.Cu" "*.Mask")
			(remove_unused_layers no)
			(net "P12V_BRICK")
			(clearance 0)
		)
		(zone
			(layers "F.Cu" "B.Cu" "In1.Cu" "In2.Cu" "In3.Cu" "In4.Cu" "In5.Cu" "In6.Cu"
				"In7.Cu" "In8.Cu"
			)
			(hatch none 0.5)
			(connect_pads
				(clearance 0)
			)
			(min_thickness 0.25)
			(keepout
				(tracks not_allowed)
				(vias allowed)
				(pads allowed)
				(copperpour not_allowed)
				(footprints allowed)
			)
			(placement
				(enabled no)
				(sheetname "")
			)
			(fill
				(thermal_gap 0.5)
				(thermal_bridge_width 0.5)
				(island_removal_mode 0)
			)
			(polygon
				(pts
					(arc
						(start 66.942208 -32.93999)
						(mid 59.677808 -32.93999)
						(end 66.942208 -32.93999)
					)
				)
			)
		)
		(zone
			(layers "F.Cu" "B.Cu" "In1.Cu" "In2.Cu" "In3.Cu" "In4.Cu" "In5.Cu" "In6.Cu"
				"In7.Cu" "In8.Cu"
			)
			(hatch none 0.5)
			(connect_pads
				(clearance 0)
			)
			(min_thickness 0.25)
			(keepout
				(tracks not_allowed)
				(vias allowed)
				(pads allowed)
				(copperpour not_allowed)
				(footprints allowed)
			)
			(placement
				(enabled no)
				(sheetname "")
			)
			(fill
				(thermal_gap 0.5)
				(thermal_bridge_width 0.5)
				(island_removal_mode 0)
			)
			(polygon
				(pts
					(arc
						(start 138.062208 -32.93999)
						(mid 130.797808 -32.93999)
						(end 138.062208 -32.93999)
					)
				)
			)
		)
		(zone
			(layer "B.Cu")
			(hatch none 0.5)
			(connect_pads
				(clearance 0)
			)
			(min_thickness 0.25)
			(keepout
				(tracks allowed)
				(vias not_allowed)
				(pads allowed)
				(copperpour not_allowed)
				(footprints allowed)
			)
			(placement
				(enabled no)
				(sheetname "")
			)
			(fill
				(thermal_gap 0.5)
				(thermal_bridge_width 0.5)
				(island_removal_mode 0)
			)
			(polygon
				(pts
					(xy 123.192286 -32.112712) (xy 123.192286 -41.387268) (xy 74.54773 -41.387268) (xy 74.54773 -32.112712)
				)
			)
		)
	)
	(footprint ""
		(layer "F.Cu")
		(at 45.67936 -61.55182)
		(property "Reference" "R5900"
			(at 0 0 0)
			(layer "F.SilkS")
			(hide yes)
			(effects
				(font
					(size 1.27 1.27)
				)
			)
		)
		(property "Value" ""
			(at 0 0 0)
			(layer "F.Fab")
			(effects
				(font
					(size 1.27 1.27)
				)
			)
		)
		(duplicate_pad_numbers_are_jumpers no)
		(fp_line
			(start -0.7874 -0.4064)
			(end 0.7874 -0.4064)
			(stroke
				(width 0.1524)
				(type default)
			)
			(layer "F.SilkS")
		)
		(fp_line
			(start -0.7874 0.4064)
			(end -0.7874 -0.4064)
			(stroke
				(width 0.1524)
				(type default)
			)
			(layer "F.SilkS")
		)
		(fp_line
			(start 0.7874 -0.4064)
			(end 0.7874 0.4064)
			(stroke
				(width 0.1524)
				(type default)
			)
			(layer "F.SilkS")
		)
		(fp_line
			(start 0.7874 0.4064)
			(end -0.7874 0.4064)
			(stroke
				(width 0.1524)
				(type default)
			)
			(layer "F.SilkS")
		)
		(fp_line
			(start -0.67945 -0.305054)
			(end -0.12065 -0.305054)
			(stroke
				(width 0.1)
				(type default)
			)
			(layer "F.Fab")
		)
		(fp_line
			(start -0.67945 0.3048)
			(end -0.67945 -0.305054)
			(stroke
				(width 0.1)
				(type default)
			)
			(layer "F.Fab")
		)
		(fp_line
			(start -0.12065 -0.305054)
			(end -0.12065 -0.2794)
			(stroke
				(width 0.1)
				(type default)
			)
			(layer "F.Fab")
		)
		(fp_line
			(start -0.12065 -0.2794)
			(end 0.12065 -0.2794)
			(stroke
				(width 0.1)
				(type default)
			)
			(layer "F.Fab")
		)
		(fp_line
			(start -0.12065 0.2794)
			(end -0.12065 0.3048)
			(stroke
				(width 0.1)
				(type default)
			)
			(layer "F.Fab")
		)
		(fp_line
			(start -0.12065 0.3048)
			(end -0.67945 0.3048)
			(stroke
				(width 0.1)
				(type default)
			)
			(layer "F.Fab")
		)
		(fp_line
			(start 0.120396 0.2794)
			(end -0.12065 0.2794)
			(stroke
				(width 0.1)
				(type default)
			)
			(layer "F.Fab")
		)
		(fp_line
			(start 0.120396 0.3048)
			(end 0.120396 0.2794)
			(stroke
				(width 0.1)
				(type default)
			)
			(layer "F.Fab")
		)
		(fp_line
			(start 0.12065 -0.3048)
			(end 0.67945 -0.3048)
			(stroke
				(width 0.1)
				(type default)
			)
			(layer "F.Fab")
		)
		(fp_line
			(start 0.12065 -0.2794)
			(end 0.12065 -0.3048)
			(stroke
				(width 0.1)
				(type default)
			)
			(layer "F.Fab")
		)
		(fp_line
			(start 0.67945 -0.3048)
			(end 0.67945 0.3048)
			(stroke
				(width 0.1)
				(type default)
			)
			(layer "F.Fab")
		)
		(fp_line
			(start 0.67945 0.3048)
			(end 0.120396 0.3048)
			(stroke
				(width 0.1)
				(type default)
			)
			(layer "F.Fab")
		)
		(pad "1" smd circle
			(at -0.40005 0)
			(size 0 0)
			(layers "F.Cu" "F.Mask" "F.Paste")
			(net "P12V_HPDB_0_IMON")
		)
		(pad "2" smd circle
			(at 0.40005 0)
			(size 0 0)
			(layers "F.Cu" "F.Mask" "F.Paste")
			(net "GND")
		)
	)
	(footprint ""
		(layer "F.Cu")
		(at 60.452 -60.198)
		(property "Reference" "PR86"
			(at 0 0 0)
			(layer "F.SilkS")
			(hide yes)
			(effects
				(font
					(size 1.27 1.27)
				)
			)
		)
		(property "Value" ""
			(at 0 0 0)
			(layer "F.Fab")
			(effects
				(font
					(size 1.27 1.27)
				)
			)
		)
		(duplicate_pad_numbers_are_jumpers no)
		(fp_line
			(start -1.651 -0.8382)
			(end 1.651 -0.8382)
			(stroke
				(width 0.1524)
				(type default)
			)
			(layer "F.SilkS")
		)
		(fp_line
			(start -1.651 0.8382)
			(end -1.651 -0.8382)
			(stroke
				(width 0.1524)
				(type default)
			)
			(layer "F.SilkS")
		)
		(fp_line
			(start 1.651 -0.8382)
			(end 1.651 0.8382)
			(stroke
				(width 0.1524)
				(type default)
			)
			(layer "F.SilkS")
		)
		(fp_line
			(start 1.651 0.8382)
			(end -1.651 0.8382)
			(stroke
				(width 0.1524)
				(type default)
			)
			(layer "F.SilkS")
		)
		(fp_line
			(start -1.559814 -0.7366)
			(end -1.559814 0.7366)
			(stroke
				(width 0.1)
				(type default)
			)
			(layer "F.Fab")
		)
		(fp_line
			(start -1.559814 0.7366)
			(end -1.524 0.7366)
			(stroke
				(width 0.1)
				(type default)
			)
			(layer "F.Fab")
		)
		(fp_line
			(start -1.524 -0.7366)
			(end -1.559814 -0.7366)
			(stroke
				(width 0.1)
				(type default)
			)
			(layer "F.Fab")
		)
		(fp_line
			(start -1.524 0.7366)
			(end 1.524 0.7366)
			(stroke
				(width 0.1)
				(type default)
			)
			(layer "F.Fab")
		)
		(fp_line
			(start 1.524 -0.7366)
			(end -1.524 -0.7366)
			(stroke
				(width 0.1)
				(type default)
			)
			(layer "F.Fab")
		)
		(fp_line
			(start 1.524 0.7366)
			(end 1.560576 0.7366)
			(stroke
				(width 0.1)
				(type default)
			)
			(layer "F.Fab")
		)
		(fp_line
			(start 1.560576 -0.7366)
			(end 1.524 -0.7366)
			(stroke
				(width 0.1)
				(type default)
			)
			(layer "F.Fab")
		)
		(fp_line
			(start 1.560576 0.7366)
			(end 1.560576 -0.7366)
			(stroke
				(width 0.1)
				(type default)
			)
			(layer "F.Fab")
		)
		(pad "1" smd rect
			(at -0.94996 0 180)
			(size 1.1176 1.3716)
			(layers "F.Cu" "F.Mask" "F.Paste")
			(net "P12V_BRICK")
		)
		(pad "2" smd rect
			(at 0.94996 0 180)
			(size 1.1176 1.3716)
			(layers "F.Cu" "F.Mask" "F.Paste")
			(net "GND")
		)
	)
	(footprint ""
		(layer "F.Cu")
		(at 315.000132 -14.59992 -90)
		(property "Reference" "H20"
			(at 0.92329 -6.246368 0)
			(unlocked yes)
			(layer "F.SilkS")
			(effects
				(font
					(size 0.7874 0.5842)
					(thickness 0.1524)
				)
				(justify left)
			)
		)
		(property "Value" ""
			(at 0 0 270)
			(layer "F.Fab")
			(effects
				(font
					(size 1.27 1.27)
				)
			)
		)
		(duplicate_pad_numbers_are_jumpers no)
		(pad "1" thru_hole circle
			(at 0 0 270)
			(size 10.16 10.16)
			(drill 6.4008
				(offset 0 0)
			)
			(layers "*.Cu" "*.Mask")
			(remove_unused_layers no)
			(net "GND")
			(clearance -1.6256)
			(padstack
				(mode front_inner_back)
				(layer "Inner"
					(shape circle)
					(size 10.16 10.16)
					(clearance -1.6256)
				)
				(layer "B.Cu"
					(shape oval)
					(size 10.0076 32.004)
					(offset 0 10.9982)
					(clearance -1.5494)
				)
			)
		)
	)
	(footprint ""
		(layer "F.Cu")
		(at 191.643 -17.399)
		(property "Reference" "PC112"
			(at 0 0 0)
			(layer "F.SilkS")
			(hide yes)
			(effects
				(font
					(size 1.27 1.27)
				)
			)
		)
		(property "Value" ""
			(at 0 0 0)
			(layer "F.Fab")
			(effects
				(font
					(size 1.27 1.27)
				)
			)
		)
		(duplicate_pad_numbers_are_jumpers no)
		(fp_line
			(start -0.7874 -0.4064)
			(end 0.7874 -0.4064)
			(stroke
				(width 0.1524)
				(type default)
			)
			(layer "F.SilkS")
		)
		(fp_line
			(start -0.7874 0.4064)
			(end -0.7874 -0.4064)
			(stroke
				(width 0.1524)
				(type default)
			)
			(layer "F.SilkS")
		)
		(fp_line
			(start 0.7874 -0.4064)
			(end 0.7874 0.4064)
			(stroke
				(width 0.1524)
				(type default)
			)
			(layer "F.SilkS")
		)
		(fp_line
			(start 0.7874 0.4064)
			(end -0.7874 0.4064)
			(stroke
				(width 0.1524)
				(type default)
			)
			(layer "F.SilkS")
		)
		(fp_line
			(start -0.67945 -0.305054)
			(end -0.12065 -0.305054)
			(stroke
				(width 0.1)
				(type default)
			)
			(layer "F.Fab")
		)
		(fp_line
			(start -0.67945 0.3048)
			(end -0.67945 -0.305054)
			(stroke
				(width 0.1)
				(type default)
			)
			(layer "F.Fab")
		)
		(fp_line
			(start -0.12065 -0.305054)
			(end -0.12065 -0.2794)
			(stroke
				(width 0.1)
				(type default)
			)
			(layer "F.Fab")
		)
		(fp_line
			(start -0.12065 -0.2794)
			(end 0.12065 -0.2794)
			(stroke
				(width 0.1)
				(type default)
			)
			(layer "F.Fab")
		)
		(fp_line
			(start -0.12065 0.2794)
			(end -0.12065 0.3048)
			(stroke
				(width 0.1)
				(type default)
			)
			(layer "F.Fab")
		)
		(fp_line
			(start -0.12065 0.3048)
			(end -0.67945 0.3048)
			(stroke
				(width 0.1)
				(type default)
			)
			(layer "F.Fab")
		)
		(fp_line
			(start 0.120396 0.2794)
			(end -0.12065 0.2794)
			(stroke
				(width 0.1)
				(type default)
			)
			(layer "F.Fab")
		)
		(fp_line
			(start 0.120396 0.3048)
			(end 0.120396 0.2794)
			(stroke
				(width 0.1)
				(type default)
			)
			(layer "F.Fab")
		)
		(fp_line
			(start 0.12065 -0.3048)
			(end 0.67945 -0.3048)
			(stroke
				(width 0.1)
				(type default)
			)
			(layer "F.Fab")
		)
		(fp_line
			(start 0.12065 -0.2794)
			(end 0.12065 -0.3048)
			(stroke
				(width 0.1)
				(type default)
			)
			(layer "F.Fab")
		)
		(fp_line
			(start 0.67945 -0.3048)
			(end 0.67945 0.3048)
			(stroke
				(width 0.1)
				(type default)
			)
			(layer "F.Fab")
		)
		(fp_line
			(start 0.67945 0.3048)
			(end 0.120396 0.3048)
			(stroke
				(width 0.1)
				(type default)
			)
			(layer "F.Fab")
		)
		(pad "1" smd circle
			(at -0.40005 0)
			(size 0 0)
			(layers "F.Cu" "F.Mask" "F.Paste")
			(net "P3V3_AUX")
		)
		(pad "2" smd circle
			(at 0.40005 0)
			(size 0 0)
			(layers "F.Cu" "F.Mask" "F.Paste")
			(net "GND")
		)
	)
	(footprint ""
		(layer "F.Cu")
		(at 297.538394 -83.5025 180)
		(property "Reference" "PR6959"
			(at 0 0 180)
			(layer "F.SilkS")
			(hide yes)
			(effects
				(font
					(size 1.27 1.27)
				)
			)
		)
		(property "Value" ""
			(at 0 0 180)
			(layer "F.Fab")
			(effects
				(font
					(size 1.27 1.27)
				)
			)
		)
		(duplicate_pad_numbers_are_jumpers no)
		(fp_line
			(start 1.2954 0.5842)
			(end -1.2954 0.5842)
			(stroke
				(width 0.1524)
				(type default)
			)
			(layer "F.SilkS")
		)
		(fp_line
			(start 1.2954 -0.5842)
			(end 1.2954 0.5842)
			(stroke
				(width 0.1524)
				(type default)
			)
			(layer "F.SilkS")
		)
		(fp_line
			(start -1.2954 0.5842)
			(end -1.2954 -0.5842)
			(stroke
				(width 0.1524)
				(type default)
			)
			(layer "F.SilkS")
		)
		(fp_line
			(start -1.2954 -0.5842)
			(end 1.2954 -0.5842)
			(stroke
				(width 0.1524)
				(type default)
			)
			(layer "F.SilkS")
		)
		(fp_line
			(start 1.1938 0.4064)
			(end 0.8636 0.4064)
			(stroke
				(width 0.1)
				(type default)
			)
			(layer "F.Fab")
		)
		(fp_line
			(start 1.1938 -0.406654)
			(end 1.1938 0.4064)
			(stroke
				(width 0.1)
				(type default)
			)
			(layer "F.Fab")
		)
		(fp_line
			(start 0.8636 0.4572)
			(end -0.8636 0.4572)
			(stroke
				(width 0.1)
				(type default)
			)
			(layer "F.Fab")
		)
		(fp_line
			(start 0.8636 0.4064)
			(end 0.8636 0.4572)
			(stroke
				(width 0.1)
				(type default)
			)
			(layer "F.Fab")
		)
		(fp_line
			(start 0.8636 -0.406654)
			(end 1.1938 -0.406654)
			(stroke
				(width 0.1)
				(type default)
			)
			(layer "F.Fab")
		)
		(fp_line
			(start 0.8636 -0.4572)
			(end 0.8636 -0.406654)
			(stroke
				(width 0.1)
				(type default)
			)
			(layer "F.Fab")
		)
		(fp_line
			(start -0.8636 0.4572)
			(end -0.8636 0.4318)
			(stroke
				(width 0.1)
				(type default)
			)
			(layer "F.Fab")
		)
		(fp_line
			(start -0.8636 0.4318)
			(end -0.8636 0.4064)
			(stroke
				(width 0.1)
				(type default)
			)
			(layer "F.Fab")
		)
		(fp_line
			(start -0.8636 0.4064)
			(end -1.1938 0.4064)
			(stroke
				(width 0.1)
				(type default)
			)
			(layer "F.Fab")
		)
		(fp_line
			(start -0.8636 -0.406654)
			(end -0.8636 -0.4572)
			(stroke
				(width 0.1)
				(type default)
			)
			(layer "F.Fab")
		)
		(fp_line
			(start -0.8636 -0.4572)
			(end 0.8636 -0.4572)
			(stroke
				(width 0.1)
				(type default)
			)
			(layer "F.Fab")
		)
		(fp_line
			(start -1.1938 0.4064)
			(end -1.1938 -0.406654)
			(stroke
				(width 0.1)
				(type default)
			)
			(layer "F.Fab")
		)
		(fp_line
			(start -1.1938 -0.406654)
			(end -0.8636 -0.406654)
			(stroke
				(width 0.1)
				(type default)
			)
			(layer "F.Fab")
		)
		(pad "1" smd rect
			(at -0.7366 0 90)
			(size 0.7112 0.8128)
			(layers "F.Cu" "F.Mask" "F.Paste")
			(net "P52V_HS_1272_S_N")
		)
		(pad "2" smd rect
			(at 0.7366 0 90)
			(size 0.7112 0.8128)
			(layers "F.Cu" "F.Mask" "F.Paste")
			(net "P52V_HS1_SENSE_N_R2")
		)
	)
	(footprint ""
		(layer "F.Cu")
		(at 139.065 -62.992)
		(property "Reference" "PC28"
			(at 0 0 0)
			(layer "F.SilkS")
			(hide yes)
			(effects
				(font
					(size 1.27 1.27)
				)
			)
		)
		(property "Value" ""
			(at 0 0 0)
			(layer "F.Fab")
			(effects
				(font
					(size 1.27 1.27)
				)
			)
		)
		(duplicate_pad_numbers_are_jumpers no)
		(fp_line
			(start -0.7874 -0.4064)
			(end 0.7874 -0.4064)
			(stroke
				(width 0.1524)
				(type default)
			)
			(layer "F.SilkS")
		)
		(fp_line
			(start -0.7874 0.4064)
			(end -0.7874 -0.4064)
			(stroke
				(width 0.1524)
				(type default)
			)
			(layer "F.SilkS")
		)
		(fp_line
			(start 0.7874 -0.4064)
			(end 0.7874 0.4064)
			(stroke
				(width 0.1524)
				(type default)
			)
			(layer "F.SilkS")
		)
		(fp_line
			(start 0.7874 0.4064)
			(end -0.7874 0.4064)
			(stroke
				(width 0.1524)
				(type default)
			)
			(layer "F.SilkS")
		)
		(fp_line
			(start -0.6858 -0.3048)
			(end -0.1016 -0.3048)
			(stroke
				(width 0.1)
				(type default)
			)
			(layer "F.Fab")
		)
		(fp_line
			(start -0.6858 0.3048)
			(end -0.6858 -0.3048)
			(stroke
				(width 0.1)
				(type default)
			)
			(layer "F.Fab")
		)
		(fp_line
			(start -0.1016 -0.3048)
			(end -0.1016 -0.2794)
			(stroke
				(width 0.1)
				(type default)
			)
			(layer "F.Fab")
		)
		(fp_line
			(start -0.1016 -0.2794)
			(end 0.1016 -0.2794)
			(stroke
				(width 0.1)
				(type default)
			)
			(layer "F.Fab")
		)
		(fp_line
			(start -0.1016 0.2794)
			(end -0.1016 0.3048)
			(stroke
				(width 0.1)
				(type default)
			)
			(layer "F.Fab")
		)
		(fp_line
			(start -0.1016 0.3048)
			(end -0.6858 0.3048)
			(stroke
				(width 0.1)
				(type default)
			)
			(layer "F.Fab")
		)
		(fp_line
			(start 0.1016 -0.3048)
			(end 0.6858 -0.3048)
			(stroke
				(width 0.1)
				(type default)
			)
			(layer "F.Fab")
		)
		(fp_line
			(start 0.1016 -0.2794)
			(end 0.1016 -0.3048)
			(stroke
				(width 0.1)
				(type default)
			)
			(layer "F.Fab")
		)
		(fp_line
			(start 0.1016 0.2794)
			(end -0.1016 0.2794)
			(stroke
				(width 0.1)
				(type default)
			)
			(layer "F.Fab")
		)
		(fp_line
			(start 0.1016 0.3048)
			(end 0.1016 0.2794)
			(stroke
				(width 0.1)
				(type default)
			)
			(layer "F.Fab")
		)
		(fp_line
			(start 0.6858 -0.3048)
			(end 0.6858 0.3048)
			(stroke
				(width 0.1)
				(type default)
			)
			(layer "F.Fab")
		)
		(fp_line
			(start 0.6858 0.3048)
			(end 0.1016 0.3048)
			(stroke
				(width 0.1)
				(type default)
			)
			(layer "F.Fab")
		)
		(pad "1" smd rect
			(at -0.40005 0 180)
			(size 0.4572 0.508)
			(layers "F.Cu" "F.Mask" "F.Paste")
			(net "P12V_BRICK")
		)
		(pad "2" smd rect
			(at 0.40005 0 180)
			(size 0.4572 0.508)
			(layers "F.Cu" "F.Mask" "F.Paste")
			(net "GND")
		)
	)
	(footprint ""
		(layer "F.Cu")
		(at 259.334 -29.972 180)
		(property "Reference" "PR313"
			(at 0 0 180)
			(layer "F.SilkS")
			(hide yes)
			(effects
				(font
					(size 1.27 1.27)
				)
			)
		)
		(property "Value" ""
			(at 0 0 180)
			(layer "F.Fab")
			(effects
				(font
					(size 1.27 1.27)
				)
			)
		)
		(duplicate_pad_numbers_are_jumpers no)
		(fp_line
			(start 0.7874 0.4064)
			(end -0.7874 0.4064)
			(stroke
				(width 0.1524)
				(type default)
			)
			(layer "F.SilkS")
		)
		(fp_line
			(start 0.7874 -0.4064)
			(end 0.7874 0.4064)
			(stroke
				(width 0.1524)
				(type default)
			)
			(layer "F.SilkS")
		)
		(fp_line
			(start -0.7874 0.4064)
			(end -0.7874 -0.4064)
			(stroke
				(width 0.1524)
				(type default)
			)
			(layer "F.SilkS")
		)
		(fp_line
			(start -0.7874 -0.4064)
			(end 0.7874 -0.4064)
			(stroke
				(width 0.1524)
				(type default)
			)
			(layer "F.SilkS")
		)
		(fp_line
			(start 0.67945 0.3048)
			(end 0.120396 0.3048)
			(stroke
				(width 0.1)
				(type default)
			)
			(layer "F.Fab")
		)
		(fp_line
			(start 0.67945 -0.3048)
			(end 0.67945 0.3048)
			(stroke
				(width 0.1)
				(type default)
			)
			(layer "F.Fab")
		)
		(fp_line
			(start 0.12065 -0.2794)
			(end 0.12065 -0.3048)
			(stroke
				(width 0.1)
				(type default)
			)
			(layer "F.Fab")
		)
		(fp_line
			(start 0.12065 -0.3048)
			(end 0.67945 -0.3048)
			(stroke
				(width 0.1)
				(type default)
			)
			(layer "F.Fab")
		)
		(fp_line
			(start 0.120396 0.3048)
			(end 0.120396 0.2794)
			(stroke
				(width 0.1)
				(type default)
			)
			(layer "F.Fab")
		)
		(fp_line
			(start 0.120396 0.2794)
			(end -0.12065 0.2794)
			(stroke
				(width 0.1)
				(type default)
			)
			(layer "F.Fab")
		)
		(fp_line
			(start -0.12065 0.3048)
			(end -0.67945 0.3048)
			(stroke
				(width 0.1)
				(type default)
			)
			(layer "F.Fab")
		)
		(fp_line
			(start -0.12065 0.2794)
			(end -0.12065 0.3048)
			(stroke
				(width 0.1)
				(type default)
			)
			(layer "F.Fab")
		)
		(fp_line
			(start -0.12065 -0.2794)
			(end 0.12065 -0.2794)
			(stroke
				(width 0.1)
				(type default)
			)
			(layer "F.Fab")
		)
		(fp_line
			(start -0.12065 -0.305054)
			(end -0.12065 -0.2794)
			(stroke
				(width 0.1)
				(type default)
			)
			(layer "F.Fab")
		)
		(fp_line
			(start -0.67945 0.3048)
			(end -0.67945 -0.305054)
			(stroke
				(width 0.1)
				(type default)
			)
			(layer "F.Fab")
		)
		(fp_line
			(start -0.67945 -0.305054)
			(end -0.12065 -0.305054)
			(stroke
				(width 0.1)
				(type default)
			)
			(layer "F.Fab")
		)
		(pad "1" smd circle
			(at -0.40005 0 180)
			(size 0 0)
			(layers "F.Cu" "F.Mask" "F.Paste")
			(net "SMB_P52V_HSC_SCL")
		)
		(pad "2" smd circle
			(at 0.40005 0 180)
			(size 0 0)
			(layers "F.Cu" "F.Mask" "F.Paste")
			(net "SMB_P52V_VPDB_DEBUG_SCL")
		)
	)
	(footprint ""
		(layer "F.Cu")
		(at 270.383 -69.428868 -90)
		(property "Reference" "PR16"
			(at 0 0 270)
			(layer "F.SilkS")
			(hide yes)
			(effects
				(font
					(size 1.27 1.27)
				)
			)
		)
		(property "Value" ""
			(at 0 0 270)
			(layer "F.Fab")
			(effects
				(font
					(size 1.27 1.27)
				)
			)
		)
		(duplicate_pad_numbers_are_jumpers no)
		(fp_line
			(start -1.2954 0.5842)
			(end -1.2954 -0.5842)
			(stroke
				(width 0.1524)
				(type default)
			)
			(layer "F.SilkS")
		)
		(fp_line
			(start 1.2954 0.5842)
			(end -1.2954 0.5842)
			(stroke
				(width 0.1524)
				(type default)
			)
			(layer "F.SilkS")
		)
		(fp_line
			(start -1.2954 -0.5842)
			(end 1.2954 -0.5842)
			(stroke
				(width 0.1524)
				(type default)
			)
			(layer "F.SilkS")
		)
		(fp_line
			(start 1.2954 -0.5842)
			(end 1.2954 0.5842)
			(stroke
				(width 0.1524)
				(type default)
			)
			(layer "F.SilkS")
		)
		(fp_line
			(start -0.8636 0.4572)
			(end -0.8636 0.4318)
			(stroke
				(width 0.1)
				(type default)
			)
			(layer "F.Fab")
		)
		(fp_line
			(start 0.8636 0.4572)
			(end -0.8636 0.4572)
			(stroke
				(width 0.1)
				(type default)
			)
			(layer "F.Fab")
		)
		(fp_line
			(start -0.8636 0.4318)
			(end -0.8636 0.4064)
			(stroke
				(width 0.1)
				(type default)
			)
			(layer "F.Fab")
		)
		(fp_line
			(start -1.1938 0.4064)
			(end -1.1938 -0.406654)
			(stroke
				(width 0.1)
				(type default)
			)
			(layer "F.Fab")
		)
		(fp_line
			(start -0.8636 0.4064)
			(end -1.1938 0.4064)
			(stroke
				(width 0.1)
				(type default)
			)
			(layer "F.Fab")
		)
		(fp_line
			(start 0.8636 0.4064)
			(end 0.8636 0.4572)
			(stroke
				(width 0.1)
				(type default)
			)
			(layer "F.Fab")
		)
		(fp_line
			(start 1.1938 0.4064)
			(end 0.8636 0.4064)
			(stroke
				(width 0.1)
				(type default)
			)
			(layer "F.Fab")
		)
		(fp_line
			(start -1.1938 -0.406654)
			(end -0.8636 -0.406654)
			(stroke
				(width 0.1)
				(type default)
			)
			(layer "F.Fab")
		)
		(fp_line
			(start -0.8636 -0.406654)
			(end -0.8636 -0.4572)
			(stroke
				(width 0.1)
				(type default)
			)
			(layer "F.Fab")
		)
		(fp_line
			(start 0.8636 -0.406654)
			(end 1.1938 -0.406654)
			(stroke
				(width 0.1)
				(type default)
			)
			(layer "F.Fab")
		)
		(fp_line
			(start 1.1938 -0.406654)
			(end 1.1938 0.4064)
			(stroke
				(width 0.1)
				(type default)
			)
			(layer "F.Fab")
		)
		(fp_line
			(start -0.8636 -0.4572)
			(end 0.8636 -0.4572)
			(stroke
				(width 0.1)
				(type default)
			)
			(layer "F.Fab")
		)
		(fp_line
			(start 0.8636 -0.4572)
			(end 0.8636 -0.406654)
			(stroke
				(width 0.1)
				(type default)
			)
			(layer "F.Fab")
		)
		(pad "1" smd rect
			(at -0.7366 0 180)
			(size 0.7112 0.8128)
			(layers "F.Cu" "F.Mask" "F.Paste")
			(net "P52V_HS1_GATE2_R")
		)
		(pad "2" smd rect
			(at 0.7366 0 180)
			(size 0.7112 0.8128)
			(layers "F.Cu" "F.Mask" "F.Paste")
			(net "P52V_HS1_GATE6")
		)
	)
	(footprint ""
		(layer "F.Cu")
		(at 230.000048 -11.999976 -90)
		(property "Reference" "H18"
			(at -6.134354 12.322048 0)
			(unlocked yes)
			(layer "F.SilkS")
			(effects
				(font
					(size 0.7874 0.5842)
					(thickness 0.1524)
				)
				(justify left)
			)
		)
		(property "Value" ""
			(at 0 0 270)
			(layer "F.Fab")
			(effects
				(font
					(size 1.27 1.27)
				)
			)
		)
		(duplicate_pad_numbers_are_jumpers no)
		(pad "1" thru_hole oval
			(at 0 0 270)
			(size 10.0076 32.004)
			(drill 3.0226
				(offset 0 10.999978)
			)
			(layers "*.Cu" "*.Mask")
			(remove_unused_layers no)
			(net "GND")
			(clearance -1.995678)
			(padstack
				(mode front_inner_back)
				(layer "Inner"
					(shape circle)
					(size 0 0)
					(clearance 0)
				)
				(layer "B.Cu"
					(shape oval)
					(size 10.0076 32.004)
					(offset 0 10.999978)
					(clearance -1.995678)
				)
			)
		)
	)
	(footprint ""
		(layer "F.Cu")
		(at 176.906174 -127.889)
		(property "Reference" "PC118"
			(at 0 0 0)
			(layer "F.SilkS")
			(hide yes)
			(effects
				(font
					(size 1.27 1.27)
				)
			)
		)
		(property "Value" ""
			(at 0 0 0)
			(layer "F.Fab")
			(effects
				(font
					(size 1.27 1.27)
				)
			)
		)
		(duplicate_pad_numbers_are_jumpers no)
		(fp_line
			(start -2.2098 -0.9398)
			(end 2.2098 -0.9398)
			(stroke
				(width 0.1524)
				(type default)
			)
			(layer "F.SilkS")
		)
		(fp_line
			(start -2.2098 0.9398)
			(end -2.2098 -0.9398)
			(stroke
				(width 0.1524)
				(type default)
			)
			(layer "F.SilkS")
		)
		(fp_line
			(start 2.2098 -0.9398)
			(end 2.2098 0.9398)
			(stroke
				(width 0.1524)
				(type default)
			)
			(layer "F.SilkS")
		)
		(fp_line
			(start 2.2098 0.9398)
			(end -2.2098 0.9398)
			(stroke
				(width 0.1524)
				(type default)
			)
			(layer "F.SilkS")
		)
		(fp_line
			(start -1.700022 -0.899922)
			(end 1.700022 -0.899922)
			(stroke
				(width 0.1)
				(type default)
			)
			(layer "F.Fab")
		)
		(fp_line
			(start -1.700022 0.899922)
			(end -1.700022 -0.899922)
			(stroke
				(width 0.1)
				(type default)
			)
			(layer "F.Fab")
		)
		(fp_line
			(start 1.700022 -0.899922)
			(end 1.700022 0.899922)
			(stroke
				(width 0.1)
				(type default)
			)
			(layer "F.Fab")
		)
		(fp_line
			(start 1.700022 0.899922)
			(end -1.700022 0.899922)
			(stroke
				(width 0.1)
				(type default)
			)
			(layer "F.Fab")
		)
		(pad "1" smd rect
			(at -1.4732 0 180)
			(size 1.1684 1.5748)
			(layers "F.Cu" "F.Mask" "F.Paste")
			(net "P52V_HS_FILTER")
		)
		(pad "2" smd rect
			(at 1.4732 0 180)
			(size 1.1684 1.5748)
			(layers "F.Cu" "F.Mask" "F.Paste")
			(net "GND")
		)
	)
	(footprint ""
		(layer "F.Cu")
		(at 21.02993 -25.329896 -90)
		(property "Reference" "J15"
			(at -6.393434 -8.43407 0)
			(unlocked yes)
			(layer "F.SilkS")
			(effects
				(font
					(size 0.7874 0.5842)
					(thickness 0.1524)
				)
				(justify left)
			)
		)
		(property "Value" ""
			(at 0 0 270)
			(layer "F.Fab")
			(effects
				(font
					(size 1.27 1.27)
				)
			)
		)
		(duplicate_pad_numbers_are_jumpers no)
		(fp_line
			(start -5.32511 21.299932)
			(end -5.32511 -10.500106)
			(stroke
				(width 0.1524)
				(type default)
			)
			(layer "F.SilkS")
		)
		(fp_line
			(start 5.32511 21.299932)
			(end -5.32511 21.299932)
			(stroke
				(width 0.1524)
				(type default)
			)
			(layer "F.SilkS")
		)
		(fp_line
			(start -5.32511 10.6299)
			(end 5.32511 10.6299)
			(stroke
				(width 0.1524)
				(type default)
			)
			(layer "F.SilkS")
		)
		(fp_line
			(start -5.32511 -10.500106)
			(end 5.32511 -10.500106)
			(stroke
				(width 0.1524)
				(type default)
			)
			(layer "F.SilkS")
		)
		(fp_line
			(start 5.32511 -10.500106)
			(end 5.32511 21.299932)
			(stroke
				(width 0.1524)
				(type default)
			)
			(layer "F.SilkS")
		)
		(fp_line
			(start -5.32511 21.299932)
			(end -5.32511 -10.500106)
			(stroke
				(width 0.1)
				(type default)
			)
			(layer "F.Fab")
		)
		(fp_line
			(start 5.32511 21.299932)
			(end -5.32511 21.299932)
			(stroke
				(width 0.1)
				(type default)
			)
			(layer "F.Fab")
		)
		(fp_line
			(start -5.32511 -10.500106)
			(end 5.32511 -10.500106)
			(stroke
				(width 0.1)
				(type default)
			)
			(layer "F.Fab")
		)
		(fp_line
			(start 5.32511 -10.500106)
			(end 5.32511 21.299932)
			(stroke
				(width 0.1)
				(type default)
			)
			(layer "F.Fab")
		)
		(pad "" np_thru_hole circle
			(at 0 -6.620002 270)
			(size 3.9624 3.9624)
			(drill 3.9624)
			(layers "*.Cu" "*.Mask")
			(clearance 0.381)
			(thermal_gap 0.381)
		)
		(pad "" np_thru_hole circle
			(at 0 0 270)
			(size 0 0)
			(drill 3.9624)
			(layers "*.Cu" "*.Mask")
			(clearance 0)
		)
		(pad "" np_thru_hole circle
			(at 0 5.62991 270)
			(size 3.9624 3.9624)
			(drill 3.9624)
			(layers "*.Cu" "*.Mask")
			(clearance 0.381)
			(thermal_gap 0.381)
		)
		(zone
			(layers "F.Cu" "B.Cu" "In1.Cu" "In2.Cu" "In3.Cu" "In4.Cu" "In5.Cu" "In6.Cu"
				"In7.Cu" "In8.Cu"
			)
			(hatch none 0.5)
			(connect_pads
				(clearance 0)
			)
			(min_thickness 0.25)
			(keepout
				(tracks not_allowed)
				(vias allowed)
				(pads allowed)
				(copperpour not_allowed)
				(footprints allowed)
			)
			(placement
				(enabled no)
				(sheetname "")
			)
			(fill
				(thermal_gap 0.5)
				(thermal_bridge_width 0.5)
				(island_removal_mode 0)
			)
			(polygon
				(pts
					(arc
						(start 17.88922 -25.329896)
						(mid 12.91082 -25.329896)
						(end 17.88922 -25.329896)
					)
				)
			)
		)
		(zone
			(layers "F.Cu" "B.Cu" "In1.Cu" "In2.Cu" "In3.Cu" "In4.Cu" "In5.Cu" "In6.Cu"
				"In7.Cu" "In8.Cu"
			)
			(hatch none 0.5)
			(connect_pads
				(clearance 0)
			)
			(min_thickness 0.25)
			(keepout
				(tracks not_allowed)
				(vias allowed)
				(pads allowed)
				(copperpour not_allowed)
				(footprints allowed)
			)
			(placement
				(enabled no)
				(sheetname "")
			)
			(fill
				(thermal_gap 0.5)
				(thermal_bridge_width 0.5)
				(island_removal_mode 0)
			)
			(polygon
				(pts
					(arc
						(start 30.139132 -25.329896)
						(mid 25.160732 -25.329896)
						(end 30.139132 -25.329896)
					)
				)
			)
		)
		(zone
			(layers "F.Cu" "B.Cu" "In1.Cu" "In2.Cu" "In3.Cu" "In4.Cu" "In5.Cu" "In6.Cu"
				"In7.Cu" "In8.Cu"
			)
			(hatch none 0.5)
			(connect_pads
				(clearance 0)
			)
			(min_thickness 0.25)
			(keepout
				(tracks not_allowed)
				(vias allowed)
				(pads allowed)
				(copperpour not_allowed)
				(footprints allowed)
			)
			(placement
				(enabled no)
				(sheetname "")
			)
			(fill
				(thermal_gap 0.5)
				(thermal_bridge_width 0.5)
				(island_removal_mode 0)
			)
			(polygon
				(pts
					(arc
						(start 25.04313 -25.329896)
						(mid 17.01673 -25.329896)
						(end 25.04313 -25.329896)
					)
				)
			)
		)
	)
	(footprint ""
		(layer "F.Cu")
		(at 224.917 -95.504 -90)
		(property "Reference" "C31"
			(at 0 0 270)
			(layer "F.SilkS")
			(hide yes)
			(effects
				(font
					(size 1.27 1.27)
				)
			)
		)
		(property "Value" ""
			(at 0 0 270)
			(layer "F.Fab")
			(effects
				(font
					(size 1.27 1.27)
				)
			)
		)
		(duplicate_pad_numbers_are_jumpers no)
		(fp_line
			(start -2.2098 0.9398)
			(end -2.2098 -0.9398)
			(stroke
				(width 0.1524)
				(type default)
			)
			(layer "F.SilkS")
		)
		(fp_line
			(start 2.2098 0.9398)
			(end -2.2098 0.9398)
			(stroke
				(width 0.1524)
				(type default)
			)
			(layer "F.SilkS")
		)
		(fp_line
			(start -2.2098 -0.9398)
			(end 2.2098 -0.9398)
			(stroke
				(width 0.1524)
				(type default)
			)
			(layer "F.SilkS")
		)
		(fp_line
			(start 2.2098 -0.9398)
			(end 2.2098 0.9398)
			(stroke
				(width 0.1524)
				(type default)
			)
			(layer "F.SilkS")
		)
		(fp_line
			(start -1.700022 0.899922)
			(end -1.700022 -0.899922)
			(stroke
				(width 0.1)
				(type default)
			)
			(layer "F.Fab")
		)
		(fp_line
			(start 1.700022 0.899922)
			(end -1.700022 0.899922)
			(stroke
				(width 0.1)
				(type default)
			)
			(layer "F.Fab")
		)
		(fp_line
			(start -1.700022 -0.899922)
			(end 1.700022 -0.899922)
			(stroke
				(width 0.1)
				(type default)
			)
			(layer "F.Fab")
		)
		(fp_line
			(start 1.700022 -0.899922)
			(end 1.700022 0.899922)
			(stroke
				(width 0.1)
				(type default)
			)
			(layer "F.Fab")
		)
		(pad "1" smd rect
			(at -1.4732 0 90)
			(size 1.1684 1.5748)
			(layers "F.Cu" "F.Mask" "F.Paste")
			(net "P52V_HS")
		)
		(pad "2" smd rect
			(at 1.4732 0 90)
			(size 1.1684 1.5748)
			(layers "F.Cu" "F.Mask" "F.Paste")
			(net "GND")
		)
	)
	(footprint ""
		(layer "F.Cu")
		(at 209.931 -85.725)
		(property "Reference" "R63"
			(at 0 0 0)
			(layer "F.SilkS")
			(hide yes)
			(effects
				(font
					(size 1.27 1.27)
				)
			)
		)
		(property "Value" ""
			(at 0 0 0)
			(layer "F.Fab")
			(effects
				(font
					(size 1.27 1.27)
				)
			)
		)
		(duplicate_pad_numbers_are_jumpers no)
		(fp_line
			(start -2.234946 -0.9271)
			(end 2.234946 -0.9271)
			(stroke
				(width 0.1524)
				(type default)
			)
			(layer "F.SilkS")
		)
		(fp_line
			(start -2.234946 0.9271)
			(end -2.234946 -0.9271)
			(stroke
				(width 0.1524)
				(type default)
			)
			(layer "F.SilkS")
		)
		(fp_line
			(start 2.234946 -0.9271)
			(end 2.234946 0.9271)
			(stroke
				(width 0.1524)
				(type default)
			)
			(layer "F.SilkS")
		)
		(fp_line
			(start 2.234946 0.9271)
			(end -2.234946 0.9271)
			(stroke
				(width 0.1524)
				(type default)
			)
			(layer "F.SilkS")
		)
		(fp_line
			(start -1.575054 -0.824992)
			(end -1.575054 0.824992)
			(stroke
				(width 0.1)
				(type default)
			)
			(layer "F.Fab")
		)
		(fp_line
			(start -1.575054 0.824992)
			(end 1.575054 0.824992)
			(stroke
				(width 0.1)
				(type default)
			)
			(layer "F.Fab")
		)
		(fp_line
			(start 1.575054 -0.824992)
			(end -1.575054 -0.824992)
			(stroke
				(width 0.1)
				(type default)
			)
			(layer "F.Fab")
		)
		(fp_line
			(start 1.575054 0.824992)
			(end 1.575054 -0.824992)
			(stroke
				(width 0.1)
				(type default)
			)
			(layer "F.Fab")
		)
		(pad "1" smd rect
			(at -1.599946 0)
			(size 1.016 1.6002)
			(layers "F.Cu" "F.Mask" "F.Paste")
			(net "LED_D1_R4")
		)
		(pad "2" smd rect
			(at 1.599946 0)
			(size 1.016 1.6002)
			(layers "F.Cu" "F.Mask" "F.Paste")
			(net "LED_D1_R5")
		)
	)
	(footprint ""
		(layer "F.Cu")
		(at 162.687 -51.816)
		(property "Reference" "PC34"
			(at 0 0 0)
			(layer "F.SilkS")
			(hide yes)
			(effects
				(font
					(size 1.27 1.27)
				)
			)
		)
		(property "Value" ""
			(at 0 0 0)
			(layer "F.Fab")
			(effects
				(font
					(size 1.27 1.27)
				)
			)
		)
		(duplicate_pad_numbers_are_jumpers no)
		(fp_line
			(start -1.524 -0.762)
			(end 1.524 -0.762)
			(stroke
				(width 0.1524)
				(type default)
			)
			(layer "F.SilkS")
		)
		(fp_line
			(start -1.524 0.762)
			(end -1.524 -0.762)
			(stroke
				(width 0.1524)
				(type default)
			)
			(layer "F.SilkS")
		)
		(fp_line
			(start 1.524 -0.762)
			(end 1.524 0.762)
			(stroke
				(width 0.1524)
				(type default)
			)
			(layer "F.SilkS")
		)
		(fp_line
			(start 1.524 0.762)
			(end -1.524 0.762)
			(stroke
				(width 0.1524)
				(type default)
			)
			(layer "F.SilkS")
		)
		(fp_line
			(start -1.1049 -0.724916)
			(end -1.1049 0.724916)
			(stroke
				(width 0.1)
				(type default)
			)
			(layer "F.Fab")
		)
		(fp_line
			(start -1.1049 0.724916)
			(end 1.1049 0.724916)
			(stroke
				(width 0.1)
				(type default)
			)
			(layer "F.Fab")
		)
		(fp_line
			(start 1.1049 -0.724916)
			(end -1.1049 -0.724916)
			(stroke
				(width 0.1)
				(type default)
			)
			(layer "F.Fab")
		)
		(fp_line
			(start 1.1049 0.724916)
			(end 1.1049 -0.724916)
			(stroke
				(width 0.1)
				(type default)
			)
			(layer "F.Fab")
		)
		(pad "1" smd rect
			(at -0.889 0 180)
			(size 1.016 1.27)
			(layers "F.Cu" "F.Mask" "F.Paste")
			(net "P12V_BRICK")
		)
		(pad "2" smd rect
			(at 0.889 0 180)
			(size 1.016 1.27)
			(layers "F.Cu" "F.Mask" "F.Paste")
			(net "GND")
		)
	)
	(footprint ""
		(layer "F.Cu")
		(at 172.0596 -12.4968 90)
		(property "Reference" "PC101"
			(at 0 0 90)
			(layer "F.SilkS")
			(hide yes)
			(effects
				(font
					(size 1.27 1.27)
				)
			)
		)
		(property "Value" ""
			(at 0 0 90)
			(layer "F.Fab")
			(effects
				(font
					(size 1.27 1.27)
				)
			)
		)
		(duplicate_pad_numbers_are_jumpers no)
		(fp_line
			(start 1.524 -0.762)
			(end 1.524 0.762)
			(stroke
				(width 0.1524)
				(type default)
			)
			(layer "F.SilkS")
		)
		(fp_line
			(start -1.524 -0.762)
			(end 1.524 -0.762)
			(stroke
				(width 0.1524)
				(type default)
			)
			(layer "F.SilkS")
		)
		(fp_line
			(start 1.524 0.762)
			(end -1.524 0.762)
			(stroke
				(width 0.1524)
				(type default)
			)
			(layer "F.SilkS")
		)
		(fp_line
			(start -1.524 0.762)
			(end -1.524 -0.762)
			(stroke
				(width 0.1524)
				(type default)
			)
			(layer "F.SilkS")
		)
		(fp_line
			(start 1.1049 -0.724916)
			(end -1.1049 -0.724916)
			(stroke
				(width 0.1)
				(type default)
			)
			(layer "F.Fab")
		)
		(fp_line
			(start -1.1049 -0.724916)
			(end -1.1049 0.724916)
			(stroke
				(width 0.1)
				(type default)
			)
			(layer "F.Fab")
		)
		(fp_line
			(start 1.1049 0.724916)
			(end 1.1049 -0.724916)
			(stroke
				(width 0.1)
				(type default)
			)
			(layer "F.Fab")
		)
		(fp_line
			(start -1.1049 0.724916)
			(end 1.1049 0.724916)
			(stroke
				(width 0.1)
				(type default)
			)
			(layer "F.Fab")
		)
		(pad "1" smd rect
			(at -0.889 0 270)
			(size 1.016 1.27)
			(layers "F.Cu" "F.Mask" "F.Paste")
			(net "SW_P12V_FILT__P3V3_AUX")
		)
		(pad "2" smd rect
			(at 0.889 0 270)
			(size 1.016 1.27)
			(layers "F.Cu" "F.Mask" "F.Paste")
			(net "GND")
		)
	)
	(footprint ""
		(layer "F.Cu")
		(at 177.8 -12.0142)
		(property "Reference" "PU5"
			(at -1.397 -3.83413 0)
			(unlocked yes)
			(layer "F.SilkS")
			(effects
				(font
					(size 0.7874 0.5842)
					(thickness 0.1524)
				)
				(justify left)
			)
		)
		(property "Value" ""
			(at 0 0 0)
			(layer "F.Fab")
			(effects
				(font
					(size 1.27 1.27)
				)
			)
		)
		(duplicate_pad_numbers_are_jumpers no)
		(fp_line
			(start -1.050036 -1.549908)
			(end -0.503936 -1.549908)
			(stroke
				(width 0.1524)
				(type default)
			)
			(layer "F.SilkS")
		)
		(fp_line
			(start -1.050036 -1.253998)
			(end -1.050036 -1.549908)
			(stroke
				(width 0.1524)
				(type default)
			)
			(layer "F.SilkS")
		)
		(fp_line
			(start -1.050036 1.549908)
			(end -1.050036 1.253998)
			(stroke
				(width 0.1524)
				(type default)
			)
			(layer "F.SilkS")
		)
		(fp_line
			(start -0.503936 1.549908)
			(end -1.050036 1.549908)
			(stroke
				(width 0.1524)
				(type default)
			)
			(layer "F.SilkS")
		)
		(fp_line
			(start 0.503936 -1.549908)
			(end 1.050036 -1.549908)
			(stroke
				(width 0.1524)
				(type default)
			)
			(layer "F.SilkS")
		)
		(fp_line
			(start 1.050036 -1.549908)
			(end 1.050036 -1.253998)
			(stroke
				(width 0.1524)
				(type default)
			)
			(layer "F.SilkS")
		)
		(fp_line
			(start 1.050036 1.253998)
			(end 1.050036 1.549908)
			(stroke
				(width 0.1524)
				(type default)
			)
			(layer "F.SilkS")
		)
		(fp_line
			(start 1.050036 1.549908)
			(end 0.503936 1.549908)
			(stroke
				(width 0.1524)
				(type default)
			)
			(layer "F.SilkS")
		)
		(fp_poly
			(pts
				(xy -1.651 -0.847598) (xy -1.651 -1.152398) (xy -1.3462 -0.999998)
			)
			(stroke
				(width 0)
				(type default)
			)
			(fill yes)
			(layer "F.SilkS")
		)
		(fp_line
			(start -1.050036 -1.549908)
			(end 1.050036 -1.549908)
			(stroke
				(width 0.1)
				(type default)
			)
			(layer "F.Fab")
		)
		(fp_line
			(start -1.050036 1.549908)
			(end -1.050036 -1.549908)
			(stroke
				(width 0.1)
				(type default)
			)
			(layer "F.Fab")
		)
		(fp_line
			(start 1.050036 -1.549908)
			(end 1.050036 1.549908)
			(stroke
				(width 0.1)
				(type default)
			)
			(layer "F.Fab")
		)
		(fp_line
			(start 1.050036 1.549908)
			(end -1.050036 1.549908)
			(stroke
				(width 0.1)
				(type default)
			)
			(layer "F.Fab")
		)
		(fp_poly
			(pts
				(xy -2.2352 -0.618998) (xy -2.2352 -1.380998) (xy -1.4732 -0.999998)
			)
			(stroke
				(width 0)
				(type default)
			)
			(fill yes)
			(layer "F.Fab")
		)
		(pad "1" smd circle
			(at -0.94996 -0.999998 270)
			(size 0 0)
			(layers "F.Cu" "F.Mask" "F.Paste")
			(net "GND")
		)
		(pad "2" smd rect
			(at -0.849884 -0.499872 90)
			(size 0.254 0.9144)
			(layers "F.Cu" "F.Mask" "F.Paste")
			(net "SW_P3V3_AUX_PH")
		)
		(pad "3" smd rect
			(at -0.649986 0 90)
			(size 0.254 1.3208)
			(layers "F.Cu" "F.Mask" "F.Paste")
			(net "SW_P12V_FILT__P3V3_AUX")
		)
		(pad "4" smd rect
			(at -0.849884 0.499872 90)
			(size 0.254 0.9144)
			(layers "F.Cu" "F.Mask" "F.Paste")
			(net "P3V3_AUX_CS")
		)
		(pad "5" smd circle
			(at -0.94996 0.999998 270)
			(size 0 0)
			(layers "F.Cu" "F.Mask" "F.Paste")
			(net "P12V_BRICK0_PWRGD")
		)
		(pad "6" smd circle
			(at -0.249936 1.450086)
			(size 0 0)
			(layers "F.Cu" "F.Mask" "F.Paste")
			(net "P3V3_AUX_FB")
		)
		(pad "7" smd circle
			(at 0.249936 1.450086)
			(size 0 0)
			(layers "F.Cu" "F.Mask" "F.Paste")
			(net "GND")
		)
		(pad "8" smd circle
			(at 0.94996 0.999998 90)
			(size 0 0)
			(layers "F.Cu" "F.Mask" "F.Paste")
			(net "P3V3_AUX_REF")
		)
		(pad "9" smd rect
			(at 0.849884 0.499872 90)
			(size 0.254 0.9144)
			(layers "F.Cu" "F.Mask" "F.Paste")
			(net "P3V3_AUX_PWRGD")
		)
		(pad "10" smd rect
			(at 0.849884 0 90)
			(size 0.254 0.9144)
			(layers "F.Cu" "F.Mask" "F.Paste")
			(net "SW_P3V3_AUX_BT")
		)
		(pad "11" smd rect
			(at 0.849884 -0.499872 90)
			(size 0.254 0.9144)
			(layers "F.Cu" "F.Mask" "F.Paste")
			(net "SW_P3V3_AUX_PH")
		)
		(pad "12" smd circle
			(at 0.94996 -0.999998 90)
			(size 0 0)
			(layers "F.Cu" "F.Mask" "F.Paste")
			(net "P3V3_AUX_MODE")
		)
		(pad "13" smd circle
			(at 0.249936 -1.450086 180)
			(size 0 0)
			(layers "F.Cu" "F.Mask" "F.Paste")
			(net "P3V3_AUX_VCC")
		)
		(pad "14" smd circle
			(at -0.249936 -1.450086 180)
			(size 0 0)
			(layers "F.Cu" "F.Mask" "F.Paste")
			(net "GND")
		)
	)
	(footprint ""
		(layer "F.Cu")
		(at 296.164 -36.703 -90)
		(property "Reference" "R5886"
			(at 0 0 270)
			(layer "F.SilkS")
			(hide yes)
			(effects
				(font
					(size 1.27 1.27)
				)
			)
		)
		(property "Value" ""
			(at 0 0 270)
			(layer "F.Fab")
			(effects
				(font
					(size 1.27 1.27)
				)
			)
		)
		(duplicate_pad_numbers_are_jumpers no)
		(fp_line
			(start -1.651 0.8382)
			(end -1.651 -0.8382)
			(stroke
				(width 0.1524)
				(type default)
			)
			(layer "F.SilkS")
		)
		(fp_line
			(start 1.651 0.8382)
			(end -1.651 0.8382)
			(stroke
				(width 0.1524)
				(type default)
			)
			(layer "F.SilkS")
		)
		(fp_line
			(start -1.651 -0.8382)
			(end 1.651 -0.8382)
			(stroke
				(width 0.1524)
				(type default)
			)
			(layer "F.SilkS")
		)
		(fp_line
			(start 1.651 -0.8382)
			(end 1.651 0.8382)
			(stroke
				(width 0.1524)
				(type default)
			)
			(layer "F.SilkS")
		)
		(fp_line
			(start -1.559814 0.7366)
			(end -1.524 0.7366)
			(stroke
				(width 0.1)
				(type default)
			)
			(layer "F.Fab")
		)
		(fp_line
			(start -1.524 0.7366)
			(end 1.524 0.7366)
			(stroke
				(width 0.1)
				(type default)
			)
			(layer "F.Fab")
		)
		(fp_line
			(start 1.524 0.7366)
			(end 1.560576 0.7366)
			(stroke
				(width 0.1)
				(type default)
			)
			(layer "F.Fab")
		)
		(fp_line
			(start 1.560576 0.7366)
			(end 1.560576 -0.7366)
			(stroke
				(width 0.1)
				(type default)
			)
			(layer "F.Fab")
		)
		(fp_line
			(start -1.559814 -0.7366)
			(end -1.559814 0.7366)
			(stroke
				(width 0.1)
				(type default)
			)
			(layer "F.Fab")
		)
		(fp_line
			(start -1.524 -0.7366)
			(end -1.559814 -0.7366)
			(stroke
				(width 0.1)
				(type default)
			)
			(layer "F.Fab")
		)
		(fp_line
			(start 1.524 -0.7366)
			(end -1.524 -0.7366)
			(stroke
				(width 0.1)
				(type default)
			)
			(layer "F.Fab")
		)
		(fp_line
			(start 1.560576 -0.7366)
			(end 1.524 -0.7366)
			(stroke
				(width 0.1)
				(type default)
			)
			(layer "F.Fab")
		)
		(pad "1" smd rect
			(at -0.94996 0 90)
			(size 1.1176 1.3716)
			(layers "F.Cu" "F.Mask" "F.Paste")
			(net "P52V_1_FUSE_1")
		)
		(pad "2" smd rect
			(at 0.94996 0 90)
			(size 1.1176 1.3716)
			(layers "F.Cu" "F.Mask" "F.Paste")
			(net "FM_HSC_EN_FUSE")
		)
	)
	(footprint ""
		(layer "F.Cu")
		(at 209.931 -87.757 180)
		(property "Reference" "R62"
			(at 0 0 180)
			(layer "F.SilkS")
			(hide yes)
			(effects
				(font
					(size 1.27 1.27)
				)
			)
		)
		(property "Value" ""
			(at 0 0 180)
			(layer "F.Fab")
			(effects
				(font
					(size 1.27 1.27)
				)
			)
		)
		(duplicate_pad_numbers_are_jumpers no)
		(fp_line
			(start 2.234946 0.9271)
			(end -2.234946 0.9271)
			(stroke
				(width 0.1524)
				(type default)
			)
			(layer "F.SilkS")
		)
		(fp_line
			(start 2.234946 -0.9271)
			(end 2.234946 0.9271)
			(stroke
				(width 0.1524)
				(type default)
			)
			(layer "F.SilkS")
		)
		(fp_line
			(start -2.234946 0.9271)
			(end -2.234946 -0.9271)
			(stroke
				(width 0.1524)
				(type default)
			)
			(layer "F.SilkS")
		)
		(fp_line
			(start -2.234946 -0.9271)
			(end 2.234946 -0.9271)
			(stroke
				(width 0.1524)
				(type default)
			)
			(layer "F.SilkS")
		)
		(fp_line
			(start 1.575054 0.824992)
			(end 1.575054 -0.824992)
			(stroke
				(width 0.1)
				(type default)
			)
			(layer "F.Fab")
		)
		(fp_line
			(start 1.575054 -0.824992)
			(end -1.575054 -0.824992)
			(stroke
				(width 0.1)
				(type default)
			)
			(layer "F.Fab")
		)
		(fp_line
			(start -1.575054 0.824992)
			(end 1.575054 0.824992)
			(stroke
				(width 0.1)
				(type default)
			)
			(layer "F.Fab")
		)
		(fp_line
			(start -1.575054 -0.824992)
			(end -1.575054 0.824992)
			(stroke
				(width 0.1)
				(type default)
			)
			(layer "F.Fab")
		)
		(pad "1" smd rect
			(at -1.599946 0 180)
			(size 1.016 1.6002)
			(layers "F.Cu" "F.Mask" "F.Paste")
			(net "LED_D1_R3")
		)
		(pad "2" smd rect
			(at 1.599946 0 180)
			(size 1.016 1.6002)
			(layers "F.Cu" "F.Mask" "F.Paste")
			(net "LED_D1_R4")
		)
	)
	(footprint ""
		(layer "F.Cu")
		(at 179.065174 -61.849)
		(property "Reference" "PC123"
			(at 0 0 0)
			(layer "F.SilkS")
			(hide yes)
			(effects
				(font
					(size 1.27 1.27)
				)
			)
		)
		(property "Value" ""
			(at 0 0 0)
			(layer "F.Fab")
			(effects
				(font
					(size 1.27 1.27)
				)
			)
		)
		(duplicate_pad_numbers_are_jumpers no)
		(fp_line
			(start -0.7874 -0.4064)
			(end 0.7874 -0.4064)
			(stroke
				(width 0.1524)
				(type default)
			)
			(layer "F.SilkS")
		)
		(fp_line
			(start -0.7874 0.4064)
			(end -0.7874 -0.4064)
			(stroke
				(width 0.1524)
				(type default)
			)
			(layer "F.SilkS")
		)
		(fp_line
			(start 0.7874 -0.4064)
			(end 0.7874 0.4064)
			(stroke
				(width 0.1524)
				(type default)
			)
			(layer "F.SilkS")
		)
		(fp_line
			(start 0.7874 0.4064)
			(end -0.7874 0.4064)
			(stroke
				(width 0.1524)
				(type default)
			)
			(layer "F.SilkS")
		)
		(fp_line
			(start -0.6858 -0.3048)
			(end -0.1016 -0.3048)
			(stroke
				(width 0.1)
				(type default)
			)
			(layer "F.Fab")
		)
		(fp_line
			(start -0.6858 0.3048)
			(end -0.6858 -0.3048)
			(stroke
				(width 0.1)
				(type default)
			)
			(layer "F.Fab")
		)
		(fp_line
			(start -0.1016 -0.3048)
			(end -0.1016 -0.2794)
			(stroke
				(width 0.1)
				(type default)
			)
			(layer "F.Fab")
		)
		(fp_line
			(start -0.1016 -0.2794)
			(end 0.1016 -0.2794)
			(stroke
				(width 0.1)
				(type default)
			)
			(layer "F.Fab")
		)
		(fp_line
			(start -0.1016 0.2794)
			(end -0.1016 0.3048)
			(stroke
				(width 0.1)
				(type default)
			)
			(layer "F.Fab")
		)
		(fp_line
			(start -0.1016 0.3048)
			(end -0.6858 0.3048)
			(stroke
				(width 0.1)
				(type default)
			)
			(layer "F.Fab")
		)
		(fp_line
			(start 0.1016 -0.3048)
			(end 0.6858 -0.3048)
			(stroke
				(width 0.1)
				(type default)
			)
			(layer "F.Fab")
		)
		(fp_line
			(start 0.1016 -0.2794)
			(end 0.1016 -0.3048)
			(stroke
				(width 0.1)
				(type default)
			)
			(layer "F.Fab")
		)
		(fp_line
			(start 0.1016 0.2794)
			(end -0.1016 0.2794)
			(stroke
				(width 0.1)
				(type default)
			)
			(layer "F.Fab")
		)
		(fp_line
			(start 0.1016 0.3048)
			(end 0.1016 0.2794)
			(stroke
				(width 0.1)
				(type default)
			)
			(layer "F.Fab")
		)
		(fp_line
			(start 0.6858 -0.3048)
			(end 0.6858 0.3048)
			(stroke
				(width 0.1)
				(type default)
			)
			(layer "F.Fab")
		)
		(fp_line
			(start 0.6858 0.3048)
			(end 0.1016 0.3048)
			(stroke
				(width 0.1)
				(type default)
			)
			(layer "F.Fab")
		)
		(pad "1" smd rect
			(at -0.40005 0 180)
			(size 0.4572 0.508)
			(layers "F.Cu" "F.Mask" "F.Paste")
			(net "P12V_BRICK")
		)
		(pad "2" smd rect
			(at 0.40005 0 180)
			(size 0.4572 0.508)
			(layers "F.Cu" "F.Mask" "F.Paste")
			(net "GND")
		)
	)
	(footprint ""
		(layer "F.Cu")
		(at 280.39568 -126.477268)
		(property "Reference" "PQ1"
			(at -7.72668 -5.703062 0)
			(unlocked yes)
			(layer "F.SilkS")
			(effects
				(font
					(size 0.7874 0.5842)
					(thickness 0.1524)
				)
				(justify left)
			)
		)
		(property "Value" ""
			(at 0 0 0)
			(layer "F.Fab")
			(effects
				(font
					(size 1.27 1.27)
				)
			)
		)
		(duplicate_pad_numbers_are_jumpers no)
		(fp_line
			(start -7.649972 -4.99999)
			(end -7.649972 -3.3274)
			(stroke
				(width 0.1524)
				(type default)
			)
			(layer "F.SilkS")
		)
		(fp_line
			(start -7.649972 -1.7526)
			(end -7.649972 1.7526)
			(stroke
				(width 0.1524)
				(type default)
			)
			(layer "F.SilkS")
		)
		(fp_line
			(start -7.649972 3.3274)
			(end -7.649972 4.99999)
			(stroke
				(width 0.1524)
				(type default)
			)
			(layer "F.SilkS")
		)
		(fp_line
			(start -7.649972 4.99999)
			(end 5.115814 4.99999)
			(stroke
				(width 0.1524)
				(type default)
			)
			(layer "F.SilkS")
		)
		(fp_line
			(start 5.115814 -4.99999)
			(end -7.649972 -4.99999)
			(stroke
				(width 0.1524)
				(type default)
			)
			(layer "F.SilkS")
		)
		(fp_line
			(start 7.630414 4.99999)
			(end 7.649972 4.99999)
			(stroke
				(width 0.1524)
				(type default)
			)
			(layer "F.SilkS")
		)
		(fp_line
			(start 7.649972 -4.99999)
			(end 7.630414 -4.99999)
			(stroke
				(width 0.1524)
				(type default)
			)
			(layer "F.SilkS")
		)
		(fp_line
			(start 7.649972 4.99999)
			(end 7.649972 -4.99999)
			(stroke
				(width 0.1524)
				(type default)
			)
			(layer "F.SilkS")
		)
		(fp_line
			(start -7.649972 -4.99999)
			(end -7.649972 4.99999)
			(stroke
				(width 0.1)
				(type default)
			)
			(layer "F.Fab")
		)
		(fp_line
			(start -7.649972 4.99999)
			(end 7.649972 4.99999)
			(stroke
				(width 0.1)
				(type default)
			)
			(layer "F.Fab")
		)
		(fp_line
			(start 7.649972 -4.99999)
			(end -7.649972 -4.99999)
			(stroke
				(width 0.1)
				(type default)
			)
			(layer "F.Fab")
		)
		(fp_line
			(start 7.649972 4.99999)
			(end 7.649972 -4.99999)
			(stroke
				(width 0.1)
				(type default)
			)
			(layer "F.Fab")
		)
		(pad "D" smd circle
			(at 2.15011 0)
			(size 0 0)
			(layers "F.Cu" "F.Mask" "F.Paste")
			(net "P52V_HS1_DRAIN_1")
		)
		(pad "G" smd rect
			(at -7.050024 -2.54 270)
			(size 1.3208 3.0988)
			(layers "F.Cu" "F.Mask" "F.Paste")
			(net "P52V_HS1_GATE1")
		)
		(pad "S" smd rect
			(at -7.050024 2.54 270)
			(size 1.3208 3.0988)
			(layers "F.Cu" "F.Mask" "F.Paste")
			(net "P52V_HS")
		)
		(zone
			(layer "F.Cu")
			(hatch none 0.5)
			(connect_pads
				(clearance 0)
			)
			(min_thickness 0.25)
			(keepout
				(tracks not_allowed)
				(vias allowed)
				(pads allowed)
				(copperpour not_allowed)
				(footprints allowed)
			)
			(placement
				(enabled no)
				(sheetname "")
			)
			(fill
				(thermal_gap 0.5)
				(thermal_bridge_width 0.5)
				(island_removal_mode 0)
			)
			(polygon
				(pts
					(xy 285.57728 -131.455668) (xy 272.75028 -131.455668) (xy 272.75028 -129.728468) (xy 274.96008 -129.728468)
					(xy 274.96008 -128.306068) (xy 272.75028 -128.306068) (xy 272.75028 -124.648468) (xy 274.96008 -124.648468)
					(xy 274.96008 -123.226068) (xy 272.75028 -123.226068) (xy 272.75028 -121.498868) (xy 285.57728 -121.498868)
					(xy 285.57728 -122.667268) (xy 279.37968 -122.667268) (xy 279.37968 -130.287268) (xy 285.57728 -130.287268)
				)
			)
		)
	)
	(footprint ""
		(layer "F.Cu")
		(at 184.470294 -121.209816)
		(property "Reference" "PU6"
			(at -26.563066 -5.12953 0)
			(unlocked yes)
			(layer "F.SilkS")
			(effects
				(font
					(size 0.7874 0.5842)
					(thickness 0.1524)
				)
				(justify left)
			)
		)
		(property "Value" ""
			(at 0 0 0)
			(layer "F.Fab")
			(effects
				(font
					(size 1.27 1.27)
				)
			)
		)
		(duplicate_pad_numbers_are_jumpers no)
		(fp_line
			(start -26.519886 -4.299966)
			(end -26.519886 55.099966)
			(stroke
				(width 0.1524)
				(type default)
			)
			(layer "F.SilkS")
		)
		(fp_line
			(start -26.519886 55.099966)
			(end 11.279886 55.099966)
			(stroke
				(width 0.1524)
				(type default)
			)
			(layer "F.SilkS")
		)
		(fp_line
			(start -26.020014 -3.800094)
			(end -26.020014 54.59984)
			(stroke
				(width 0.1524)
				(type default)
			)
			(layer "F.SilkS")
		)
		(fp_line
			(start -26.020014 54.59984)
			(end 10.780014 54.59984)
			(stroke
				(width 0.1524)
				(type default)
			)
			(layer "F.SilkS")
		)
		(fp_line
			(start 10.780014 -3.800094)
			(end -26.020014 -3.800094)
			(stroke
				(width 0.1524)
				(type default)
			)
			(layer "F.SilkS")
		)
		(fp_line
			(start 10.780014 54.59984)
			(end 10.780014 -3.800094)
			(stroke
				(width 0.1524)
				(type default)
			)
			(layer "F.SilkS")
		)
		(fp_line
			(start 11.279886 -4.299966)
			(end -26.519886 -4.299966)
			(stroke
				(width 0.1524)
				(type default)
			)
			(layer "F.SilkS")
		)
		(fp_line
			(start 11.279886 55.099966)
			(end 11.279886 -4.299966)
			(stroke
				(width 0.1524)
				(type default)
			)
			(layer "F.SilkS")
		)
		(fp_poly
			(pts
				(xy 1.27 -7.44728) (xy -1.27 -7.44728) (xy 0 -4.90728)
			)
			(stroke
				(width 0)
				(type default)
			)
			(fill yes)
			(layer "F.SilkS")
		)
		(fp_line
			(start -26.020014 -3.800094)
			(end -26.020014 54.59984)
			(stroke
				(width 0.1)
				(type default)
			)
			(layer "F.Fab")
		)
		(fp_line
			(start -26.020014 54.59984)
			(end 10.780014 54.59984)
			(stroke
				(width 0.1)
				(type default)
			)
			(layer "F.Fab")
		)
		(fp_line
			(start 10.780014 -3.800094)
			(end -26.020014 -3.800094)
			(stroke
				(width 0.1)
				(type default)
			)
			(layer "F.Fab")
		)
		(fp_line
			(start 10.780014 54.59984)
			(end 10.780014 -3.800094)
			(stroke
				(width 0.1)
				(type default)
			)
			(layer "F.Fab")
		)
		(fp_poly
			(pts
				(xy 1.27 -7.44728) (xy -1.27 -7.44728) (xy 0 -4.90728)
			)
			(stroke
				(width 0)
				(type default)
			)
			(fill yes)
			(layer "F.Fab")
		)
		(pad "1" thru_hole rect
			(at 0 0 270)
			(size 2.3622 2.3622)
			(drill 1.6002)
			(layers "*.Cu" "*.Mask")
			(remove_unused_layers no)
			(net "P52V_HS_FILTER")
			(clearance -0.127)
			(padstack
				(mode front_inner_back)
				(layer "Inner"
					(shape circle)
					(size 2.3622 2.3622)
					(clearance -0.127)
				)
				(layer "B.Cu"
					(shape rect)
					(size 2.3622 2.3622)
					(clearance -0.127)
				)
			)
		)
		(pad "2" thru_hole circle
			(at -7.62 0 270)
			(size 2.3622 2.3622)
			(drill 1.6002)
			(layers "*.Cu" "*.Mask")
			(remove_unused_layers no)
			(net "BRICK_P12V2_ON_OFF_R")
			(clearance -0.127)
		)
		(pad "3" thru_hole circle
			(at -15.24 0 270)
			(size 2.3622 2.3622)
			(drill 1.6002)
			(layers "*.Cu" "*.Mask")
			(remove_unused_layers no)
			(net "GND")
			(clearance -0.127)
		)
		(pad "4" thru_hole circle
			(at -19.05 50.8 270)
			(size 3.1242 3.1242)
			(drill 2.1082)
			(layers "*.Cu" "*.Mask")
			(remove_unused_layers no)
			(net "GND")
			(clearance -0.254)
		)
		(pad "5" thru_hole circle
			(at -15.24 50.8 270)
			(size 3.1242 3.1242)
			(drill 2.1082)
			(layers "*.Cu" "*.Mask")
			(remove_unused_layers no)
			(net "GND")
			(clearance -0.254)
		)
		(pad "6" thru_hole circle
			(at 0 50.8 270)
			(size 3.1242 3.1242)
			(drill 2.1082)
			(layers "*.Cu" "*.Mask")
			(remove_unused_layers no)
			(net "P12V_BRICK")
			(clearance -0.254)
		)
		(pad "7" thru_hole circle
			(at 3.81 50.8 270)
			(size 3.1242 3.1242)
			(drill 2.1082)
			(layers "*.Cu" "*.Mask")
			(remove_unused_layers no)
			(net "P12V_BRICK")
			(clearance -0.254)
		)
		(pad "8" thru_hole circle
			(at -13.619988 53.34 270)
			(size 1.3208 1.3208)
			(drill 0.9144)
			(layers "*.Cu" "*.Mask")
			(remove_unused_layers no)
			(net "P12V_BRICK_PWRGD")
			(clearance 0.0508)
			(thermal_gap 0.0508)
		)
		(pad "9" thru_hole circle
			(at -11.619992 53.34 270)
			(size 1.3208 1.3208)
			(drill 0.9144)
			(layers "*.Cu" "*.Mask")
			(remove_unused_layers no)
			(net "P12V_MB2_SENSE-")
			(clearance 0.0508)
			(thermal_gap 0.0508)
		)
		(pad "10" thru_hole circle
			(at -9.619996 53.34 270)
			(size 1.3208 1.3208)
			(drill 0.9144)
			(layers "*.Cu" "*.Mask")
			(remove_unused_layers no)
			(net "SMB_BRICK2_SDA")
			(clearance 0.0508)
			(thermal_gap 0.0508)
		)
		(pad "11" thru_hole circle
			(at -7.62 53.34 270)
			(size 1.3208 1.3208)
			(drill 0.9144)
			(layers "*.Cu" "*.Mask")
			(remove_unused_layers no)
			(net "SMB_BRICK2_ALERT")
			(clearance 0.0508)
			(thermal_gap 0.0508)
		)
		(pad "12" thru_hole circle
			(at -5.620004 53.34 270)
			(size 1.3208 1.3208)
			(drill 0.9144)
			(layers "*.Cu" "*.Mask")
			(remove_unused_layers no)
			(net "SMB_BRICK2_SCL")
			(clearance 0.0508)
			(thermal_gap 0.0508)
		)
		(pad "13" thru_hole circle
			(at -3.620008 53.34 270)
			(size 1.3208 1.3208)
			(drill 0.9144)
			(layers "*.Cu" "*.Mask")
			(remove_unused_layers no)
			(net "BRICK2_PMBADD")
			(clearance 0.0508)
			(thermal_gap 0.0508)
		)
		(pad "14" thru_hole circle
			(at -1.620012 53.34 270)
			(size 1.3208 1.3208)
			(drill 0.9144)
			(layers "*.Cu" "*.Mask")
			(remove_unused_layers no)
			(net "P12V_MB2_SENSE+")
			(clearance 0.0508)
			(thermal_gap 0.0508)
		)
	)
	(footprint ""
		(layer "F.Cu")
		(at 280.39568 -78.217268)
		(property "Reference" "PQ5"
			(at -7.723886 -5.895848 0)
			(unlocked yes)
			(layer "F.SilkS")
			(effects
				(font
					(size 0.7874 0.5842)
					(thickness 0.1524)
				)
				(justify left)
			)
		)
		(property "Value" ""
			(at 0 0 0)
			(layer "F.Fab")
			(effects
				(font
					(size 1.27 1.27)
				)
			)
		)
		(duplicate_pad_numbers_are_jumpers no)
		(fp_line
			(start -7.649972 -4.99999)
			(end -7.649972 -3.3274)
			(stroke
				(width 0.1524)
				(type default)
			)
			(layer "F.SilkS")
		)
		(fp_line
			(start -7.649972 -1.7526)
			(end -7.649972 1.7526)
			(stroke
				(width 0.1524)
				(type default)
			)
			(layer "F.SilkS")
		)
		(fp_line
			(start -7.649972 3.3274)
			(end -7.649972 4.99999)
			(stroke
				(width 0.1524)
				(type default)
			)
			(layer "F.SilkS")
		)
		(fp_line
			(start -7.649972 4.99999)
			(end 5.115814 4.99999)
			(stroke
				(width 0.1524)
				(type default)
			)
			(layer "F.SilkS")
		)
		(fp_line
			(start 5.115814 -4.99999)
			(end -7.649972 -4.99999)
			(stroke
				(width 0.1524)
				(type default)
			)
			(layer "F.SilkS")
		)
		(fp_line
			(start 7.630414 4.99999)
			(end 7.649972 4.99999)
			(stroke
				(width 0.1524)
				(type default)
			)
			(layer "F.SilkS")
		)
		(fp_line
			(start 7.649972 -4.99999)
			(end 7.630414 -4.99999)
			(stroke
				(width 0.1524)
				(type default)
			)
			(layer "F.SilkS")
		)
		(fp_line
			(start 7.649972 4.99999)
			(end 7.649972 -4.99999)
			(stroke
				(width 0.1524)
				(type default)
			)
			(layer "F.SilkS")
		)
		(fp_line
			(start -7.649972 -4.99999)
			(end -7.649972 4.99999)
			(stroke
				(width 0.1)
				(type default)
			)
			(layer "F.Fab")
		)
		(fp_line
			(start -7.649972 4.99999)
			(end 7.649972 4.99999)
			(stroke
				(width 0.1)
				(type default)
			)
			(layer "F.Fab")
		)
		(fp_line
			(start 7.649972 -4.99999)
			(end -7.649972 -4.99999)
			(stroke
				(width 0.1)
				(type default)
			)
			(layer "F.Fab")
		)
		(fp_line
			(start 7.649972 4.99999)
			(end 7.649972 -4.99999)
			(stroke
				(width 0.1)
				(type default)
			)
			(layer "F.Fab")
		)
		(pad "D" smd circle
			(at 2.15011 0)
			(size 0 0)
			(layers "F.Cu" "F.Mask" "F.Paste")
			(net "P52V_HS1_DRAIN_2")
		)
		(pad "G" smd rect
			(at -7.050024 -2.54 270)
			(size 1.3208 3.0988)
			(layers "F.Cu" "F.Mask" "F.Paste")
			(net "P52V_HS1_GATE5")
		)
		(pad "S" smd rect
			(at -7.050024 2.54 270)
			(size 1.3208 3.0988)
			(layers "F.Cu" "F.Mask" "F.Paste")
			(net "P52V_HS")
		)
		(zone
			(layer "F.Cu")
			(hatch none 0.5)
			(connect_pads
				(clearance 0)
			)
			(min_thickness 0.25)
			(keepout
				(tracks not_allowed)
				(vias allowed)
				(pads allowed)
				(copperpour not_allowed)
				(footprints allowed)
			)
			(placement
				(enabled no)
				(sheetname "")
			)
			(fill
				(thermal_gap 0.5)
				(thermal_bridge_width 0.5)
				(island_removal_mode 0)
			)
			(polygon
				(pts
					(xy 285.57728 -83.195668) (xy 272.75028 -83.195668) (xy 272.75028 -81.468468) (xy 274.96008 -81.468468)
					(xy 274.96008 -80.046068) (xy 272.75028 -80.046068) (xy 272.75028 -76.388468) (xy 274.96008 -76.388468)
					(xy 274.96008 -74.966068) (xy 272.75028 -74.966068) (xy 272.75028 -73.238868) (xy 285.57728 -73.238868)
					(xy 285.57728 -74.407268) (xy 279.37968 -74.407268) (xy 279.37968 -82.027268) (xy 285.57728 -82.027268)
				)
			)
		)
	)
	(footprint ""
		(layer "F.Cu")
		(at 109.097826 -127.889)
		(property "Reference" "PC46"
			(at 0 0 0)
			(layer "F.SilkS")
			(hide yes)
			(effects
				(font
					(size 1.27 1.27)
				)
			)
		)
		(property "Value" ""
			(at 0 0 0)
			(layer "F.Fab")
			(effects
				(font
					(size 1.27 1.27)
				)
			)
		)
		(duplicate_pad_numbers_are_jumpers no)
		(fp_line
			(start -2.2098 -0.9398)
			(end 2.2098 -0.9398)
			(stroke
				(width 0.1524)
				(type default)
			)
			(layer "F.SilkS")
		)
		(fp_line
			(start -2.2098 0.9398)
			(end -2.2098 -0.9398)
			(stroke
				(width 0.1524)
				(type default)
			)
			(layer "F.SilkS")
		)
		(fp_line
			(start 2.2098 -0.9398)
			(end 2.2098 0.9398)
			(stroke
				(width 0.1524)
				(type default)
			)
			(layer "F.SilkS")
		)
		(fp_line
			(start 2.2098 0.9398)
			(end -2.2098 0.9398)
			(stroke
				(width 0.1524)
				(type default)
			)
			(layer "F.SilkS")
		)
		(fp_line
			(start -1.700022 -0.899922)
			(end 1.700022 -0.899922)
			(stroke
				(width 0.1)
				(type default)
			)
			(layer "F.Fab")
		)
		(fp_line
			(start -1.700022 0.899922)
			(end -1.700022 -0.899922)
			(stroke
				(width 0.1)
				(type default)
			)
			(layer "F.Fab")
		)
		(fp_line
			(start 1.700022 -0.899922)
			(end 1.700022 0.899922)
			(stroke
				(width 0.1)
				(type default)
			)
			(layer "F.Fab")
		)
		(fp_line
			(start 1.700022 0.899922)
			(end -1.700022 0.899922)
			(stroke
				(width 0.1)
				(type default)
			)
			(layer "F.Fab")
		)
		(pad "1" smd rect
			(at -1.4732 0 180)
			(size 1.1684 1.5748)
			(layers "F.Cu" "F.Mask" "F.Paste")
			(net "P52V_HS_FILTER")
		)
		(pad "2" smd rect
			(at 1.4732 0 180)
			(size 1.1684 1.5748)
			(layers "F.Cu" "F.Mask" "F.Paste")
			(net "GND")
		)
	)
	(footprint ""
		(layer "F.Cu")
		(at 298.91101 -141.069568)
		(property "Reference" ""
			(at 0 0 0)
			(layer "F.SilkS")
			(hide yes)
			(effects
				(font
					(size 1.27 1.27)
				)
			)
		)
		(property "Value" ""
			(at 0 0 0)
			(layer "F.Fab")
			(effects
				(font
					(size 1.27 1.27)
				)
			)
		)
		(duplicate_pad_numbers_are_jumpers no)
		(pad "1" smd circle
			(at 0 0)
			(size 0.9906 0.9906)
			(layers "F.Cu" "F.Mask" "F.Paste")
			(net "Net_154")
		)
		(zone
			(layer "F.Cu")
			(hatch none 0.5)
			(connect_pads
				(clearance 0)
			)
			(min_thickness 0.25)
			(keepout
				(tracks not_allowed)
				(vias allowed)
				(pads allowed)
				(copperpour not_allowed)
				(footprints allowed)
			)
			(placement
				(enabled no)
				(sheetname "")
			)
			(fill
				(thermal_gap 0.5)
				(thermal_bridge_width 0.5)
				(island_removal_mode 0)
			)
			(polygon
				(pts
					(arc
						(start 300.53661 -141.069568)
						(mid 297.28541 -141.069568)
						(end 300.53661 -141.069568)
					)
				)
			)
		)
	)
	(footprint ""
		(layer "F.Cu")
		(at 100.965 -50.038)
		(property "Reference" "PC67"
			(at 0 0 0)
			(layer "F.SilkS")
			(hide yes)
			(effects
				(font
					(size 1.27 1.27)
				)
			)
		)
		(property "Value" ""
			(at 0 0 0)
			(layer "F.Fab")
			(effects
				(font
					(size 1.27 1.27)
				)
			)
		)
		(duplicate_pad_numbers_are_jumpers no)
		(fp_line
			(start -1.524 -0.762)
			(end 1.524 -0.762)
			(stroke
				(width 0.1524)
				(type default)
			)
			(layer "F.SilkS")
		)
		(fp_line
			(start -1.524 0.762)
			(end -1.524 -0.762)
			(stroke
				(width 0.1524)
				(type default)
			)
			(layer "F.SilkS")
		)
		(fp_line
			(start 1.524 -0.762)
			(end 1.524 0.762)
			(stroke
				(width 0.1524)
				(type default)
			)
			(layer "F.SilkS")
		)
		(fp_line
			(start 1.524 0.762)
			(end -1.524 0.762)
			(stroke
				(width 0.1524)
				(type default)
			)
			(layer "F.SilkS")
		)
		(fp_line
			(start -1.1049 -0.724916)
			(end -1.1049 0.724916)
			(stroke
				(width 0.1)
				(type default)
			)
			(layer "F.Fab")
		)
		(fp_line
			(start -1.1049 0.724916)
			(end 1.1049 0.724916)
			(stroke
				(width 0.1)
				(type default)
			)
			(layer "F.Fab")
		)
		(fp_line
			(start 1.1049 -0.724916)
			(end -1.1049 -0.724916)
			(stroke
				(width 0.1)
				(type default)
			)
			(layer "F.Fab")
		)
		(fp_line
			(start 1.1049 0.724916)
			(end 1.1049 -0.724916)
			(stroke
				(width 0.1)
				(type default)
			)
			(layer "F.Fab")
		)
		(pad "1" smd rect
			(at -0.889 0 180)
			(size 1.016 1.27)
			(layers "F.Cu" "F.Mask" "F.Paste")
			(net "P12V_BRICK")
		)
		(pad "2" smd rect
			(at 0.889 0 180)
			(size 1.016 1.27)
			(layers "F.Cu" "F.Mask" "F.Paste")
			(net "GND")
		)
	)
	(footprint ""
		(layer "F.Cu")
		(at 100.076 -60.071)
		(property "Reference" "PR74"
			(at 0 0 0)
			(layer "F.SilkS")
			(hide yes)
			(effects
				(font
					(size 1.27 1.27)
				)
			)
		)
		(property "Value" ""
			(at 0 0 0)
			(layer "F.Fab")
			(effects
				(font
					(size 1.27 1.27)
				)
			)
		)
		(duplicate_pad_numbers_are_jumpers no)
		(fp_line
			(start -1.651 -0.8382)
			(end 1.651 -0.8382)
			(stroke
				(width 0.1524)
				(type default)
			)
			(layer "F.SilkS")
		)
		(fp_line
			(start -1.651 0.8382)
			(end -1.651 -0.8382)
			(stroke
				(width 0.1524)
				(type default)
			)
			(layer "F.SilkS")
		)
		(fp_line
			(start 1.651 -0.8382)
			(end 1.651 0.8382)
			(stroke
				(width 0.1524)
				(type default)
			)
			(layer "F.SilkS")
		)
		(fp_line
			(start 1.651 0.8382)
			(end -1.651 0.8382)
			(stroke
				(width 0.1524)
				(type default)
			)
			(layer "F.SilkS")
		)
		(fp_line
			(start -1.559814 -0.7366)
			(end -1.559814 0.7366)
			(stroke
				(width 0.1)
				(type default)
			)
			(layer "F.Fab")
		)
		(fp_line
			(start -1.559814 0.7366)
			(end -1.524 0.7366)
			(stroke
				(width 0.1)
				(type default)
			)
			(layer "F.Fab")
		)
		(fp_line
			(start -1.524 -0.7366)
			(end -1.559814 -0.7366)
			(stroke
				(width 0.1)
				(type default)
			)
			(layer "F.Fab")
		)
		(fp_line
			(start -1.524 0.7366)
			(end 1.524 0.7366)
			(stroke
				(width 0.1)
				(type default)
			)
			(layer "F.Fab")
		)
		(fp_line
			(start 1.524 -0.7366)
			(end -1.524 -0.7366)
			(stroke
				(width 0.1)
				(type default)
			)
			(layer "F.Fab")
		)
		(fp_line
			(start 1.524 0.7366)
			(end 1.560576 0.7366)
			(stroke
				(width 0.1)
				(type default)
			)
			(layer "F.Fab")
		)
		(fp_line
			(start 1.560576 -0.7366)
			(end 1.524 -0.7366)
			(stroke
				(width 0.1)
				(type default)
			)
			(layer "F.Fab")
		)
		(fp_line
			(start 1.560576 0.7366)
			(end 1.560576 -0.7366)
			(stroke
				(width 0.1)
				(type default)
			)
			(layer "F.Fab")
		)
		(pad "1" smd rect
			(at -0.94996 0 180)
			(size 1.1176 1.3716)
			(layers "F.Cu" "F.Mask" "F.Paste")
			(net "P12V_BRICK")
		)
		(pad "2" smd rect
			(at 0.94996 0 180)
			(size 1.1176 1.3716)
			(layers "F.Cu" "F.Mask" "F.Paste")
			(net "GND")
		)
	)
	(footprint ""
		(layer "F.Cu")
		(at 278.388318 -161.464498 90)
		(property "Reference" "J10"
			(at 1.222502 -5.580634 90)
			(unlocked yes)
			(layer "F.SilkS")
			(effects
				(font
					(size 0.7874 0.5842)
					(thickness 0.1524)
				)
				(justify left)
			)
		)
		(property "Value" ""
			(at 0 0 90)
			(layer "F.Fab")
			(effects
				(font
					(size 1.27 1.27)
				)
			)
		)
		(duplicate_pad_numbers_are_jumpers no)
		(fp_line
			(start 3.330702 -4.771136)
			(end 0 4.011168)
			(stroke
				(width 0.1524)
				(type default)
			)
			(layer "F.SilkS")
		)
		(fp_line
			(start -3.330702 -4.771136)
			(end 3.330702 -4.771136)
			(stroke
				(width 0.1524)
				(type default)
			)
			(layer "F.SilkS")
		)
		(fp_line
			(start 0 4.011168)
			(end -3.330702 -4.771136)
			(stroke
				(width 0.1524)
				(type default)
			)
			(layer "F.SilkS")
		)
		(fp_line
			(start 3.330702 -4.771136)
			(end 0 4.011168)
			(stroke
				(width 0.1)
				(type default)
			)
			(layer "F.Fab")
		)
		(fp_line
			(start -3.330702 -4.771136)
			(end 3.330702 -4.771136)
			(stroke
				(width 0.1)
				(type default)
			)
			(layer "F.Fab")
		)
		(fp_line
			(start 0 4.011168)
			(end -3.330702 -4.771136)
			(stroke
				(width 0.1)
				(type default)
			)
			(layer "F.Fab")
		)
		(pad "1" thru_hole circle
			(at 0 0 90)
			(size 2.159 2.159)
			(drill 1.7018)
			(layers "*.Cu" "*.Mask")
			(remove_unused_layers no)
			(net "GND3")
			(clearance 0.0254)
			(thermal_gap 0.0254)
		)
		(pad "2" thru_hole circle
			(at -1.27 -3.348736 90)
			(size 2.159 2.159)
			(drill 1.7018)
			(layers "*.Cu" "*.Mask")
			(remove_unused_layers no)
			(net "TDR_SE_50_OHM_TOP")
			(clearance 0.0254)
			(thermal_gap 0.0254)
		)
		(pad "3" thru_hole circle
			(at 1.27 -3.348736 90)
			(size 2.159 2.159)
			(drill 1.7018)
			(layers "*.Cu" "*.Mask")
			(remove_unused_layers no)
			(net "TDR_SE_50_OHM_TOP")
			(clearance 0.0254)
			(thermal_gap 0.0254)
		)
	)
	(footprint ""
		(layer "F.Cu")
		(at 280.39568 -90.282268)
		(property "Reference" "PQ4"
			(at -7.723886 -5.895848 0)
			(unlocked yes)
			(layer "F.SilkS")
			(effects
				(font
					(size 0.7874 0.5842)
					(thickness 0.1524)
				)
				(justify left)
			)
		)
		(property "Value" ""
			(at 0 0 0)
			(layer "F.Fab")
			(effects
				(font
					(size 1.27 1.27)
				)
			)
		)
		(duplicate_pad_numbers_are_jumpers no)
		(fp_line
			(start -7.649972 -4.99999)
			(end -7.649972 -3.3274)
			(stroke
				(width 0.1524)
				(type default)
			)
			(layer "F.SilkS")
		)
		(fp_line
			(start -7.649972 -1.7526)
			(end -7.649972 1.7526)
			(stroke
				(width 0.1524)
				(type default)
			)
			(layer "F.SilkS")
		)
		(fp_line
			(start -7.649972 3.3274)
			(end -7.649972 4.99999)
			(stroke
				(width 0.1524)
				(type default)
			)
			(layer "F.SilkS")
		)
		(fp_line
			(start -7.649972 4.99999)
			(end 5.115814 4.99999)
			(stroke
				(width 0.1524)
				(type default)
			)
			(layer "F.SilkS")
		)
		(fp_line
			(start 5.115814 -4.99999)
			(end -7.649972 -4.99999)
			(stroke
				(width 0.1524)
				(type default)
			)
			(layer "F.SilkS")
		)
		(fp_line
			(start 7.630414 4.99999)
			(end 7.649972 4.99999)
			(stroke
				(width 0.1524)
				(type default)
			)
			(layer "F.SilkS")
		)
		(fp_line
			(start 7.649972 -4.99999)
			(end 7.630414 -4.99999)
			(stroke
				(width 0.1524)
				(type default)
			)
			(layer "F.SilkS")
		)
		(fp_line
			(start 7.649972 4.99999)
			(end 7.649972 -4.99999)
			(stroke
				(width 0.1524)
				(type default)
			)
			(layer "F.SilkS")
		)
		(fp_line
			(start -7.649972 -4.99999)
			(end -7.649972 4.99999)
			(stroke
				(width 0.1)
				(type default)
			)
			(layer "F.Fab")
		)
		(fp_line
			(start -7.649972 4.99999)
			(end 7.649972 4.99999)
			(stroke
				(width 0.1)
				(type default)
			)
			(layer "F.Fab")
		)
		(fp_line
			(start 7.649972 -4.99999)
			(end -7.649972 -4.99999)
			(stroke
				(width 0.1)
				(type default)
			)
			(layer "F.Fab")
		)
		(fp_line
			(start 7.649972 4.99999)
			(end 7.649972 -4.99999)
			(stroke
				(width 0.1)
				(type default)
			)
			(layer "F.Fab")
		)
		(pad "D" smd circle
			(at 2.15011 0)
			(size 0 0)
			(layers "F.Cu" "F.Mask" "F.Paste")
			(net "P52V_HS1_DRAIN_2")
		)
		(pad "G" smd rect
			(at -7.050024 -2.54 270)
			(size 1.3208 3.0988)
			(layers "F.Cu" "F.Mask" "F.Paste")
			(net "P52V_HS1_GATE4")
		)
		(pad "S" smd rect
			(at -7.050024 2.54 270)
			(size 1.3208 3.0988)
			(layers "F.Cu" "F.Mask" "F.Paste")
			(net "P52V_HS")
		)
		(zone
			(layer "F.Cu")
			(hatch none 0.5)
			(connect_pads
				(clearance 0)
			)
			(min_thickness 0.25)
			(keepout
				(tracks not_allowed)
				(vias allowed)
				(pads allowed)
				(copperpour not_allowed)
				(footprints allowed)
			)
			(placement
				(enabled no)
				(sheetname "")
			)
			(fill
				(thermal_gap 0.5)
				(thermal_bridge_width 0.5)
				(island_removal_mode 0)
			)
			(polygon
				(pts
					(xy 285.57728 -95.260668) (xy 272.75028 -95.260668) (xy 272.75028 -93.533468) (xy 274.96008 -93.533468)
					(xy 274.96008 -92.111068) (xy 272.75028 -92.111068) (xy 272.75028 -88.453468) (xy 274.96008 -88.453468)
					(xy 274.96008 -87.031068) (xy 272.75028 -87.031068) (xy 272.75028 -85.303868) (xy 285.57728 -85.303868)
					(xy 285.57728 -86.472268) (xy 279.37968 -86.472268) (xy 279.37968 -94.092268) (xy 285.57728 -94.092268)
				)
			)
		)
	)
	(footprint ""
		(layer "F.Cu")
		(at 177.8254 -14.6812 180)
		(property "Reference" "PC109"
			(at 0 0 180)
			(layer "F.SilkS")
			(hide yes)
			(effects
				(font
					(size 1.27 1.27)
				)
			)
		)
		(property "Value" ""
			(at 0 0 180)
			(layer "F.Fab")
			(effects
				(font
					(size 1.27 1.27)
				)
			)
		)
		(duplicate_pad_numbers_are_jumpers no)
		(fp_line
			(start 0.7874 0.4064)
			(end -0.7874 0.4064)
			(stroke
				(width 0.1524)
				(type default)
			)
			(layer "F.SilkS")
		)
		(fp_line
			(start 0.7874 -0.4064)
			(end 0.7874 0.4064)
			(stroke
				(width 0.1524)
				(type default)
			)
			(layer "F.SilkS")
		)
		(fp_line
			(start -0.7874 0.4064)
			(end -0.7874 -0.4064)
			(stroke
				(width 0.1524)
				(type default)
			)
			(layer "F.SilkS")
		)
		(fp_line
			(start -0.7874 -0.4064)
			(end 0.7874 -0.4064)
			(stroke
				(width 0.1524)
				(type default)
			)
			(layer "F.SilkS")
		)
		(fp_line
			(start 0.67945 0.3048)
			(end 0.120396 0.3048)
			(stroke
				(width 0.1)
				(type default)
			)
			(layer "F.Fab")
		)
		(fp_line
			(start 0.67945 -0.3048)
			(end 0.67945 0.3048)
			(stroke
				(width 0.1)
				(type default)
			)
			(layer "F.Fab")
		)
		(fp_line
			(start 0.12065 -0.2794)
			(end 0.12065 -0.3048)
			(stroke
				(width 0.1)
				(type default)
			)
			(layer "F.Fab")
		)
		(fp_line
			(start 0.12065 -0.3048)
			(end 0.67945 -0.3048)
			(stroke
				(width 0.1)
				(type default)
			)
			(layer "F.Fab")
		)
		(fp_line
			(start 0.120396 0.3048)
			(end 0.120396 0.2794)
			(stroke
				(width 0.1)
				(type default)
			)
			(layer "F.Fab")
		)
		(fp_line
			(start 0.120396 0.2794)
			(end -0.12065 0.2794)
			(stroke
				(width 0.1)
				(type default)
			)
			(layer "F.Fab")
		)
		(fp_line
			(start -0.12065 0.3048)
			(end -0.67945 0.3048)
			(stroke
				(width 0.1)
				(type default)
			)
			(layer "F.Fab")
		)
		(fp_line
			(start -0.12065 0.2794)
			(end -0.12065 0.3048)
			(stroke
				(width 0.1)
				(type default)
			)
			(layer "F.Fab")
		)
		(fp_line
			(start -0.12065 -0.2794)
			(end 0.12065 -0.2794)
			(stroke
				(width 0.1)
				(type default)
			)
			(layer "F.Fab")
		)
		(fp_line
			(start -0.12065 -0.305054)
			(end -0.12065 -0.2794)
			(stroke
				(width 0.1)
				(type default)
			)
			(layer "F.Fab")
		)
		(fp_line
			(start -0.67945 0.3048)
			(end -0.67945 -0.305054)
			(stroke
				(width 0.1)
				(type default)
			)
			(layer "F.Fab")
		)
		(fp_line
			(start -0.67945 -0.305054)
			(end -0.12065 -0.305054)
			(stroke
				(width 0.1)
				(type default)
			)
			(layer "F.Fab")
		)
		(pad "1" smd circle
			(at -0.40005 0 180)
			(size 0 0)
			(layers "F.Cu" "F.Mask" "F.Paste")
			(net "P3V3_AUX_VCC")
		)
		(pad "2" smd circle
			(at 0.40005 0 180)
			(size 0 0)
			(layers "F.Cu" "F.Mask" "F.Paste")
			(net "GND")
		)
	)
	(footprint ""
		(layer "F.Cu")
		(at 45.67936 -55.07482 180)
		(property "Reference" "R5892"
			(at 0 0 180)
			(layer "F.SilkS")
			(hide yes)
			(effects
				(font
					(size 1.27 1.27)
				)
			)
		)
		(property "Value" ""
			(at 0 0 180)
			(layer "F.Fab")
			(effects
				(font
					(size 1.27 1.27)
				)
			)
		)
		(duplicate_pad_numbers_are_jumpers no)
		(fp_line
			(start 0.7874 0.4064)
			(end -0.7874 0.4064)
			(stroke
				(width 0.1524)
				(type default)
			)
			(layer "F.SilkS")
		)
		(fp_line
			(start 0.7874 -0.4064)
			(end 0.7874 0.4064)
			(stroke
				(width 0.1524)
				(type default)
			)
			(layer "F.SilkS")
		)
		(fp_line
			(start -0.7874 0.4064)
			(end -0.7874 -0.4064)
			(stroke
				(width 0.1524)
				(type default)
			)
			(layer "F.SilkS")
		)
		(fp_line
			(start -0.7874 -0.4064)
			(end 0.7874 -0.4064)
			(stroke
				(width 0.1524)
				(type default)
			)
			(layer "F.SilkS")
		)
		(fp_line
			(start 0.67945 0.3048)
			(end 0.120396 0.3048)
			(stroke
				(width 0.1)
				(type default)
			)
			(layer "F.Fab")
		)
		(fp_line
			(start 0.67945 -0.3048)
			(end 0.67945 0.3048)
			(stroke
				(width 0.1)
				(type default)
			)
			(layer "F.Fab")
		)
		(fp_line
			(start 0.12065 -0.2794)
			(end 0.12065 -0.3048)
			(stroke
				(width 0.1)
				(type default)
			)
			(layer "F.Fab")
		)
		(fp_line
			(start 0.12065 -0.3048)
			(end 0.67945 -0.3048)
			(stroke
				(width 0.1)
				(type default)
			)
			(layer "F.Fab")
		)
		(fp_line
			(start 0.120396 0.3048)
			(end 0.120396 0.2794)
			(stroke
				(width 0.1)
				(type default)
			)
			(layer "F.Fab")
		)
		(fp_line
			(start 0.120396 0.2794)
			(end -0.12065 0.2794)
			(stroke
				(width 0.1)
				(type default)
			)
			(layer "F.Fab")
		)
		(fp_line
			(start -0.12065 0.3048)
			(end -0.67945 0.3048)
			(stroke
				(width 0.1)
				(type default)
			)
			(layer "F.Fab")
		)
		(fp_line
			(start -0.12065 0.2794)
			(end -0.12065 0.3048)
			(stroke
				(width 0.1)
				(type default)
			)
			(layer "F.Fab")
		)
		(fp_line
			(start -0.12065 -0.2794)
			(end 0.12065 -0.2794)
			(stroke
				(width 0.1)
				(type default)
			)
			(layer "F.Fab")
		)
		(fp_line
			(start -0.12065 -0.305054)
			(end -0.12065 -0.2794)
			(stroke
				(width 0.1)
				(type default)
			)
			(layer "F.Fab")
		)
		(fp_line
			(start -0.67945 0.3048)
			(end -0.67945 -0.305054)
			(stroke
				(width 0.1)
				(type default)
			)
			(layer "F.Fab")
		)
		(fp_line
			(start -0.67945 -0.305054)
			(end -0.12065 -0.305054)
			(stroke
				(width 0.1)
				(type default)
			)
			(layer "F.Fab")
		)
		(pad "1" smd circle
			(at -0.40005 0 180)
			(size 0 0)
			(layers "F.Cu" "F.Mask" "F.Paste")
			(net "P12V_BRICK_PWRGD")
		)
		(pad "2" smd circle
			(at 0.40005 0 180)
			(size 0 0)
			(layers "F.Cu" "F.Mask" "F.Paste")
			(net "P12V_HPDB_0_EN_R")
		)
	)
	(footprint ""
		(layer "F.Cu")
		(at 139.065 -61.849)
		(property "Reference" "PC29"
			(at 0 0 0)
			(layer "F.SilkS")
			(hide yes)
			(effects
				(font
					(size 1.27 1.27)
				)
			)
		)
		(property "Value" ""
			(at 0 0 0)
			(layer "F.Fab")
			(effects
				(font
					(size 1.27 1.27)
				)
			)
		)
		(duplicate_pad_numbers_are_jumpers no)
		(fp_line
			(start -0.7874 -0.4064)
			(end 0.7874 -0.4064)
			(stroke
				(width 0.1524)
				(type default)
			)
			(layer "F.SilkS")
		)
		(fp_line
			(start -0.7874 0.4064)
			(end -0.7874 -0.4064)
			(stroke
				(width 0.1524)
				(type default)
			)
			(layer "F.SilkS")
		)
		(fp_line
			(start 0.7874 -0.4064)
			(end 0.7874 0.4064)
			(stroke
				(width 0.1524)
				(type default)
			)
			(layer "F.SilkS")
		)
		(fp_line
			(start 0.7874 0.4064)
			(end -0.7874 0.4064)
			(stroke
				(width 0.1524)
				(type default)
			)
			(layer "F.SilkS")
		)
		(fp_line
			(start -0.6858 -0.3048)
			(end -0.1016 -0.3048)
			(stroke
				(width 0.1)
				(type default)
			)
			(layer "F.Fab")
		)
		(fp_line
			(start -0.6858 0.3048)
			(end -0.6858 -0.3048)
			(stroke
				(width 0.1)
				(type default)
			)
			(layer "F.Fab")
		)
		(fp_line
			(start -0.1016 -0.3048)
			(end -0.1016 -0.2794)
			(stroke
				(width 0.1)
				(type default)
			)
			(layer "F.Fab")
		)
		(fp_line
			(start -0.1016 -0.2794)
			(end 0.1016 -0.2794)
			(stroke
				(width 0.1)
				(type default)
			)
			(layer "F.Fab")
		)
		(fp_line
			(start -0.1016 0.2794)
			(end -0.1016 0.3048)
			(stroke
				(width 0.1)
				(type default)
			)
			(layer "F.Fab")
		)
		(fp_line
			(start -0.1016 0.3048)
			(end -0.6858 0.3048)
			(stroke
				(width 0.1)
				(type default)
			)
			(layer "F.Fab")
		)
		(fp_line
			(start 0.1016 -0.3048)
			(end 0.6858 -0.3048)
			(stroke
				(width 0.1)
				(type default)
			)
			(layer "F.Fab")
		)
		(fp_line
			(start 0.1016 -0.2794)
			(end 0.1016 -0.3048)
			(stroke
				(width 0.1)
				(type default)
			)
			(layer "F.Fab")
		)
		(fp_line
			(start 0.1016 0.2794)
			(end -0.1016 0.2794)
			(stroke
				(width 0.1)
				(type default)
			)
			(layer "F.Fab")
		)
		(fp_line
			(start 0.1016 0.3048)
			(end 0.1016 0.2794)
			(stroke
				(width 0.1)
				(type default)
			)
			(layer "F.Fab")
		)
		(fp_line
			(start 0.6858 -0.3048)
			(end 0.6858 0.3048)
			(stroke
				(width 0.1)
				(type default)
			)
			(layer "F.Fab")
		)
		(fp_line
			(start 0.6858 0.3048)
			(end 0.1016 0.3048)
			(stroke
				(width 0.1)
				(type default)
			)
			(layer "F.Fab")
		)
		(pad "1" smd rect
			(at -0.40005 0 180)
			(size 0.4572 0.508)
			(layers "F.Cu" "F.Mask" "F.Paste")
			(net "P12V_BRICK")
		)
		(pad "2" smd rect
			(at 0.40005 0 180)
			(size 0.4572 0.508)
			(layers "F.Cu" "F.Mask" "F.Paste")
			(net "GND")
		)
	)
	(footprint ""
		(layer "F.Cu")
		(at 191.341756 -154.315668 -90)
		(property "Reference" "J12"
			(at -1.259332 -5.773928 90)
			(unlocked yes)
			(layer "F.SilkS")
			(effects
				(font
					(size 0.7874 0.5842)
					(thickness 0.1524)
				)
				(justify left)
			)
		)
		(property "Value" ""
			(at 0 0 270)
			(layer "F.Fab")
			(effects
				(font
					(size 1.27 1.27)
				)
			)
		)
		(duplicate_pad_numbers_are_jumpers no)
		(fp_line
			(start 0 4.011168)
			(end -3.330702 -4.771136)
			(stroke
				(width 0.1524)
				(type default)
			)
			(layer "F.SilkS")
		)
		(fp_line
			(start -3.330702 -4.771136)
			(end 3.330702 -4.771136)
			(stroke
				(width 0.1524)
				(type default)
			)
			(layer "F.SilkS")
		)
		(fp_line
			(start 3.330702 -4.771136)
			(end 0 4.011168)
			(stroke
				(width 0.1524)
				(type default)
			)
			(layer "F.SilkS")
		)
		(fp_line
			(start 0 4.011168)
			(end -3.330702 -4.771136)
			(stroke
				(width 0.1)
				(type default)
			)
			(layer "F.Fab")
		)
		(fp_line
			(start -3.330702 -4.771136)
			(end 3.330702 -4.771136)
			(stroke
				(width 0.1)
				(type default)
			)
			(layer "F.Fab")
		)
		(fp_line
			(start 3.330702 -4.771136)
			(end 0 4.011168)
			(stroke
				(width 0.1)
				(type default)
			)
			(layer "F.Fab")
		)
		(pad "1" thru_hole circle
			(at 0 0 270)
			(size 2.159 2.159)
			(drill 1.7018)
			(layers "*.Cu" "*.Mask")
			(remove_unused_layers no)
			(net "GND3")
			(clearance 0.0254)
			(thermal_gap 0.0254)
		)
		(pad "2" thru_hole circle
			(at -1.27 -3.348736 270)
			(size 2.159 2.159)
			(drill 1.7018)
			(layers "*.Cu" "*.Mask")
			(remove_unused_layers no)
			(net "TDR_SE_50_OHM_IN1")
			(clearance 0.0254)
			(thermal_gap 0.0254)
		)
		(pad "3" thru_hole circle
			(at 1.27 -3.348736 270)
			(size 2.159 2.159)
			(drill 1.7018)
			(layers "*.Cu" "*.Mask")
			(remove_unused_layers no)
			(net "TDR_SE_50_OHM_IN1")
			(clearance 0.0254)
			(thermal_gap 0.0254)
		)
	)
	(footprint ""
		(layer "F.Cu")
		(at 178.57089 -9.32053)
		(property "Reference" "PC110"
			(at 0 0 0)
			(layer "F.SilkS")
			(hide yes)
			(effects
				(font
					(size 1.27 1.27)
				)
			)
		)
		(property "Value" ""
			(at 0 0 0)
			(layer "F.Fab")
			(effects
				(font
					(size 1.27 1.27)
				)
			)
		)
		(duplicate_pad_numbers_are_jumpers no)
		(fp_line
			(start -0.7874 -0.4064)
			(end 0.7874 -0.4064)
			(stroke
				(width 0.1524)
				(type default)
			)
			(layer "F.SilkS")
		)
		(fp_line
			(start -0.7874 0.4064)
			(end -0.7874 -0.4064)
			(stroke
				(width 0.1524)
				(type default)
			)
			(layer "F.SilkS")
		)
		(fp_line
			(start 0.7874 -0.4064)
			(end 0.7874 0.4064)
			(stroke
				(width 0.1524)
				(type default)
			)
			(layer "F.SilkS")
		)
		(fp_line
			(start 0.7874 0.4064)
			(end -0.7874 0.4064)
			(stroke
				(width 0.1524)
				(type default)
			)
			(layer "F.SilkS")
		)
		(fp_line
			(start -0.67945 -0.305054)
			(end -0.12065 -0.305054)
			(stroke
				(width 0.1)
				(type default)
			)
			(layer "F.Fab")
		)
		(fp_line
			(start -0.67945 0.3048)
			(end -0.67945 -0.305054)
			(stroke
				(width 0.1)
				(type default)
			)
			(layer "F.Fab")
		)
		(fp_line
			(start -0.12065 -0.305054)
			(end -0.12065 -0.2794)
			(stroke
				(width 0.1)
				(type default)
			)
			(layer "F.Fab")
		)
		(fp_line
			(start -0.12065 -0.2794)
			(end 0.12065 -0.2794)
			(stroke
				(width 0.1)
				(type default)
			)
			(layer "F.Fab")
		)
		(fp_line
			(start -0.12065 0.2794)
			(end -0.12065 0.3048)
			(stroke
				(width 0.1)
				(type default)
			)
			(layer "F.Fab")
		)
		(fp_line
			(start -0.12065 0.3048)
			(end -0.67945 0.3048)
			(stroke
				(width 0.1)
				(type default)
			)
			(layer "F.Fab")
		)
		(fp_line
			(start 0.120396 0.2794)
			(end -0.12065 0.2794)
			(stroke
				(width 0.1)
				(type default)
			)
			(layer "F.Fab")
		)
		(fp_line
			(start 0.120396 0.3048)
			(end 0.120396 0.2794)
			(stroke
				(width 0.1)
				(type default)
			)
			(layer "F.Fab")
		)
		(fp_line
			(start 0.12065 -0.3048)
			(end 0.67945 -0.3048)
			(stroke
				(width 0.1)
				(type default)
			)
			(layer "F.Fab")
		)
		(fp_line
			(start 0.12065 -0.2794)
			(end 0.12065 -0.3048)
			(stroke
				(width 0.1)
				(type default)
			)
			(layer "F.Fab")
		)
		(fp_line
			(start 0.67945 -0.3048)
			(end 0.67945 0.3048)
			(stroke
				(width 0.1)
				(type default)
			)
			(layer "F.Fab")
		)
		(fp_line
			(start 0.67945 0.3048)
			(end 0.120396 0.3048)
			(stroke
				(width 0.1)
				(type default)
			)
			(layer "F.Fab")
		)
		(pad "1" smd circle
			(at -0.40005 0)
			(size 0 0)
			(layers "F.Cu" "F.Mask" "F.Paste")
			(net "GND")
		)
		(pad "2" smd circle
			(at 0.40005 0)
			(size 0 0)
			(layers "F.Cu" "F.Mask" "F.Paste")
			(net "P3V3_AUX_REF")
		)
	)
	(footprint ""
		(layer "F.Cu")
		(at 271.018 -47.625 -90)
		(property "Reference" "PR209"
			(at 0 0 270)
			(layer "F.SilkS")
			(hide yes)
			(effects
				(font
					(size 1.27 1.27)
				)
			)
		)
		(property "Value" ""
			(at 0 0 270)
			(layer "F.Fab")
			(effects
				(font
					(size 1.27 1.27)
				)
			)
		)
		(duplicate_pad_numbers_are_jumpers no)
		(fp_line
			(start -0.7874 0.4064)
			(end -0.7874 -0.4064)
			(stroke
				(width 0.1524)
				(type default)
			)
			(layer "F.SilkS")
		)
		(fp_line
			(start 0.7874 0.4064)
			(end -0.7874 0.4064)
			(stroke
				(width 0.1524)
				(type default)
			)
			(layer "F.SilkS")
		)
		(fp_line
			(start -0.7874 -0.4064)
			(end 0.7874 -0.4064)
			(stroke
				(width 0.1524)
				(type default)
			)
			(layer "F.SilkS")
		)
		(fp_line
			(start 0.7874 -0.4064)
			(end 0.7874 0.4064)
			(stroke
				(width 0.1524)
				(type default)
			)
			(layer "F.SilkS")
		)
		(fp_line
			(start -0.67945 0.3048)
			(end -0.67945 -0.305054)
			(stroke
				(width 0.1)
				(type default)
			)
			(layer "F.Fab")
		)
		(fp_line
			(start -0.12065 0.3048)
			(end -0.67945 0.3048)
			(stroke
				(width 0.1)
				(type default)
			)
			(layer "F.Fab")
		)
		(fp_line
			(start 0.120396 0.3048)
			(end 0.120396 0.2794)
			(stroke
				(width 0.1)
				(type default)
			)
			(layer "F.Fab")
		)
		(fp_line
			(start 0.67945 0.3048)
			(end 0.120396 0.3048)
			(stroke
				(width 0.1)
				(type default)
			)
			(layer "F.Fab")
		)
		(fp_line
			(start -0.12065 0.2794)
			(end -0.12065 0.3048)
			(stroke
				(width 0.1)
				(type default)
			)
			(layer "F.Fab")
		)
		(fp_line
			(start 0.120396 0.2794)
			(end -0.12065 0.2794)
			(stroke
				(width 0.1)
				(type default)
			)
			(layer "F.Fab")
		)
		(fp_line
			(start -0.12065 -0.2794)
			(end 0.12065 -0.2794)
			(stroke
				(width 0.1)
				(type default)
			)
			(layer "F.Fab")
		)
		(fp_line
			(start 0.12065 -0.2794)
			(end 0.12065 -0.3048)
			(stroke
				(width 0.1)
				(type default)
			)
			(layer "F.Fab")
		)
		(fp_line
			(start 0.12065 -0.3048)
			(end 0.67945 -0.3048)
			(stroke
				(width 0.1)
				(type default)
			)
			(layer "F.Fab")
		)
		(fp_line
			(start 0.67945 -0.3048)
			(end 0.67945 0.3048)
			(stroke
				(width 0.1)
				(type default)
			)
			(layer "F.Fab")
		)
		(fp_line
			(start -0.67945 -0.305054)
			(end -0.12065 -0.305054)
			(stroke
				(width 0.1)
				(type default)
			)
			(layer "F.Fab")
		)
		(fp_line
			(start -0.12065 -0.305054)
			(end -0.12065 -0.2794)
			(stroke
				(width 0.1)
				(type default)
			)
			(layer "F.Fab")
		)
		(pad "1" smd circle
			(at -0.40005 0 270)
			(size 0 0)
			(layers "F.Cu" "F.Mask" "F.Paste")
			(net "GND_FIELD_SIGNAL")
		)
		(pad "2" smd circle
			(at 0.40005 0 270)
			(size 0 0)
			(layers "F.Cu" "F.Mask" "F.Paste")
			(net "P52V_HS1_CS")
		)
	)
	(footprint ""
		(layer "F.Cu")
		(at 264.541 -47.625 90)
		(property "Reference" "PC6"
			(at 0 0 90)
			(layer "F.SilkS")
			(hide yes)
			(effects
				(font
					(size 1.27 1.27)
				)
			)
		)
		(property "Value" ""
			(at 0 0 90)
			(layer "F.Fab")
			(effects
				(font
					(size 1.27 1.27)
				)
			)
		)
		(duplicate_pad_numbers_are_jumpers no)
		(fp_line
			(start 0.7874 -0.4064)
			(end 0.7874 0.4064)
			(stroke
				(width 0.1524)
				(type default)
			)
			(layer "F.SilkS")
		)
		(fp_line
			(start -0.7874 -0.4064)
			(end 0.7874 -0.4064)
			(stroke
				(width 0.1524)
				(type default)
			)
			(layer "F.SilkS")
		)
		(fp_line
			(start 0.7874 0.4064)
			(end -0.7874 0.4064)
			(stroke
				(width 0.1524)
				(type default)
			)
			(layer "F.SilkS")
		)
		(fp_line
			(start -0.7874 0.4064)
			(end -0.7874 -0.4064)
			(stroke
				(width 0.1524)
				(type default)
			)
			(layer "F.SilkS")
		)
		(fp_line
			(start -0.12065 -0.305054)
			(end -0.12065 -0.2794)
			(stroke
				(width 0.1)
				(type default)
			)
			(layer "F.Fab")
		)
		(fp_line
			(start -0.67945 -0.305054)
			(end -0.12065 -0.305054)
			(stroke
				(width 0.1)
				(type default)
			)
			(layer "F.Fab")
		)
		(fp_line
			(start 0.67945 -0.3048)
			(end 0.67945 0.3048)
			(stroke
				(width 0.1)
				(type default)
			)
			(layer "F.Fab")
		)
		(fp_line
			(start 0.12065 -0.3048)
			(end 0.67945 -0.3048)
			(stroke
				(width 0.1)
				(type default)
			)
			(layer "F.Fab")
		)
		(fp_line
			(start 0.12065 -0.2794)
			(end 0.12065 -0.3048)
			(stroke
				(width 0.1)
				(type default)
			)
			(layer "F.Fab")
		)
		(fp_line
			(start -0.12065 -0.2794)
			(end 0.12065 -0.2794)
			(stroke
				(width 0.1)
				(type default)
			)
			(layer "F.Fab")
		)
		(fp_line
			(start 0.120396 0.2794)
			(end -0.12065 0.2794)
			(stroke
				(width 0.1)
				(type default)
			)
			(layer "F.Fab")
		)
		(fp_line
			(start -0.12065 0.2794)
			(end -0.12065 0.3048)
			(stroke
				(width 0.1)
				(type default)
			)
			(layer "F.Fab")
		)
		(fp_line
			(start 0.67945 0.3048)
			(end 0.120396 0.3048)
			(stroke
				(width 0.1)
				(type default)
			)
			(layer "F.Fab")
		)
		(fp_line
			(start 0.120396 0.3048)
			(end 0.120396 0.2794)
			(stroke
				(width 0.1)
				(type default)
			)
			(layer "F.Fab")
		)
		(fp_line
			(start -0.12065 0.3048)
			(end -0.67945 0.3048)
			(stroke
				(width 0.1)
				(type default)
			)
			(layer "F.Fab")
		)
		(fp_line
			(start -0.67945 0.3048)
			(end -0.67945 -0.305054)
			(stroke
				(width 0.1)
				(type default)
			)
			(layer "F.Fab")
		)
		(pad "1" smd circle
			(at -0.40005 0 90)
			(size 0 0)
			(layers "F.Cu" "F.Mask" "F.Paste")
			(net "P52V_HS1_TEMP")
		)
		(pad "2" smd circle
			(at 0.40005 0 90)
			(size 0 0)
			(layers "F.Cu" "F.Mask" "F.Paste")
			(net "GND_FIELD_SIGNAL")
		)
	)
	(footprint ""
		(layer "F.Cu")
		(at 300.624494 -36.438586 90)
		(property "Reference" "PD7"
			(at -4.7244 -3.851148 90)
			(unlocked yes)
			(layer "F.SilkS")
			(effects
				(font
					(size 0.7874 0.5842)
					(thickness 0.1524)
				)
				(justify left)
			)
		)
		(property "Value" ""
			(at 0 0 90)
			(layer "F.Fab")
			(effects
				(font
					(size 1.27 1.27)
				)
			)
		)
		(duplicate_pad_numbers_are_jumpers no)
		(fp_line
			(start 5.4102 -3.109976)
			(end 4.783074 -3.109976)
			(stroke
				(width 0.1524)
				(type default)
			)
			(layer "F.SilkS")
		)
		(fp_line
			(start 5.313426 -3.109976)
			(end 5.313426 3.109976)
			(stroke
				(width 0.1524)
				(type default)
			)
			(layer "F.SilkS")
		)
		(fp_line
			(start 5.262626 -3.109976)
			(end 5.262626 3.109976)
			(stroke
				(width 0.1524)
				(type default)
			)
			(layer "F.SilkS")
		)
		(fp_line
			(start 5.211826 -3.109976)
			(end 5.211826 3.109976)
			(stroke
				(width 0.1524)
				(type default)
			)
			(layer "F.SilkS")
		)
		(fp_line
			(start 5.110226 -3.109976)
			(end 5.110226 3.109976)
			(stroke
				(width 0.1524)
				(type default)
			)
			(layer "F.SilkS")
		)
		(fp_line
			(start 5.008626 -3.109976)
			(end 5.008626 3.109976)
			(stroke
				(width 0.1524)
				(type default)
			)
			(layer "F.SilkS")
		)
		(fp_line
			(start 4.932426 -3.109976)
			(end 4.932426 3.109976)
			(stroke
				(width 0.1524)
				(type default)
			)
			(layer "F.SilkS")
		)
		(fp_line
			(start 4.805426 -3.109976)
			(end 4.805426 3.109976)
			(stroke
				(width 0.1524)
				(type default)
			)
			(layer "F.SilkS")
		)
		(fp_line
			(start 4.70535 -3.109976)
			(end 4.70535 3.109976)
			(stroke
				(width 0.1524)
				(type default)
			)
			(layer "F.SilkS")
		)
		(fp_line
			(start 4.70535 -3.109976)
			(end 4.70535 3.109976)
			(stroke
				(width 0.1524)
				(type default)
			)
			(layer "F.SilkS")
		)
		(fp_line
			(start 4.70535 -3.109976)
			(end 4.70535 3.109976)
			(stroke
				(width 0.1524)
				(type default)
			)
			(layer "F.SilkS")
		)
		(fp_line
			(start 4.695444 -3.109976)
			(end 4.695444 3.109976)
			(stroke
				(width 0.1524)
				(type default)
			)
			(layer "F.SilkS")
		)
		(fp_line
			(start 4.6101 -3.109976)
			(end 4.283202 -3.109976)
			(stroke
				(width 0.1524)
				(type default)
			)
			(layer "F.SilkS")
		)
		(fp_line
			(start 4.511802 -3.109976)
			(end 4.207002 -3.109976)
			(stroke
				(width 0.1524)
				(type default)
			)
			(layer "F.SilkS")
		)
		(fp_line
			(start 4.183126 -3.109976)
			(end 4.794504 -3.109976)
			(stroke
				(width 0.1524)
				(type default)
			)
			(layer "F.SilkS")
		)
		(fp_line
			(start -4.664456 -3.109976)
			(end 4.743704 -3.109976)
			(stroke
				(width 0.1524)
				(type default)
			)
			(layer "F.SilkS")
		)
		(fp_line
			(start -0.508 -1.016)
			(end 0.762 0)
			(stroke
				(width 0.1524)
				(type default)
			)
			(layer "F.SilkS")
		)
		(fp_line
			(start 0.762 0)
			(end 1.2192 0)
			(stroke
				(width 0.1524)
				(type default)
			)
			(layer "F.SilkS")
		)
		(fp_line
			(start 0.762 0)
			(end -0.508 1.016)
			(stroke
				(width 0.1524)
				(type default)
			)
			(layer "F.SilkS")
		)
		(fp_line
			(start -1.0668 0)
			(end -0.6096 0)
			(stroke
				(width 0.1524)
				(type default)
			)
			(layer "F.SilkS")
		)
		(fp_line
			(start -0.508 1.016)
			(end -0.508 -1.016)
			(stroke
				(width 0.1524)
				(type default)
			)
			(layer "F.SilkS")
		)
		(fp_line
			(start 0.762 1.27)
			(end 0.762 -1.27)
			(stroke
				(width 0.1524)
				(type default)
			)
			(layer "F.SilkS")
		)
		(fp_line
			(start 4.715002 3.035554)
			(end 4.7117 2.984754)
			(stroke
				(width 0.1524)
				(type default)
			)
			(layer "F.SilkS")
		)
		(fp_line
			(start 5.4102 3.109976)
			(end 5.4102 -3.109976)
			(stroke
				(width 0.1524)
				(type default)
			)
			(layer "F.SilkS")
		)
		(fp_line
			(start 4.794504 3.109976)
			(end 3.554984 3.109976)
			(stroke
				(width 0.1524)
				(type default)
			)
			(layer "F.SilkS")
		)
		(fp_line
			(start 4.769104 3.109976)
			(end -4.664456 3.109976)
			(stroke
				(width 0.1524)
				(type default)
			)
			(layer "F.SilkS")
		)
		(fp_line
			(start 4.743704 3.109976)
			(end 5.4102 3.109976)
			(stroke
				(width 0.1524)
				(type default)
			)
			(layer "F.SilkS")
		)
		(fp_line
			(start 4.743704 3.109976)
			(end 4.6101 3.109976)
			(stroke
				(width 0.1524)
				(type default)
			)
			(layer "F.SilkS")
		)
		(fp_line
			(start 4.156202 3.109976)
			(end 4.183126 3.109976)
			(stroke
				(width 0.1524)
				(type default)
			)
			(layer "F.SilkS")
		)
		(fp_line
			(start -4.664456 3.109976)
			(end -4.664456 -3.109976)
			(stroke
				(width 0.1524)
				(type default)
			)
			(layer "F.SilkS")
		)
		(fp_line
			(start 4.065016 -3.109976)
			(end 4.065016 3.109976)
			(stroke
				(width 0.1)
				(type default)
			)
			(layer "F.Fab")
		)
		(fp_line
			(start -4.065016 -3.109976)
			(end 4.065016 -3.109976)
			(stroke
				(width 0.1)
				(type default)
			)
			(layer "F.Fab")
		)
		(fp_line
			(start 4.065016 3.109976)
			(end -4.065016 3.109976)
			(stroke
				(width 0.1)
				(type default)
			)
			(layer "F.Fab")
		)
		(fp_line
			(start -4.065016 3.109976)
			(end -4.065016 -3.109976)
			(stroke
				(width 0.1)
				(type default)
			)
			(layer "F.Fab")
		)
		(fp_text user "+"
			(at -5.831586 -0.021844 270)
			(unlocked yes)
			(layer "F.SilkS")
			(effects
				(font
					(size 1.905 1.4224)
					(thickness 0.1524)
				)
				(justify left)
			)
		)
		(fp_text user "-"
			(at 6.741414 2.645156 270)
			(unlocked yes)
			(layer "F.SilkS")
			(effects
				(font
					(size 1.905 1.4224)
					(thickness 0.1524)
				)
				(justify left)
			)
		)
		(fp_text user "+"
			(at -4.5974 0.24765 270)
			(unlocked yes)
			(layer "F.Fab")
			(effects
				(font
					(size 1.905 1.4224)
					(thickness 0.1524)
				)
				(justify left)
			)
		)
		(fp_text user "-"
			(at 6.643624 0.40005 270)
			(unlocked yes)
			(layer "F.Fab")
			(effects
				(font
					(size 1.905 1.4224)
					(thickness 0.1524)
				)
				(justify left)
			)
		)
		(pad "A" smd rect
			(at -3.299968 0 270)
			(size 2.413 3.302)
			(layers "F.Cu" "F.Mask" "F.Paste")
			(net "GND")
		)
		(pad "C" smd rect
			(at 3.299968 0 270)
			(size 2.413 3.302)
			(layers "F.Cu" "F.Mask" "F.Paste")
			(net "P52V_1_FUSE_1")
		)
	)
	(footprint ""
		(layer "F.Cu")
		(at 68.072 -60.96)
		(property "Reference" "PC98"
			(at -1.27 -3.52933 0)
			(unlocked yes)
			(layer "F.SilkS")
			(effects
				(font
					(size 0.7874 0.5842)
					(thickness 0.1524)
				)
				(justify left)
			)
		)
		(property "Value" ""
			(at 0 0 0)
			(layer "F.Fab")
			(effects
				(font
					(size 1.27 1.27)
				)
			)
		)
		(duplicate_pad_numbers_are_jumpers no)
		(fp_line
			(start 5.2578 2.499868)
			(end -5.2578 2.499868)
			(stroke
				(width 0.1524)
				(type default)
			)
			(layer "F.SilkS")
		)
		(fp_circle
			(center 0 2.499868)
			(end 5.2578 2.499868)
			(stroke
				(width 0.1524)
				(type default)
			)
			(fill no)
			(layer "F.SilkS")
		)
		(fp_poly
			(pts
				(arc
					(start 5.2578 2.499868)
					(mid 0 7.757922)
					(end -5.2578 2.499868)
				)
			)
			(stroke
				(width 0)
				(type default)
			)
			(fill yes)
			(layer "F.SilkS")
		)
		(fp_circle
			(center 0 2.499868)
			(end 5.2578 2.499868)
			(stroke
				(width 0.1)
				(type default)
			)
			(fill no)
			(layer "F.Fab")
		)
		(pad "1" thru_hole rect
			(at 0 0 270)
			(size 1.524 1.524)
			(drill 1.016)
			(layers "*.Cu" "*.Mask")
			(remove_unused_layers no)
			(net "P12V_BRICK")
			(clearance 0)
			(padstack
				(mode front_inner_back)
				(layer "Inner"
					(shape circle)
					(size 1.524 1.524)
					(clearance 0)
				)
				(layer "B.Cu"
					(shape rect)
					(size 1.524 1.524)
					(clearance 0)
				)
			)
		)
		(pad "2" thru_hole circle
			(at 0 4.99999 270)
			(size 1.524 1.524)
			(drill 1.016)
			(layers "*.Cu" "*.Mask")
			(remove_unused_layers no)
			(net "GND")
			(clearance 0)
		)
	)
	(footprint ""
		(layer "F.Cu")
		(at 174.239174 -136.906 90)
		(property "Reference" "PC114"
			(at 6.19633 0.766826 0)
			(unlocked yes)
			(layer "F.SilkS")
			(effects
				(font
					(size 0.7874 0.5842)
					(thickness 0.1524)
				)
				(justify left)
			)
		)
		(property "Value" ""
			(at 0 0 90)
			(layer "F.Fab")
			(effects
				(font
					(size 1.27 1.27)
				)
			)
		)
		(duplicate_pad_numbers_are_jumpers no)
		(fp_line
			(start 5.2578 2.499868)
			(end -5.2578 2.499868)
			(stroke
				(width 0.1524)
				(type default)
			)
			(layer "F.SilkS")
		)
		(fp_circle
			(center 0 2.500122)
			(end 0 7.758176)
			(stroke
				(width 0.1524)
				(type default)
			)
			(fill no)
			(layer "F.SilkS")
		)
		(fp_poly
			(pts
				(arc
					(start 5.2578 2.499868)
					(mid 0 7.757922)
					(end -5.2578 2.499868)
				)
			)
			(stroke
				(width 0)
				(type default)
			)
			(fill yes)
			(layer "F.SilkS")
		)
		(fp_circle
			(center 0 2.500122)
			(end 0 7.758176)
			(stroke
				(width 0.1)
				(type default)
			)
			(fill no)
			(layer "F.Fab")
		)
		(pad "1" thru_hole rect
			(at 0 0)
			(size 1.5748 1.5748)
			(drill 1.0668)
			(layers "*.Cu" "*.Mask")
			(remove_unused_layers no)
			(net "P52V_HS_FILTER")
			(clearance 0)
			(padstack
				(mode front_inner_back)
				(layer "Inner"
					(shape circle)
					(size 1.5748 1.5748)
					(clearance 0)
				)
				(layer "B.Cu"
					(shape rect)
					(size 1.5748 1.5748)
					(clearance 0)
				)
			)
		)
		(pad "2" thru_hole circle
			(at 0 4.99999)
			(size 1.5748 1.5748)
			(drill 1.0668)
			(layers "*.Cu" "*.Mask")
			(remove_unused_layers no)
			(net "GND")
			(clearance 0)
		)
	)
	(footprint ""
		(layer "F.Cu")
		(at 279.027128 -36.358576)
		(property "Reference" "R145"
			(at 0 0 0)
			(layer "F.SilkS")
			(hide yes)
			(effects
				(font
					(size 1.27 1.27)
				)
			)
		)
		(property "Value" ""
			(at 0 0 0)
			(layer "F.Fab")
			(effects
				(font
					(size 1.27 1.27)
				)
			)
		)
		(duplicate_pad_numbers_are_jumpers no)
		(fp_line
			(start -0.7874 -0.4064)
			(end 0.7874 -0.4064)
			(stroke
				(width 0.1524)
				(type default)
			)
			(layer "F.SilkS")
		)
		(fp_line
			(start -0.7874 0.4064)
			(end -0.7874 -0.4064)
			(stroke
				(width 0.1524)
				(type default)
			)
			(layer "F.SilkS")
		)
		(fp_line
			(start 0.7874 -0.4064)
			(end 0.7874 0.4064)
			(stroke
				(width 0.1524)
				(type default)
			)
			(layer "F.SilkS")
		)
		(fp_line
			(start 0.7874 0.4064)
			(end -0.7874 0.4064)
			(stroke
				(width 0.1524)
				(type default)
			)
			(layer "F.SilkS")
		)
		(fp_line
			(start -0.67945 -0.305054)
			(end -0.12065 -0.305054)
			(stroke
				(width 0.1)
				(type default)
			)
			(layer "F.Fab")
		)
		(fp_line
			(start -0.67945 0.3048)
			(end -0.67945 -0.305054)
			(stroke
				(width 0.1)
				(type default)
			)
			(layer "F.Fab")
		)
		(fp_line
			(start -0.12065 -0.305054)
			(end -0.12065 -0.2794)
			(stroke
				(width 0.1)
				(type default)
			)
			(layer "F.Fab")
		)
		(fp_line
			(start -0.12065 -0.2794)
			(end 0.12065 -0.2794)
			(stroke
				(width 0.1)
				(type default)
			)
			(layer "F.Fab")
		)
		(fp_line
			(start -0.12065 0.2794)
			(end -0.12065 0.3048)
			(stroke
				(width 0.1)
				(type default)
			)
			(layer "F.Fab")
		)
		(fp_line
			(start -0.12065 0.3048)
			(end -0.67945 0.3048)
			(stroke
				(width 0.1)
				(type default)
			)
			(layer "F.Fab")
		)
		(fp_line
			(start 0.120396 0.2794)
			(end -0.12065 0.2794)
			(stroke
				(width 0.1)
				(type default)
			)
			(layer "F.Fab")
		)
		(fp_line
			(start 0.120396 0.3048)
			(end 0.120396 0.2794)
			(stroke
				(width 0.1)
				(type default)
			)
			(layer "F.Fab")
		)
		(fp_line
			(start 0.12065 -0.3048)
			(end 0.67945 -0.3048)
			(stroke
				(width 0.1)
				(type default)
			)
			(layer "F.Fab")
		)
		(fp_line
			(start 0.12065 -0.2794)
			(end 0.12065 -0.3048)
			(stroke
				(width 0.1)
				(type default)
			)
			(layer "F.Fab")
		)
		(fp_line
			(start 0.67945 -0.3048)
			(end 0.67945 0.3048)
			(stroke
				(width 0.1)
				(type default)
			)
			(layer "F.Fab")
		)
		(fp_line
			(start 0.67945 0.3048)
			(end 0.120396 0.3048)
			(stroke
				(width 0.1)
				(type default)
			)
			(layer "F.Fab")
		)
		(pad "1" smd circle
			(at -0.40005 0)
			(size 0 0)
			(layers "F.Cu" "F.Mask" "F.Paste")
			(net "SMB_P52V_HSC_SDA")
		)
		(pad "2" smd circle
			(at 0.40005 0)
			(size 0 0)
			(layers "F.Cu" "F.Mask" "F.Paste")
			(net "SMB_CM_HS1_3V3SB_DATO")
		)
	)
	(footprint ""
		(layer "F.Cu")
		(at 124.714 -127.889)
		(property "Reference" "PC23"
			(at 0 0 0)
			(layer "F.SilkS")
			(hide yes)
			(effects
				(font
					(size 1.27 1.27)
				)
			)
		)
		(property "Value" ""
			(at 0 0 0)
			(layer "F.Fab")
			(effects
				(font
					(size 1.27 1.27)
				)
			)
		)
		(duplicate_pad_numbers_are_jumpers no)
		(fp_line
			(start -2.2098 -0.9398)
			(end 2.2098 -0.9398)
			(stroke
				(width 0.1524)
				(type default)
			)
			(layer "F.SilkS")
		)
		(fp_line
			(start -2.2098 0.9398)
			(end -2.2098 -0.9398)
			(stroke
				(width 0.1524)
				(type default)
			)
			(layer "F.SilkS")
		)
		(fp_line
			(start 2.2098 -0.9398)
			(end 2.2098 0.9398)
			(stroke
				(width 0.1524)
				(type default)
			)
			(layer "F.SilkS")
		)
		(fp_line
			(start 2.2098 0.9398)
			(end -2.2098 0.9398)
			(stroke
				(width 0.1524)
				(type default)
			)
			(layer "F.SilkS")
		)
		(fp_line
			(start -1.700022 -0.899922)
			(end 1.700022 -0.899922)
			(stroke
				(width 0.1)
				(type default)
			)
			(layer "F.Fab")
		)
		(fp_line
			(start -1.700022 0.899922)
			(end -1.700022 -0.899922)
			(stroke
				(width 0.1)
				(type default)
			)
			(layer "F.Fab")
		)
		(fp_line
			(start 1.700022 -0.899922)
			(end 1.700022 0.899922)
			(stroke
				(width 0.1)
				(type default)
			)
			(layer "F.Fab")
		)
		(fp_line
			(start 1.700022 0.899922)
			(end -1.700022 0.899922)
			(stroke
				(width 0.1)
				(type default)
			)
			(layer "F.Fab")
		)
		(pad "1" smd rect
			(at -1.4732 0 180)
			(size 1.1684 1.5748)
			(layers "F.Cu" "F.Mask" "F.Paste")
			(net "P52V_HS_FILTER")
		)
		(pad "2" smd rect
			(at 1.4732 0 180)
			(size 1.1684 1.5748)
			(layers "F.Cu" "F.Mask" "F.Paste")
			(net "GND")
		)
	)
	(footprint ""
		(layer "F.Cu")
		(at 215.646 -95.504 -90)
		(property "Reference" "C23"
			(at 0 0 270)
			(layer "F.SilkS")
			(hide yes)
			(effects
				(font
					(size 1.27 1.27)
				)
			)
		)
		(property "Value" ""
			(at 0 0 270)
			(layer "F.Fab")
			(effects
				(font
					(size 1.27 1.27)
				)
			)
		)
		(duplicate_pad_numbers_are_jumpers no)
		(fp_line
			(start -2.2098 0.9398)
			(end -2.2098 -0.9398)
			(stroke
				(width 0.1524)
				(type default)
			)
			(layer "F.SilkS")
		)
		(fp_line
			(start 2.2098 0.9398)
			(end -2.2098 0.9398)
			(stroke
				(width 0.1524)
				(type default)
			)
			(layer "F.SilkS")
		)
		(fp_line
			(start -2.2098 -0.9398)
			(end 2.2098 -0.9398)
			(stroke
				(width 0.1524)
				(type default)
			)
			(layer "F.SilkS")
		)
		(fp_line
			(start 2.2098 -0.9398)
			(end 2.2098 0.9398)
			(stroke
				(width 0.1524)
				(type default)
			)
			(layer "F.SilkS")
		)
		(fp_line
			(start -1.700022 0.899922)
			(end -1.700022 -0.899922)
			(stroke
				(width 0.1)
				(type default)
			)
			(layer "F.Fab")
		)
		(fp_line
			(start 1.700022 0.899922)
			(end -1.700022 0.899922)
			(stroke
				(width 0.1)
				(type default)
			)
			(layer "F.Fab")
		)
		(fp_line
			(start -1.700022 -0.899922)
			(end 1.700022 -0.899922)
			(stroke
				(width 0.1)
				(type default)
			)
			(layer "F.Fab")
		)
		(fp_line
			(start 1.700022 -0.899922)
			(end 1.700022 0.899922)
			(stroke
				(width 0.1)
				(type default)
			)
			(layer "F.Fab")
		)
		(pad "1" smd rect
			(at -1.4732 0 90)
			(size 1.1684 1.5748)
			(layers "F.Cu" "F.Mask" "F.Paste")
			(net "P52V_HS")
		)
		(pad "2" smd rect
			(at 1.4732 0 90)
			(size 1.1684 1.5748)
			(layers "F.Cu" "F.Mask" "F.Paste")
			(net "GND")
		)
	)
	(footprint ""
		(layer "F.Cu")
		(at 280.39568 -66.152268)
		(property "Reference" "PQ6"
			(at -7.723886 -5.895848 0)
			(unlocked yes)
			(layer "F.SilkS")
			(effects
				(font
					(size 0.7874 0.5842)
					(thickness 0.1524)
				)
				(justify left)
			)
		)
		(property "Value" ""
			(at 0 0 0)
			(layer "F.Fab")
			(effects
				(font
					(size 1.27 1.27)
				)
			)
		)
		(duplicate_pad_numbers_are_jumpers no)
		(fp_line
			(start -7.649972 -4.99999)
			(end -7.649972 -3.3274)
			(stroke
				(width 0.1524)
				(type default)
			)
			(layer "F.SilkS")
		)
		(fp_line
			(start -7.649972 -1.7526)
			(end -7.649972 1.7526)
			(stroke
				(width 0.1524)
				(type default)
			)
			(layer "F.SilkS")
		)
		(fp_line
			(start -7.649972 3.3274)
			(end -7.649972 4.99999)
			(stroke
				(width 0.1524)
				(type default)
			)
			(layer "F.SilkS")
		)
		(fp_line
			(start -7.649972 4.99999)
			(end 5.115814 4.99999)
			(stroke
				(width 0.1524)
				(type default)
			)
			(layer "F.SilkS")
		)
		(fp_line
			(start 5.115814 -4.99999)
			(end -7.649972 -4.99999)
			(stroke
				(width 0.1524)
				(type default)
			)
			(layer "F.SilkS")
		)
		(fp_line
			(start 7.630414 4.99999)
			(end 7.649972 4.99999)
			(stroke
				(width 0.1524)
				(type default)
			)
			(layer "F.SilkS")
		)
		(fp_line
			(start 7.649972 -4.99999)
			(end 7.630414 -4.99999)
			(stroke
				(width 0.1524)
				(type default)
			)
			(layer "F.SilkS")
		)
		(fp_line
			(start 7.649972 4.99999)
			(end 7.649972 -4.99999)
			(stroke
				(width 0.1524)
				(type default)
			)
			(layer "F.SilkS")
		)
		(fp_line
			(start -7.649972 -4.99999)
			(end -7.649972 4.99999)
			(stroke
				(width 0.1)
				(type default)
			)
			(layer "F.Fab")
		)
		(fp_line
			(start -7.649972 4.99999)
			(end 7.649972 4.99999)
			(stroke
				(width 0.1)
				(type default)
			)
			(layer "F.Fab")
		)
		(fp_line
			(start 7.649972 -4.99999)
			(end -7.649972 -4.99999)
			(stroke
				(width 0.1)
				(type default)
			)
			(layer "F.Fab")
		)
		(fp_line
			(start 7.649972 4.99999)
			(end 7.649972 -4.99999)
			(stroke
				(width 0.1)
				(type default)
			)
			(layer "F.Fab")
		)
		(pad "D" smd circle
			(at 2.15011 0)
			(size 0 0)
			(layers "F.Cu" "F.Mask" "F.Paste")
			(net "P52V_HS1_DRAIN_2")
		)
		(pad "G" smd rect
			(at -7.050024 -2.54 270)
			(size 1.3208 3.0988)
			(layers "F.Cu" "F.Mask" "F.Paste")
			(net "P52V_HS1_GATE6")
		)
		(pad "S" smd rect
			(at -7.050024 2.54 270)
			(size 1.3208 3.0988)
			(layers "F.Cu" "F.Mask" "F.Paste")
			(net "P52V_HS")
		)
		(zone
			(layer "F.Cu")
			(hatch none 0.5)
			(connect_pads
				(clearance 0)
			)
			(min_thickness 0.25)
			(keepout
				(tracks not_allowed)
				(vias allowed)
				(pads allowed)
				(copperpour not_allowed)
				(footprints allowed)
			)
			(placement
				(enabled no)
				(sheetname "")
			)
			(fill
				(thermal_gap 0.5)
				(thermal_bridge_width 0.5)
				(island_removal_mode 0)
			)
			(polygon
				(pts
					(xy 285.57728 -71.130668) (xy 272.75028 -71.130668) (xy 272.75028 -69.403468) (xy 274.96008 -69.403468)
					(xy 274.96008 -67.981068) (xy 272.75028 -67.981068) (xy 272.75028 -64.323468) (xy 274.96008 -64.323468)
					(xy 274.96008 -62.901068) (xy 272.75028 -62.901068) (xy 272.75028 -61.173868) (xy 285.57728 -61.173868)
					(xy 285.57728 -62.342268) (xy 279.37968 -62.342268) (xy 279.37968 -69.962268) (xy 285.57728 -69.962268)
				)
			)
		)
	)
	(footprint ""
		(layer "F.Cu")
		(at 276.352 -26.162)
		(property "Reference" "PR6973"
			(at 0 0 0)
			(layer "F.SilkS")
			(hide yes)
			(effects
				(font
					(size 1.27 1.27)
				)
			)
		)
		(property "Value" ""
			(at 0 0 0)
			(layer "F.Fab")
			(effects
				(font
					(size 1.27 1.27)
				)
			)
		)
		(duplicate_pad_numbers_are_jumpers no)
		(fp_line
			(start -0.7874 -0.4064)
			(end 0.7874 -0.4064)
			(stroke
				(width 0.1524)
				(type default)
			)
			(layer "F.SilkS")
		)
		(fp_line
			(start -0.7874 0.4064)
			(end -0.7874 -0.4064)
			(stroke
				(width 0.1524)
				(type default)
			)
			(layer "F.SilkS")
		)
		(fp_line
			(start 0.7874 -0.4064)
			(end 0.7874 0.4064)
			(stroke
				(width 0.1524)
				(type default)
			)
			(layer "F.SilkS")
		)
		(fp_line
			(start 0.7874 0.4064)
			(end -0.7874 0.4064)
			(stroke
				(width 0.1524)
				(type default)
			)
			(layer "F.SilkS")
		)
		(fp_line
			(start -0.67945 -0.305054)
			(end -0.12065 -0.305054)
			(stroke
				(width 0.1)
				(type default)
			)
			(layer "F.Fab")
		)
		(fp_line
			(start -0.67945 0.3048)
			(end -0.67945 -0.305054)
			(stroke
				(width 0.1)
				(type default)
			)
			(layer "F.Fab")
		)
		(fp_line
			(start -0.12065 -0.305054)
			(end -0.12065 -0.2794)
			(stroke
				(width 0.1)
				(type default)
			)
			(layer "F.Fab")
		)
		(fp_line
			(start -0.12065 -0.2794)
			(end 0.12065 -0.2794)
			(stroke
				(width 0.1)
				(type default)
			)
			(layer "F.Fab")
		)
		(fp_line
			(start -0.12065 0.2794)
			(end -0.12065 0.3048)
			(stroke
				(width 0.1)
				(type default)
			)
			(layer "F.Fab")
		)
		(fp_line
			(start -0.12065 0.3048)
			(end -0.67945 0.3048)
			(stroke
				(width 0.1)
				(type default)
			)
			(layer "F.Fab")
		)
		(fp_line
			(start 0.120396 0.2794)
			(end -0.12065 0.2794)
			(stroke
				(width 0.1)
				(type default)
			)
			(layer "F.Fab")
		)
		(fp_line
			(start 0.120396 0.3048)
			(end 0.120396 0.2794)
			(stroke
				(width 0.1)
				(type default)
			)
			(layer "F.Fab")
		)
		(fp_line
			(start 0.12065 -0.3048)
			(end 0.67945 -0.3048)
			(stroke
				(width 0.1)
				(type default)
			)
			(layer "F.Fab")
		)
		(fp_line
			(start 0.12065 -0.2794)
			(end 0.12065 -0.3048)
			(stroke
				(width 0.1)
				(type default)
			)
			(layer "F.Fab")
		)
		(fp_line
			(start 0.67945 -0.3048)
			(end 0.67945 0.3048)
			(stroke
				(width 0.1)
				(type default)
			)
			(layer "F.Fab")
		)
		(fp_line
			(start 0.67945 0.3048)
			(end 0.120396 0.3048)
			(stroke
				(width 0.1)
				(type default)
			)
			(layer "F.Fab")
		)
		(pad "1" smd circle
			(at -0.40005 0)
			(size 0 0)
			(layers "F.Cu" "F.Mask" "F.Paste")
			(net "P52V_HS1_EN")
		)
		(pad "2" smd circle
			(at 0.40005 0)
			(size 0 0)
			(layers "F.Cu" "F.Mask" "F.Paste")
			(net "P52V_HS1_R_EN")
		)
	)
	(footprint ""
		(layer "F.Cu")
		(at 299.593 -124.2695 180)
		(property "Reference" "PR6972"
			(at 0 0 180)
			(layer "F.SilkS")
			(hide yes)
			(effects
				(font
					(size 1.27 1.27)
				)
			)
		)
		(property "Value" ""
			(at 0 0 180)
			(layer "F.Fab")
			(effects
				(font
					(size 1.27 1.27)
				)
			)
		)
		(duplicate_pad_numbers_are_jumpers no)
		(fp_line
			(start 0.7874 0.4064)
			(end -0.7874 0.4064)
			(stroke
				(width 0.1524)
				(type default)
			)
			(layer "F.SilkS")
		)
		(fp_line
			(start 0.7874 -0.4064)
			(end 0.7874 0.4064)
			(stroke
				(width 0.1524)
				(type default)
			)
			(layer "F.SilkS")
		)
		(fp_line
			(start -0.7874 0.4064)
			(end -0.7874 -0.4064)
			(stroke
				(width 0.1524)
				(type default)
			)
			(layer "F.SilkS")
		)
		(fp_line
			(start -0.7874 -0.4064)
			(end 0.7874 -0.4064)
			(stroke
				(width 0.1524)
				(type default)
			)
			(layer "F.SilkS")
		)
		(fp_line
			(start 0.67945 0.3048)
			(end 0.120396 0.3048)
			(stroke
				(width 0.1)
				(type default)
			)
			(layer "F.Fab")
		)
		(fp_line
			(start 0.67945 -0.3048)
			(end 0.67945 0.3048)
			(stroke
				(width 0.1)
				(type default)
			)
			(layer "F.Fab")
		)
		(fp_line
			(start 0.12065 -0.2794)
			(end 0.12065 -0.3048)
			(stroke
				(width 0.1)
				(type default)
			)
			(layer "F.Fab")
		)
		(fp_line
			(start 0.12065 -0.3048)
			(end 0.67945 -0.3048)
			(stroke
				(width 0.1)
				(type default)
			)
			(layer "F.Fab")
		)
		(fp_line
			(start 0.120396 0.3048)
			(end 0.120396 0.2794)
			(stroke
				(width 0.1)
				(type default)
			)
			(layer "F.Fab")
		)
		(fp_line
			(start 0.120396 0.2794)
			(end -0.12065 0.2794)
			(stroke
				(width 0.1)
				(type default)
			)
			(layer "F.Fab")
		)
		(fp_line
			(start -0.12065 0.3048)
			(end -0.67945 0.3048)
			(stroke
				(width 0.1)
				(type default)
			)
			(layer "F.Fab")
		)
		(fp_line
			(start -0.12065 0.2794)
			(end -0.12065 0.3048)
			(stroke
				(width 0.1)
				(type default)
			)
			(layer "F.Fab")
		)
		(fp_line
			(start -0.12065 -0.2794)
			(end 0.12065 -0.2794)
			(stroke
				(width 0.1)
				(type default)
			)
			(layer "F.Fab")
		)
		(fp_line
			(start -0.12065 -0.305054)
			(end -0.12065 -0.2794)
			(stroke
				(width 0.1)
				(type default)
			)
			(layer "F.Fab")
		)
		(fp_line
			(start -0.67945 0.3048)
			(end -0.67945 -0.305054)
			(stroke
				(width 0.1)
				(type default)
			)
			(layer "F.Fab")
		)
		(fp_line
			(start -0.67945 -0.305054)
			(end -0.12065 -0.305054)
			(stroke
				(width 0.1)
				(type default)
			)
			(layer "F.Fab")
		)
		(pad "1" smd circle
			(at -0.40005 0 180)
			(size 0 0)
			(layers "F.Cu" "F.Mask" "F.Paste")
			(net "P52V_HS_4287_S1P")
		)
		(pad "2" smd circle
			(at 0.40005 0 180)
			(size 0 0)
			(layers "F.Cu" "F.Mask" "F.Paste")
			(net "P52V_HS_4287_S1N")
		)
	)
	(footprint ""
		(layer "F.Cu")
		(at 191.643 -8.763)
		(property "Reference" "PC105"
			(at 0 0 0)
			(layer "F.SilkS")
			(hide yes)
			(effects
				(font
					(size 1.27 1.27)
				)
			)
		)
		(property "Value" ""
			(at 0 0 0)
			(layer "F.Fab")
			(effects
				(font
					(size 1.27 1.27)
				)
			)
		)
		(duplicate_pad_numbers_are_jumpers no)
		(fp_line
			(start -1.524 -0.762)
			(end 1.524 -0.762)
			(stroke
				(width 0.1524)
				(type default)
			)
			(layer "F.SilkS")
		)
		(fp_line
			(start -1.524 0.762)
			(end -1.524 -0.762)
			(stroke
				(width 0.1524)
				(type default)
			)
			(layer "F.SilkS")
		)
		(fp_line
			(start 1.524 -0.762)
			(end 1.524 0.762)
			(stroke
				(width 0.1524)
				(type default)
			)
			(layer "F.SilkS")
		)
		(fp_line
			(start 1.524 0.762)
			(end -1.524 0.762)
			(stroke
				(width 0.1524)
				(type default)
			)
			(layer "F.SilkS")
		)
		(fp_line
			(start -1.1049 -0.724916)
			(end -1.1049 0.724916)
			(stroke
				(width 0.1)
				(type default)
			)
			(layer "F.Fab")
		)
		(fp_line
			(start -1.1049 0.724916)
			(end 1.1049 0.724916)
			(stroke
				(width 0.1)
				(type default)
			)
			(layer "F.Fab")
		)
		(fp_line
			(start 1.1049 -0.724916)
			(end -1.1049 -0.724916)
			(stroke
				(width 0.1)
				(type default)
			)
			(layer "F.Fab")
		)
		(fp_line
			(start 1.1049 0.724916)
			(end 1.1049 -0.724916)
			(stroke
				(width 0.1)
				(type default)
			)
			(layer "F.Fab")
		)
		(pad "1" smd rect
			(at -0.889 0 180)
			(size 1.016 1.27)
			(layers "F.Cu" "F.Mask" "F.Paste")
			(net "P3V3_AUX")
		)
		(pad "2" smd rect
			(at 0.889 0 180)
			(size 1.016 1.27)
			(layers "F.Cu" "F.Mask" "F.Paste")
			(net "GND")
		)
	)
	(footprint ""
		(layer "F.Cu")
		(at 41.6814 -57.4548 180)
		(property "Reference" "U32"
			(at 2.3495 -4.91617 0)
			(unlocked yes)
			(layer "F.SilkS")
			(effects
				(font
					(size 0.7874 0.5842)
					(thickness 0.1524)
				)
				(justify left)
			)
		)
		(property "Value" ""
			(at 0 0 180)
			(layer "F.Fab")
			(effects
				(font
					(size 1.27 1.27)
				)
			)
		)
		(duplicate_pad_numbers_are_jumpers no)
		(fp_line
			(start 1.549908 2.549906)
			(end 1.549908 2.253996)
			(stroke
				(width 0.1524)
				(type default)
			)
			(layer "F.SilkS")
		)
		(fp_line
			(start 1.549908 -2.253996)
			(end 1.549908 -2.549906)
			(stroke
				(width 0.1524)
				(type default)
			)
			(layer "F.SilkS")
		)
		(fp_line
			(start 1.549908 -2.549906)
			(end 0.752094 -2.549906)
			(stroke
				(width 0.1524)
				(type default)
			)
			(layer "F.SilkS")
		)
		(fp_line
			(start 0.753872 2.549906)
			(end 1.549908 2.549906)
			(stroke
				(width 0.1524)
				(type default)
			)
			(layer "F.SilkS")
		)
		(fp_line
			(start 0.2413 -2.549906)
			(end -0.2413 -2.549906)
			(stroke
				(width 0.1524)
				(type default)
			)
			(layer "F.SilkS")
		)
		(fp_line
			(start -0.245872 2.549906)
			(end 0.245872 2.549906)
			(stroke
				(width 0.1524)
				(type default)
			)
			(layer "F.SilkS")
		)
		(fp_line
			(start -0.752094 -2.549906)
			(end -1.549908 -2.549906)
			(stroke
				(width 0.1524)
				(type default)
			)
			(layer "F.SilkS")
		)
		(fp_line
			(start -1.549908 2.549906)
			(end -0.753872 2.549906)
			(stroke
				(width 0.1524)
				(type default)
			)
			(layer "F.SilkS")
		)
		(fp_line
			(start -1.549908 2.253996)
			(end -1.549908 2.549906)
			(stroke
				(width 0.1524)
				(type default)
			)
			(layer "F.SilkS")
		)
		(fp_line
			(start -1.549908 -2.549906)
			(end -1.549908 -2.251964)
			(stroke
				(width 0.1524)
				(type default)
			)
			(layer "F.SilkS")
		)
		(fp_poly
			(pts
				(xy -1.95961 -2.28981) (xy -2.862834 -2.591054) (xy -2.260854 -3.193034)
			)
			(stroke
				(width 0)
				(type default)
			)
			(fill yes)
			(layer "F.SilkS")
		)
		(fp_line
			(start 1.549908 2.549906)
			(end 1.549908 -2.549906)
			(stroke
				(width 0.1)
				(type default)
			)
			(layer "F.Fab")
		)
		(fp_line
			(start 1.549908 -2.549906)
			(end -1.549908 -2.549906)
			(stroke
				(width 0.1)
				(type default)
			)
			(layer "F.Fab")
		)
		(fp_line
			(start -1.549908 2.549906)
			(end 1.549908 2.549906)
			(stroke
				(width 0.1)
				(type default)
			)
			(layer "F.Fab")
		)
		(fp_line
			(start -1.549908 -2.549906)
			(end -1.549908 2.549906)
			(stroke
				(width 0.1)
				(type default)
			)
			(layer "F.Fab")
		)
		(fp_poly
			(pts
				(xy -1.891538 -1.999996) (xy -2.7432 -1.574292) (xy -2.7432 -2.4257)
			)
			(stroke
				(width 0)
				(type default)
			)
			(fill yes)
			(layer "F.Fab")
		)
		(fp_text user "12"
			(at 3.16865 5.0292 90)
			(unlocked yes)
			(layer "F.SilkS")
			(effects
				(font
					(size 0.635 0.4064)
					(thickness 0.1524)
				)
			)
		)
		(fp_text user "20"
			(at 2.91465 -3.7338 90)
			(unlocked yes)
			(layer "F.SilkS")
			(effects
				(font
					(size 0.635 0.4064)
					(thickness 0.1524)
				)
			)
		)
		(fp_text user "11"
			(at 2.3114 6.07695 180)
			(unlocked yes)
			(layer "F.SilkS")
			(effects
				(font
					(size 0.635 0.4064)
					(thickness 0.1524)
				)
			)
		)
		(fp_text user "21_22"
			(at -0.0762 -3.401568 180)
			(unlocked yes)
			(layer "F.SilkS")
			(effects
				(font
					(size 0.635 0.4064)
					(thickness 0.1524)
				)
			)
		)
		(fp_text user "10"
			(at -1.4224 3.253232 180)
			(unlocked yes)
			(layer "F.SilkS")
			(effects
				(font
					(size 0.635 0.4064)
					(thickness 0.1524)
				)
			)
		)
		(fp_text user "9"
			(at -2.338832 2.5908 90)
			(unlocked yes)
			(layer "F.SilkS")
			(effects
				(font
					(size 0.635 0.4064)
					(thickness 0.1524)
				)
			)
		)
		(fp_text user "12"
			(at 2.207768 2.7178 90)
			(unlocked yes)
			(layer "F.Fab")
			(effects
				(font
					(size 0.635 0.4064)
					(thickness 0.1524)
				)
			)
		)
		(fp_text user "20"
			(at 2.055368 -2.7686 90)
			(unlocked yes)
			(layer "F.Fab")
			(effects
				(font
					(size 0.635 0.4064)
					(thickness 0.1524)
				)
			)
		)
		(fp_text user "11"
			(at 1.1938 3.329432 180)
			(unlocked yes)
			(layer "F.Fab")
			(effects
				(font
					(size 0.635 0.4064)
					(thickness 0.1524)
				)
			)
		)
		(fp_text user "21_22"
			(at -0.0762 -3.401568 180)
			(unlocked yes)
			(layer "F.Fab")
			(effects
				(font
					(size 0.635 0.4064)
					(thickness 0.1524)
				)
			)
		)
		(fp_text user "10"
			(at -1.4224 3.253232 180)
			(unlocked yes)
			(layer "F.Fab")
			(effects
				(font
					(size 0.635 0.4064)
					(thickness 0.1524)
				)
			)
		)
		(fp_text user "9"
			(at -2.338832 2.5908 90)
			(unlocked yes)
			(layer "F.Fab")
			(effects
				(font
					(size 0.635 0.4064)
					(thickness 0.1524)
				)
			)
		)
		(pad "1" smd circle
			(at -1.374902 -1.999996 90)
			(size 0 0)
			(layers "F.Cu" "F.Mask" "F.Paste")
			(net "P12V_HPDB_0_EN_R")
		)
		(pad "2" smd rect
			(at -1.400048 -1.500124 90)
			(size 0.254 0.8128)
			(layers "F.Cu" "F.Mask" "F.Paste")
			(net "GND")
		)
		(pad "3" smd rect
			(at -1.400048 -0.999998 90)
			(size 0.254 0.8128)
			(layers "F.Cu" "F.Mask" "F.Paste")
			(net "GND")
		)
		(pad "4" smd rect
			(at -1.400048 -0.499872 90)
			(size 0.254 0.8128)
			(layers "F.Cu" "F.Mask" "F.Paste")
			(net "P12V_HPDB_0_TIMER")
		)
		(pad "5" smd rect
			(at -1.400048 0 90)
			(size 0.254 0.8128)
			(layers "F.Cu" "F.Mask" "F.Paste")
			(net "P12V_HPDB_0_ISET")
		)
		(pad "6" smd rect
			(at -1.400048 0.499872 90)
			(size 0.254 0.8128)
			(layers "F.Cu" "F.Mask" "F.Paste")
			(net "P12V_HPDB_0_SS")
		)
		(pad "7" smd rect
			(at -1.400048 0.999998 90)
			(size 0.254 0.8128)
			(layers "F.Cu" "F.Mask" "F.Paste")
			(net "GND")
		)
		(pad "8" smd rect
			(at -1.400048 1.500124 90)
			(size 0.254 0.8128)
			(layers "F.Cu" "F.Mask" "F.Paste")
			(net "P12V_HPDB_0_IMON")
		)
		(pad "9" smd rect
			(at -1.400048 1.999996 90)
			(size 0.254 0.8128)
			(layers "F.Cu" "F.Mask" "F.Paste")
			(net "P12V_HPDB_0_FLTB")
		)
		(pad "10" smd rect
			(at -0.499872 2.400046 180)
			(size 0.254 0.8128)
			(layers "F.Cu" "F.Mask" "F.Paste")
			(net "P12V_HPDB_PWRGD")
		)
		(pad "11" smd rect
			(at 0.499872 2.400046 180)
			(size 0.254 0.8128)
			(layers "F.Cu" "F.Mask" "F.Paste")
			(net "P12V_HPDB_0_FB")
		)
		(pad "12" smd rect
			(at 1.400048 1.999996 90)
			(size 0.254 0.8128)
			(layers "F.Cu" "F.Mask" "F.Paste")
			(net "P12V_HPDB_0_PD")
		)
		(pad "13" smd rect
			(at 1.400048 1.500124 90)
			(size 0.254 0.8128)
			(layers "F.Cu" "F.Mask" "F.Paste")
			(net "P12V_HPDB")
		)
		(pad "14" smd rect
			(at 1.400048 0.999998 90)
			(size 0.254 0.8128)
			(layers "F.Cu" "F.Mask" "F.Paste")
			(net "P12V_HPDB")
		)
		(pad "15" smd rect
			(at 1.400048 0.499872 90)
			(size 0.254 0.8128)
			(layers "F.Cu" "F.Mask" "F.Paste")
			(net "P12V_HPDB")
		)
		(pad "16" smd rect
			(at 1.400048 0 90)
			(size 0.254 0.8128)
			(layers "F.Cu" "F.Mask" "F.Paste")
			(net "P12V_HPDB")
		)
		(pad "17" smd rect
			(at 1.400048 -0.499872 90)
			(size 0.254 0.8128)
			(layers "F.Cu" "F.Mask" "F.Paste")
			(net "P12V_HPDB")
		)
		(pad "18" smd rect
			(at 1.400048 -0.999998 90)
			(size 0.254 0.8128)
			(layers "F.Cu" "F.Mask" "F.Paste")
			(net "P12V_HPDB")
		)
		(pad "19" smd rect
			(at 1.400048 -1.500124 90)
			(size 0.254 0.8128)
			(layers "F.Cu" "F.Mask" "F.Paste")
			(net "P12V_HPDB")
		)
		(pad "20" smd rect
			(at 1.400048 -1.999996 90)
			(size 0.254 0.8128)
			(layers "F.Cu" "F.Mask" "F.Paste")
			(net "P12V_HPDB")
		)
		(pad "21_22" smd circle
			(at 0.499872 -2.337562 90)
			(size 0 0)
			(layers "F.Cu" "F.Mask" "F.Paste")
			(net "P12V_BRICK")
		)
		(pad "23" smd rect
			(at 0 -1.100074 90)
			(size 0.254 1.27)
			(layers "F.Cu" "F.Mask" "F.Paste")
			(net "P12V_BRICK")
		)
		(pad "24" smd rect
			(at 0 -0.199898 90)
			(size 0.254 1.27)
			(layers "F.Cu" "F.Mask" "F.Paste")
			(net "P12V_BRICK")
		)
		(pad "25" smd rect
			(at 0 0.700024 90)
			(size 0.254 1.27)
			(layers "F.Cu" "F.Mask" "F.Paste")
			(net "P12V_BRICK")
		)
		(pad "26" smd rect
			(at 0 1.599946 90)
			(size 0.254 1.27)
			(layers "F.Cu" "F.Mask" "F.Paste")
			(net "P12V_BRICK")
		)
	)
	(footprint ""
		(layer "F.Cu")
		(at 149.098 -130.175)
		(property "Reference" "PC18"
			(at 0 0 0)
			(layer "F.SilkS")
			(hide yes)
			(effects
				(font
					(size 1.27 1.27)
				)
			)
		)
		(property "Value" ""
			(at 0 0 0)
			(layer "F.Fab")
			(effects
				(font
					(size 1.27 1.27)
				)
			)
		)
		(duplicate_pad_numbers_are_jumpers no)
		(fp_line
			(start -2.2098 -0.9398)
			(end 2.2098 -0.9398)
			(stroke
				(width 0.1524)
				(type default)
			)
			(layer "F.SilkS")
		)
		(fp_line
			(start -2.2098 0.9398)
			(end -2.2098 -0.9398)
			(stroke
				(width 0.1524)
				(type default)
			)
			(layer "F.SilkS")
		)
		(fp_line
			(start 2.2098 -0.9398)
			(end 2.2098 0.9398)
			(stroke
				(width 0.1524)
				(type default)
			)
			(layer "F.SilkS")
		)
		(fp_line
			(start 2.2098 0.9398)
			(end -2.2098 0.9398)
			(stroke
				(width 0.1524)
				(type default)
			)
			(layer "F.SilkS")
		)
		(fp_line
			(start -1.700022 -0.899922)
			(end 1.700022 -0.899922)
			(stroke
				(width 0.1)
				(type default)
			)
			(layer "F.Fab")
		)
		(fp_line
			(start -1.700022 0.899922)
			(end -1.700022 -0.899922)
			(stroke
				(width 0.1)
				(type default)
			)
			(layer "F.Fab")
		)
		(fp_line
			(start 1.700022 -0.899922)
			(end 1.700022 0.899922)
			(stroke
				(width 0.1)
				(type default)
			)
			(layer "F.Fab")
		)
		(fp_line
			(start 1.700022 0.899922)
			(end -1.700022 0.899922)
			(stroke
				(width 0.1)
				(type default)
			)
			(layer "F.Fab")
		)
		(pad "1" smd rect
			(at -1.4732 0 180)
			(size 1.1684 1.5748)
			(layers "F.Cu" "F.Mask" "F.Paste")
			(net "P52V_HS_FILTER")
		)
		(pad "2" smd rect
			(at 1.4732 0 180)
			(size 1.1684 1.5748)
			(layers "F.Cu" "F.Mask" "F.Paste")
			(net "GND")
		)
	)
	(footprint ""
		(layer "F.Cu")
		(at 168.148 -49.911)
		(property "Reference" "PC33"
			(at 0 0 0)
			(layer "F.SilkS")
			(hide yes)
			(effects
				(font
					(size 1.27 1.27)
				)
			)
		)
		(property "Value" ""
			(at 0 0 0)
			(layer "F.Fab")
			(effects
				(font
					(size 1.27 1.27)
				)
			)
		)
		(duplicate_pad_numbers_are_jumpers no)
		(fp_line
			(start -1.524 -0.762)
			(end 1.524 -0.762)
			(stroke
				(width 0.1524)
				(type default)
			)
			(layer "F.SilkS")
		)
		(fp_line
			(start -1.524 0.762)
			(end -1.524 -0.762)
			(stroke
				(width 0.1524)
				(type default)
			)
			(layer "F.SilkS")
		)
		(fp_line
			(start 1.524 -0.762)
			(end 1.524 0.762)
			(stroke
				(width 0.1524)
				(type default)
			)
			(layer "F.SilkS")
		)
		(fp_line
			(start 1.524 0.762)
			(end -1.524 0.762)
			(stroke
				(width 0.1524)
				(type default)
			)
			(layer "F.SilkS")
		)
		(fp_line
			(start -1.1049 -0.724916)
			(end -1.1049 0.724916)
			(stroke
				(width 0.1)
				(type default)
			)
			(layer "F.Fab")
		)
		(fp_line
			(start -1.1049 0.724916)
			(end 1.1049 0.724916)
			(stroke
				(width 0.1)
				(type default)
			)
			(layer "F.Fab")
		)
		(fp_line
			(start 1.1049 -0.724916)
			(end -1.1049 -0.724916)
			(stroke
				(width 0.1)
				(type default)
			)
			(layer "F.Fab")
		)
		(fp_line
			(start 1.1049 0.724916)
			(end 1.1049 -0.724916)
			(stroke
				(width 0.1)
				(type default)
			)
			(layer "F.Fab")
		)
		(pad "1" smd rect
			(at -0.889 0 180)
			(size 1.016 1.27)
			(layers "F.Cu" "F.Mask" "F.Paste")
			(net "P12V_BRICK")
		)
		(pad "2" smd rect
			(at 0.889 0 180)
			(size 1.016 1.27)
			(layers "F.Cu" "F.Mask" "F.Paste")
			(net "GND")
		)
	)
	(footprint ""
		(layer "F.Cu")
		(at 136.906 -130.175)
		(property "Reference" "PC21"
			(at 0 0 0)
			(layer "F.SilkS")
			(hide yes)
			(effects
				(font
					(size 1.27 1.27)
				)
			)
		)
		(property "Value" ""
			(at 0 0 0)
			(layer "F.Fab")
			(effects
				(font
					(size 1.27 1.27)
				)
			)
		)
		(duplicate_pad_numbers_are_jumpers no)
		(fp_line
			(start -2.2098 -0.9398)
			(end 2.2098 -0.9398)
			(stroke
				(width 0.1524)
				(type default)
			)
			(layer "F.SilkS")
		)
		(fp_line
			(start -2.2098 0.9398)
			(end -2.2098 -0.9398)
			(stroke
				(width 0.1524)
				(type default)
			)
			(layer "F.SilkS")
		)
		(fp_line
			(start 2.2098 -0.9398)
			(end 2.2098 0.9398)
			(stroke
				(width 0.1524)
				(type default)
			)
			(layer "F.SilkS")
		)
		(fp_line
			(start 2.2098 0.9398)
			(end -2.2098 0.9398)
			(stroke
				(width 0.1524)
				(type default)
			)
			(layer "F.SilkS")
		)
		(fp_line
			(start -1.700022 -0.899922)
			(end 1.700022 -0.899922)
			(stroke
				(width 0.1)
				(type default)
			)
			(layer "F.Fab")
		)
		(fp_line
			(start -1.700022 0.899922)
			(end -1.700022 -0.899922)
			(stroke
				(width 0.1)
				(type default)
			)
			(layer "F.Fab")
		)
		(fp_line
			(start 1.700022 -0.899922)
			(end 1.700022 0.899922)
			(stroke
				(width 0.1)
				(type default)
			)
			(layer "F.Fab")
		)
		(fp_line
			(start 1.700022 0.899922)
			(end -1.700022 0.899922)
			(stroke
				(width 0.1)
				(type default)
			)
			(layer "F.Fab")
		)
		(pad "1" smd rect
			(at -1.4732 0 180)
			(size 1.1684 1.5748)
			(layers "F.Cu" "F.Mask" "F.Paste")
			(net "P52V_HS_FILTER")
		)
		(pad "2" smd rect
			(at 1.4732 0 180)
			(size 1.1684 1.5748)
			(layers "F.Cu" "F.Mask" "F.Paste")
			(net "GND")
		)
	)
	(footprint ""
		(layer "F.Cu")
		(at 279.019 -37.465)
		(property "Reference" "R144"
			(at 0 0 0)
			(layer "F.SilkS")
			(hide yes)
			(effects
				(font
					(size 1.27 1.27)
				)
			)
		)
		(property "Value" ""
			(at 0 0 0)
			(layer "F.Fab")
			(effects
				(font
					(size 1.27 1.27)
				)
			)
		)
		(duplicate_pad_numbers_are_jumpers no)
		(fp_line
			(start -0.7874 -0.4064)
			(end 0.7874 -0.4064)
			(stroke
				(width 0.1524)
				(type default)
			)
			(layer "F.SilkS")
		)
		(fp_line
			(start -0.7874 0.4064)
			(end -0.7874 -0.4064)
			(stroke
				(width 0.1524)
				(type default)
			)
			(layer "F.SilkS")
		)
		(fp_line
			(start 0.7874 -0.4064)
			(end 0.7874 0.4064)
			(stroke
				(width 0.1524)
				(type default)
			)
			(layer "F.SilkS")
		)
		(fp_line
			(start 0.7874 0.4064)
			(end -0.7874 0.4064)
			(stroke
				(width 0.1524)
				(type default)
			)
			(layer "F.SilkS")
		)
		(fp_line
			(start -0.67945 -0.305054)
			(end -0.12065 -0.305054)
			(stroke
				(width 0.1)
				(type default)
			)
			(layer "F.Fab")
		)
		(fp_line
			(start -0.67945 0.3048)
			(end -0.67945 -0.305054)
			(stroke
				(width 0.1)
				(type default)
			)
			(layer "F.Fab")
		)
		(fp_line
			(start -0.12065 -0.305054)
			(end -0.12065 -0.2794)
			(stroke
				(width 0.1)
				(type default)
			)
			(layer "F.Fab")
		)
		(fp_line
			(start -0.12065 -0.2794)
			(end 0.12065 -0.2794)
			(stroke
				(width 0.1)
				(type default)
			)
			(layer "F.Fab")
		)
		(fp_line
			(start -0.12065 0.2794)
			(end -0.12065 0.3048)
			(stroke
				(width 0.1)
				(type default)
			)
			(layer "F.Fab")
		)
		(fp_line
			(start -0.12065 0.3048)
			(end -0.67945 0.3048)
			(stroke
				(width 0.1)
				(type default)
			)
			(layer "F.Fab")
		)
		(fp_line
			(start 0.120396 0.2794)
			(end -0.12065 0.2794)
			(stroke
				(width 0.1)
				(type default)
			)
			(layer "F.Fab")
		)
		(fp_line
			(start 0.120396 0.3048)
			(end 0.120396 0.2794)
			(stroke
				(width 0.1)
				(type default)
			)
			(layer "F.Fab")
		)
		(fp_line
			(start 0.12065 -0.3048)
			(end 0.67945 -0.3048)
			(stroke
				(width 0.1)
				(type default)
			)
			(layer "F.Fab")
		)
		(fp_line
			(start 0.12065 -0.2794)
			(end 0.12065 -0.3048)
			(stroke
				(width 0.1)
				(type default)
			)
			(layer "F.Fab")
		)
		(fp_line
			(start 0.67945 -0.3048)
			(end 0.67945 0.3048)
			(stroke
				(width 0.1)
				(type default)
			)
			(layer "F.Fab")
		)
		(fp_line
			(start 0.67945 0.3048)
			(end 0.120396 0.3048)
			(stroke
				(width 0.1)
				(type default)
			)
			(layer "F.Fab")
		)
		(pad "1" smd circle
			(at -0.40005 0)
			(size 0 0)
			(layers "F.Cu" "F.Mask" "F.Paste")
			(net "SMB_P52V_HSC_SDA")
		)
		(pad "2" smd circle
			(at 0.40005 0)
			(size 0 0)
			(layers "F.Cu" "F.Mask" "F.Paste")
			(net "SMB_CM_HS1_3V3SB_DATI")
		)
	)
	(footprint ""
		(layer "F.Cu")
		(at 279.908 -44.069)
		(property "Reference" "PR6934"
			(at 0 0 0)
			(layer "F.SilkS")
			(hide yes)
			(effects
				(font
					(size 1.27 1.27)
				)
			)
		)
		(property "Value" ""
			(at 0 0 0)
			(layer "F.Fab")
			(effects
				(font
					(size 1.27 1.27)
				)
			)
		)
		(duplicate_pad_numbers_are_jumpers no)
		(fp_line
			(start -0.7874 -0.4064)
			(end 0.7874 -0.4064)
			(stroke
				(width 0.1524)
				(type default)
			)
			(layer "F.SilkS")
		)
		(fp_line
			(start -0.7874 0.4064)
			(end -0.7874 -0.4064)
			(stroke
				(width 0.1524)
				(type default)
			)
			(layer "F.SilkS")
		)
		(fp_line
			(start 0.7874 -0.4064)
			(end 0.7874 0.4064)
			(stroke
				(width 0.1524)
				(type default)
			)
			(layer "F.SilkS")
		)
		(fp_line
			(start 0.7874 0.4064)
			(end -0.7874 0.4064)
			(stroke
				(width 0.1524)
				(type default)
			)
			(layer "F.SilkS")
		)
		(fp_line
			(start -0.67945 -0.305054)
			(end -0.12065 -0.305054)
			(stroke
				(width 0.1)
				(type default)
			)
			(layer "F.Fab")
		)
		(fp_line
			(start -0.67945 0.3048)
			(end -0.67945 -0.305054)
			(stroke
				(width 0.1)
				(type default)
			)
			(layer "F.Fab")
		)
		(fp_line
			(start -0.12065 -0.305054)
			(end -0.12065 -0.2794)
			(stroke
				(width 0.1)
				(type default)
			)
			(layer "F.Fab")
		)
		(fp_line
			(start -0.12065 -0.2794)
			(end 0.12065 -0.2794)
			(stroke
				(width 0.1)
				(type default)
			)
			(layer "F.Fab")
		)
		(fp_line
			(start -0.12065 0.2794)
			(end -0.12065 0.3048)
			(stroke
				(width 0.1)
				(type default)
			)
			(layer "F.Fab")
		)
		(fp_line
			(start -0.12065 0.3048)
			(end -0.67945 0.3048)
			(stroke
				(width 0.1)
				(type default)
			)
			(layer "F.Fab")
		)
		(fp_line
			(start 0.120396 0.2794)
			(end -0.12065 0.2794)
			(stroke
				(width 0.1)
				(type default)
			)
			(layer "F.Fab")
		)
		(fp_line
			(start 0.120396 0.3048)
			(end 0.120396 0.2794)
			(stroke
				(width 0.1)
				(type default)
			)
			(layer "F.Fab")
		)
		(fp_line
			(start 0.12065 -0.3048)
			(end 0.67945 -0.3048)
			(stroke
				(width 0.1)
				(type default)
			)
			(layer "F.Fab")
		)
		(fp_line
			(start 0.12065 -0.2794)
			(end 0.12065 -0.3048)
			(stroke
				(width 0.1)
				(type default)
			)
			(layer "F.Fab")
		)
		(fp_line
			(start 0.67945 -0.3048)
			(end 0.67945 0.3048)
			(stroke
				(width 0.1)
				(type default)
			)
			(layer "F.Fab")
		)
		(fp_line
			(start 0.67945 0.3048)
			(end 0.120396 0.3048)
			(stroke
				(width 0.1)
				(type default)
			)
			(layer "F.Fab")
		)
		(pad "1" smd circle
			(at -0.40005 0)
			(size 0 0)
			(layers "F.Cu" "F.Mask" "F.Paste")
			(net "P52V_HS1_ISTART")
		)
		(pad "2" smd circle
			(at 0.40005 0)
			(size 0 0)
			(layers "F.Cu" "F.Mask" "F.Paste")
			(net "P52V_HS1_VCAP")
		)
	)
	(footprint ""
		(layer "F.Cu")
		(at 209.931 -93.6244 180)
		(property "Reference" "R57"
			(at 0 0 180)
			(layer "F.SilkS")
			(hide yes)
			(effects
				(font
					(size 1.27 1.27)
				)
			)
		)
		(property "Value" ""
			(at 0 0 180)
			(layer "F.Fab")
			(effects
				(font
					(size 1.27 1.27)
				)
			)
		)
		(duplicate_pad_numbers_are_jumpers no)
		(fp_line
			(start 2.234946 0.9271)
			(end -2.234946 0.9271)
			(stroke
				(width 0.1524)
				(type default)
			)
			(layer "F.SilkS")
		)
		(fp_line
			(start 2.234946 -0.9271)
			(end 2.234946 0.9271)
			(stroke
				(width 0.1524)
				(type default)
			)
			(layer "F.SilkS")
		)
		(fp_line
			(start -2.234946 0.9271)
			(end -2.234946 -0.9271)
			(stroke
				(width 0.1524)
				(type default)
			)
			(layer "F.SilkS")
		)
		(fp_line
			(start -2.234946 -0.9271)
			(end 2.234946 -0.9271)
			(stroke
				(width 0.1524)
				(type default)
			)
			(layer "F.SilkS")
		)
		(fp_line
			(start 1.575054 0.824992)
			(end 1.575054 -0.824992)
			(stroke
				(width 0.1)
				(type default)
			)
			(layer "F.Fab")
		)
		(fp_line
			(start 1.575054 -0.824992)
			(end -1.575054 -0.824992)
			(stroke
				(width 0.1)
				(type default)
			)
			(layer "F.Fab")
		)
		(fp_line
			(start -1.575054 0.824992)
			(end 1.575054 0.824992)
			(stroke
				(width 0.1)
				(type default)
			)
			(layer "F.Fab")
		)
		(fp_line
			(start -1.575054 -0.824992)
			(end -1.575054 0.824992)
			(stroke
				(width 0.1)
				(type default)
			)
			(layer "F.Fab")
		)
		(pad "1" smd rect
			(at -1.599946 0 180)
			(size 1.016 1.6002)
			(layers "F.Cu" "F.Mask" "F.Paste")
			(net "LED_D1_R1")
		)
		(pad "2" smd rect
			(at 1.599946 0 180)
			(size 1.016 1.6002)
			(layers "F.Cu" "F.Mask" "F.Paste")
			(net "LED_D1_R2")
		)
	)
	(footprint ""
		(layer "F.Cu")
		(at 186.431174 -136.906 90)
		(property "Reference" "PC113"
			(at 6.06933 0.639826 0)
			(unlocked yes)
			(layer "F.SilkS")
			(effects
				(font
					(size 0.7874 0.5842)
					(thickness 0.1524)
				)
				(justify left)
			)
		)
		(property "Value" ""
			(at 0 0 90)
			(layer "F.Fab")
			(effects
				(font
					(size 1.27 1.27)
				)
			)
		)
		(duplicate_pad_numbers_are_jumpers no)
		(fp_line
			(start 5.2578 2.499868)
			(end -5.2578 2.499868)
			(stroke
				(width 0.1524)
				(type default)
			)
			(layer "F.SilkS")
		)
		(fp_circle
			(center 0 2.500122)
			(end 0 7.758176)
			(stroke
				(width 0.1524)
				(type default)
			)
			(fill no)
			(layer "F.SilkS")
		)
		(fp_poly
			(pts
				(arc
					(start 5.2578 2.499868)
					(mid 0 7.757922)
					(end -5.2578 2.499868)
				)
			)
			(stroke
				(width 0)
				(type default)
			)
			(fill yes)
			(layer "F.SilkS")
		)
		(fp_circle
			(center 0 2.500122)
			(end 0 7.758176)
			(stroke
				(width 0.1)
				(type default)
			)
			(fill no)
			(layer "F.Fab")
		)
		(pad "1" thru_hole rect
			(at 0 0)
			(size 1.5748 1.5748)
			(drill 1.0668)
			(layers "*.Cu" "*.Mask")
			(remove_unused_layers no)
			(net "P52V_HS_FILTER")
			(clearance 0)
			(padstack
				(mode front_inner_back)
				(layer "Inner"
					(shape circle)
					(size 1.5748 1.5748)
					(clearance 0)
				)
				(layer "B.Cu"
					(shape rect)
					(size 1.5748 1.5748)
					(clearance 0)
				)
			)
		)
		(pad "2" thru_hole circle
			(at 0 4.99999)
			(size 1.5748 1.5748)
			(drill 1.0668)
			(layers "*.Cu" "*.Mask")
			(remove_unused_layers no)
			(net "GND")
			(clearance 0)
		)
	)
	(footprint ""
		(layer "F.Cu")
		(at 241.808 -95.504 -90)
		(property "Reference" "C45"
			(at 0 0 270)
			(layer "F.SilkS")
			(hide yes)
			(effects
				(font
					(size 1.27 1.27)
				)
			)
		)
		(property "Value" ""
			(at 0 0 270)
			(layer "F.Fab")
			(effects
				(font
					(size 1.27 1.27)
				)
			)
		)
		(duplicate_pad_numbers_are_jumpers no)
		(fp_line
			(start -2.2098 0.9398)
			(end -2.2098 -0.9398)
			(stroke
				(width 0.1524)
				(type default)
			)
			(layer "F.SilkS")
		)
		(fp_line
			(start 2.2098 0.9398)
			(end -2.2098 0.9398)
			(stroke
				(width 0.1524)
				(type default)
			)
			(layer "F.SilkS")
		)
		(fp_line
			(start -2.2098 -0.9398)
			(end 2.2098 -0.9398)
			(stroke
				(width 0.1524)
				(type default)
			)
			(layer "F.SilkS")
		)
		(fp_line
			(start 2.2098 -0.9398)
			(end 2.2098 0.9398)
			(stroke
				(width 0.1524)
				(type default)
			)
			(layer "F.SilkS")
		)
		(fp_line
			(start -1.700022 0.899922)
			(end -1.700022 -0.899922)
			(stroke
				(width 0.1)
				(type default)
			)
			(layer "F.Fab")
		)
		(fp_line
			(start 1.700022 0.899922)
			(end -1.700022 0.899922)
			(stroke
				(width 0.1)
				(type default)
			)
			(layer "F.Fab")
		)
		(fp_line
			(start -1.700022 -0.899922)
			(end 1.700022 -0.899922)
			(stroke
				(width 0.1)
				(type default)
			)
			(layer "F.Fab")
		)
		(fp_line
			(start 1.700022 -0.899922)
			(end 1.700022 0.899922)
			(stroke
				(width 0.1)
				(type default)
			)
			(layer "F.Fab")
		)
		(pad "1" smd rect
			(at -1.4732 0 90)
			(size 1.1684 1.5748)
			(layers "F.Cu" "F.Mask" "F.Paste")
			(net "P52V_HS")
		)
		(pad "2" smd rect
			(at 1.4732 0 90)
			(size 1.1684 1.5748)
			(layers "F.Cu" "F.Mask" "F.Paste")
			(net "GND")
		)
	)
	(footprint ""
		(layer "F.Cu")
		(at 222.88754 -141.88948)
		(property "Reference" "H23"
			(at -1.143 -3.65633 0)
			(unlocked yes)
			(layer "F.SilkS")
			(effects
				(font
					(size 0.7874 0.5842)
					(thickness 0.1524)
				)
				(justify left)
			)
		)
		(property "Value" ""
			(at 0 0 0)
			(layer "F.Fab")
			(effects
				(font
					(size 1.27 1.27)
				)
			)
		)
		(duplicate_pad_numbers_are_jumpers no)
		(fp_circle
			(center 0 0)
			(end 2.4003 0)
			(stroke
				(width 0.1524)
				(type default)
			)
			(fill no)
			(layer "F.SilkS")
		)
		(fp_arc
			(start 5.098288 -4.177538)
			(mid 6.206839 -2.21816)
			(end 6.5913 0)
			(stroke
				(width 0.1524)
				(type default)
			)
			(layer "B.SilkS")
		)
		(fp_arc
			(start 6.5913 0)
			(mid -2.179183 6.220643)
			(end -5.150358 -4.113276)
			(stroke
				(width 0.1524)
				(type default)
			)
			(layer "B.SilkS")
		)
		(fp_circle
			(center 0 0)
			(end 6.5913 0)
			(stroke
				(width 0.1)
				(type default)
			)
			(fill no)
			(layer "B.Fab")
		)
		(fp_circle
			(center 0 0)
			(end 2.4003 0)
			(stroke
				(width 0.1)
				(type default)
			)
			(fill no)
			(layer "F.Fab")
		)
		(pad "" np_thru_hole circle
			(at 0 0)
			(size 3.175 3.175)
			(drill 3.175)
			(layers "*.Cu" "*.Mask")
			(clearance 0.381)
			(thermal_gap 0.381)
		)
		(zone
			(layers "F.Cu" "B.Cu" "In1.Cu" "In2.Cu" "In3.Cu" "In4.Cu" "In5.Cu" "In6.Cu"
				"In7.Cu" "In8.Cu"
			)
			(hatch none 0.5)
			(connect_pads
				(clearance 0)
			)
			(min_thickness 0.25)
			(keepout
				(tracks not_allowed)
				(vias allowed)
				(pads allowed)
				(copperpour not_allowed)
				(footprints allowed)
			)
			(placement
				(enabled no)
				(sheetname "")
			)
			(fill
				(thermal_gap 0.5)
				(thermal_bridge_width 0.5)
				(island_removal_mode 0)
			)
			(polygon
				(pts
					(arc
						(start 224.98304 -141.88948)
						(mid 220.79204 -141.88948)
						(end 224.98304 -141.88948)
					)
				)
			)
		)
	)
	(footprint ""
		(layer "F.Cu")
		(at 264.668 -32.131 180)
		(property "Reference" "PC83"
			(at 0 0 180)
			(layer "F.SilkS")
			(hide yes)
			(effects
				(font
					(size 1.27 1.27)
				)
			)
		)
		(property "Value" ""
			(at 0 0 180)
			(layer "F.Fab")
			(effects
				(font
					(size 1.27 1.27)
				)
			)
		)
		(duplicate_pad_numbers_are_jumpers no)
		(fp_line
			(start 1.2954 0.5842)
			(end -1.2954 0.5842)
			(stroke
				(width 0.1524)
				(type default)
			)
			(layer "F.SilkS")
		)
		(fp_line
			(start 1.2954 -0.5842)
			(end 1.2954 0.5842)
			(stroke
				(width 0.1524)
				(type default)
			)
			(layer "F.SilkS")
		)
		(fp_line
			(start -1.2954 0.5842)
			(end -1.2954 -0.5842)
			(stroke
				(width 0.1524)
				(type default)
			)
			(layer "F.SilkS")
		)
		(fp_line
			(start -1.2954 -0.5842)
			(end 1.2954 -0.5842)
			(stroke
				(width 0.1524)
				(type default)
			)
			(layer "F.SilkS")
		)
		(fp_line
			(start 1.1938 0.4064)
			(end 0.8636 0.4064)
			(stroke
				(width 0.1)
				(type default)
			)
			(layer "F.Fab")
		)
		(fp_line
			(start 1.1938 -0.4064)
			(end 1.1938 0.4064)
			(stroke
				(width 0.1)
				(type default)
			)
			(layer "F.Fab")
		)
		(fp_line
			(start 0.8636 0.4572)
			(end -0.8636 0.4572)
			(stroke
				(width 0.1)
				(type default)
			)
			(layer "F.Fab")
		)
		(fp_line
			(start 0.8636 0.4064)
			(end 0.8636 0.4572)
			(stroke
				(width 0.1)
				(type default)
			)
			(layer "F.Fab")
		)
		(fp_line
			(start 0.8636 -0.4064)
			(end 1.1938 -0.4064)
			(stroke
				(width 0.1)
				(type default)
			)
			(layer "F.Fab")
		)
		(fp_line
			(start 0.8636 -0.4572)
			(end 0.8636 -0.4064)
			(stroke
				(width 0.1)
				(type default)
			)
			(layer "F.Fab")
		)
		(fp_line
			(start -0.8636 0.4572)
			(end -0.8636 0.4064)
			(stroke
				(width 0.1)
				(type default)
			)
			(layer "F.Fab")
		)
		(fp_line
			(start -0.8636 0.4064)
			(end -1.1938 0.4064)
			(stroke
				(width 0.1)
				(type default)
			)
			(layer "F.Fab")
		)
		(fp_line
			(start -0.8636 -0.4064)
			(end -0.8636 -0.4572)
			(stroke
				(width 0.1)
				(type default)
			)
			(layer "F.Fab")
		)
		(fp_line
			(start -0.8636 -0.4572)
			(end 0.8636 -0.4572)
			(stroke
				(width 0.1)
				(type default)
			)
			(layer "F.Fab")
		)
		(fp_line
			(start -1.1938 0.4064)
			(end -1.1938 -0.4064)
			(stroke
				(width 0.1)
				(type default)
			)
			(layer "F.Fab")
		)
		(fp_line
			(start -1.1938 -0.4064)
			(end -0.8636 -0.4064)
			(stroke
				(width 0.1)
				(type default)
			)
			(layer "F.Fab")
		)
		(pad "1" smd rect
			(at -0.7366 0 90)
			(size 0.7112 0.8128)
			(layers "F.Cu" "F.Mask" "F.Paste")
			(net "HS1_TMR2")
		)
		(pad "2" smd rect
			(at 0.7366 0 90)
			(size 0.7112 0.8128)
			(layers "F.Cu" "F.Mask" "F.Paste")
			(net "GND_FIELD_SIGNAL")
		)
	)
	(footprint ""
		(layer "F.Cu")
		(at 285.623 -35.168078 180)
		(property "Reference" "R149"
			(at 0 0 180)
			(layer "F.SilkS")
			(hide yes)
			(effects
				(font
					(size 1.27 1.27)
				)
			)
		)
		(property "Value" ""
			(at 0 0 180)
			(layer "F.Fab")
			(effects
				(font
					(size 1.27 1.27)
				)
			)
		)
		(duplicate_pad_numbers_are_jumpers no)
		(fp_line
			(start 0.7874 0.4064)
			(end -0.7874 0.4064)
			(stroke
				(width 0.1524)
				(type default)
			)
			(layer "F.SilkS")
		)
		(fp_line
			(start 0.7874 -0.4064)
			(end 0.7874 0.4064)
			(stroke
				(width 0.1524)
				(type default)
			)
			(layer "F.SilkS")
		)
		(fp_line
			(start -0.7874 0.4064)
			(end -0.7874 -0.4064)
			(stroke
				(width 0.1524)
				(type default)
			)
			(layer "F.SilkS")
		)
		(fp_line
			(start -0.7874 -0.4064)
			(end 0.7874 -0.4064)
			(stroke
				(width 0.1524)
				(type default)
			)
			(layer "F.SilkS")
		)
		(fp_line
			(start 0.67945 0.3048)
			(end 0.120396 0.3048)
			(stroke
				(width 0.1)
				(type default)
			)
			(layer "F.Fab")
		)
		(fp_line
			(start 0.67945 -0.3048)
			(end 0.67945 0.3048)
			(stroke
				(width 0.1)
				(type default)
			)
			(layer "F.Fab")
		)
		(fp_line
			(start 0.12065 -0.2794)
			(end 0.12065 -0.3048)
			(stroke
				(width 0.1)
				(type default)
			)
			(layer "F.Fab")
		)
		(fp_line
			(start 0.12065 -0.3048)
			(end 0.67945 -0.3048)
			(stroke
				(width 0.1)
				(type default)
			)
			(layer "F.Fab")
		)
		(fp_line
			(start 0.120396 0.3048)
			(end 0.120396 0.2794)
			(stroke
				(width 0.1)
				(type default)
			)
			(layer "F.Fab")
		)
		(fp_line
			(start 0.120396 0.2794)
			(end -0.12065 0.2794)
			(stroke
				(width 0.1)
				(type default)
			)
			(layer "F.Fab")
		)
		(fp_line
			(start -0.12065 0.3048)
			(end -0.67945 0.3048)
			(stroke
				(width 0.1)
				(type default)
			)
			(layer "F.Fab")
		)
		(fp_line
			(start -0.12065 0.2794)
			(end -0.12065 0.3048)
			(stroke
				(width 0.1)
				(type default)
			)
			(layer "F.Fab")
		)
		(fp_line
			(start -0.12065 -0.2794)
			(end 0.12065 -0.2794)
			(stroke
				(width 0.1)
				(type default)
			)
			(layer "F.Fab")
		)
		(fp_line
			(start -0.12065 -0.305054)
			(end -0.12065 -0.2794)
			(stroke
				(width 0.1)
				(type default)
			)
			(layer "F.Fab")
		)
		(fp_line
			(start -0.67945 0.3048)
			(end -0.67945 -0.305054)
			(stroke
				(width 0.1)
				(type default)
			)
			(layer "F.Fab")
		)
		(fp_line
			(start -0.67945 -0.305054)
			(end -0.12065 -0.305054)
			(stroke
				(width 0.1)
				(type default)
			)
			(layer "F.Fab")
		)
		(pad "1" smd circle
			(at -0.40005 0 180)
			(size 0 0)
			(layers "F.Cu" "F.Mask" "F.Paste")
			(net "PWRGD_P52V_HS1_PG")
		)
		(pad "2" smd circle
			(at 0.40005 0 180)
			(size 0 0)
			(layers "F.Cu" "F.Mask" "F.Paste")
			(net "GND_FIELD_SIGNAL")
		)
	)
	(footprint ""
		(layer "F.Cu")
		(at 280.39568 -114.412268)
		(property "Reference" "PQ2"
			(at -7.723886 -5.895848 0)
			(unlocked yes)
			(layer "F.SilkS")
			(effects
				(font
					(size 0.7874 0.5842)
					(thickness 0.1524)
				)
				(justify left)
			)
		)
		(property "Value" ""
			(at 0 0 0)
			(layer "F.Fab")
			(effects
				(font
					(size 1.27 1.27)
				)
			)
		)
		(duplicate_pad_numbers_are_jumpers no)
		(fp_line
			(start -7.649972 -4.99999)
			(end -7.649972 -3.3274)
			(stroke
				(width 0.1524)
				(type default)
			)
			(layer "F.SilkS")
		)
		(fp_line
			(start -7.649972 -1.7526)
			(end -7.649972 1.7526)
			(stroke
				(width 0.1524)
				(type default)
			)
			(layer "F.SilkS")
		)
		(fp_line
			(start -7.649972 3.3274)
			(end -7.649972 4.99999)
			(stroke
				(width 0.1524)
				(type default)
			)
			(layer "F.SilkS")
		)
		(fp_line
			(start -7.649972 4.99999)
			(end 5.115814 4.99999)
			(stroke
				(width 0.1524)
				(type default)
			)
			(layer "F.SilkS")
		)
		(fp_line
			(start 5.115814 -4.99999)
			(end -7.649972 -4.99999)
			(stroke
				(width 0.1524)
				(type default)
			)
			(layer "F.SilkS")
		)
		(fp_line
			(start 7.630414 4.99999)
			(end 7.649972 4.99999)
			(stroke
				(width 0.1524)
				(type default)
			)
			(layer "F.SilkS")
		)
		(fp_line
			(start 7.649972 -4.99999)
			(end 7.630414 -4.99999)
			(stroke
				(width 0.1524)
				(type default)
			)
			(layer "F.SilkS")
		)
		(fp_line
			(start 7.649972 4.99999)
			(end 7.649972 -4.99999)
			(stroke
				(width 0.1524)
				(type default)
			)
			(layer "F.SilkS")
		)
		(fp_line
			(start -7.649972 -4.99999)
			(end -7.649972 4.99999)
			(stroke
				(width 0.1)
				(type default)
			)
			(layer "F.Fab")
		)
		(fp_line
			(start -7.649972 4.99999)
			(end 7.649972 4.99999)
			(stroke
				(width 0.1)
				(type default)
			)
			(layer "F.Fab")
		)
		(fp_line
			(start 7.649972 -4.99999)
			(end -7.649972 -4.99999)
			(stroke
				(width 0.1)
				(type default)
			)
			(layer "F.Fab")
		)
		(fp_line
			(start 7.649972 4.99999)
			(end 7.649972 -4.99999)
			(stroke
				(width 0.1)
				(type default)
			)
			(layer "F.Fab")
		)
		(pad "D" smd circle
			(at 2.15011 0)
			(size 0 0)
			(layers "F.Cu" "F.Mask" "F.Paste")
			(net "P52V_HS1_DRAIN_1")
		)
		(pad "G" smd rect
			(at -7.050024 -2.54 270)
			(size 1.3208 3.0988)
			(layers "F.Cu" "F.Mask" "F.Paste")
			(net "P52V_HS1_GATE2")
		)
		(pad "S" smd rect
			(at -7.050024 2.54 270)
			(size 1.3208 3.0988)
			(layers "F.Cu" "F.Mask" "F.Paste")
			(net "P52V_HS")
		)
		(zone
			(layer "F.Cu")
			(hatch none 0.5)
			(connect_pads
				(clearance 0)
			)
			(min_thickness 0.25)
			(keepout
				(tracks not_allowed)
				(vias allowed)
				(pads allowed)
				(copperpour not_allowed)
				(footprints allowed)
			)
			(placement
				(enabled no)
				(sheetname "")
			)
			(fill
				(thermal_gap 0.5)
				(thermal_bridge_width 0.5)
				(island_removal_mode 0)
			)
			(polygon
				(pts
					(xy 285.57728 -119.390668) (xy 272.75028 -119.390668) (xy 272.75028 -117.663468) (xy 274.96008 -117.663468)
					(xy 274.96008 -116.241068) (xy 272.75028 -116.241068) (xy 272.75028 -112.583468) (xy 274.96008 -112.583468)
					(xy 274.96008 -111.161068) (xy 272.75028 -111.161068) (xy 272.75028 -109.433868) (xy 285.57728 -109.433868)
					(xy 285.57728 -110.602268) (xy 279.37968 -110.602268) (xy 279.37968 -118.222268) (xy 285.57728 -118.222268)
				)
			)
		)
	)
	(footprint ""
		(layer "F.Cu")
		(at 281.960574 -58.862214)
		(property "Reference" "PR6966"
			(at 0 0 0)
			(layer "F.SilkS")
			(hide yes)
			(effects
				(font
					(size 1.27 1.27)
				)
			)
		)
		(property "Value" ""
			(at 0 0 0)
			(layer "F.Fab")
			(effects
				(font
					(size 1.27 1.27)
				)
			)
		)
		(duplicate_pad_numbers_are_jumpers no)
		(fp_line
			(start -0.7874 -0.4064)
			(end 0.7874 -0.4064)
			(stroke
				(width 0.1524)
				(type default)
			)
			(layer "F.SilkS")
		)
		(fp_line
			(start -0.7874 0.4064)
			(end -0.7874 -0.4064)
			(stroke
				(width 0.1524)
				(type default)
			)
			(layer "F.SilkS")
		)
		(fp_line
			(start 0.7874 -0.4064)
			(end 0.7874 0.4064)
			(stroke
				(width 0.1524)
				(type default)
			)
			(layer "F.SilkS")
		)
		(fp_line
			(start 0.7874 0.4064)
			(end -0.7874 0.4064)
			(stroke
				(width 0.1524)
				(type default)
			)
			(layer "F.SilkS")
		)
		(fp_line
			(start -0.67945 -0.305054)
			(end -0.12065 -0.305054)
			(stroke
				(width 0.1)
				(type default)
			)
			(layer "F.Fab")
		)
		(fp_line
			(start -0.67945 0.3048)
			(end -0.67945 -0.305054)
			(stroke
				(width 0.1)
				(type default)
			)
			(layer "F.Fab")
		)
		(fp_line
			(start -0.12065 -0.305054)
			(end -0.12065 -0.2794)
			(stroke
				(width 0.1)
				(type default)
			)
			(layer "F.Fab")
		)
		(fp_line
			(start -0.12065 -0.2794)
			(end 0.12065 -0.2794)
			(stroke
				(width 0.1)
				(type default)
			)
			(layer "F.Fab")
		)
		(fp_line
			(start -0.12065 0.2794)
			(end -0.12065 0.3048)
			(stroke
				(width 0.1)
				(type default)
			)
			(layer "F.Fab")
		)
		(fp_line
			(start -0.12065 0.3048)
			(end -0.67945 0.3048)
			(stroke
				(width 0.1)
				(type default)
			)
			(layer "F.Fab")
		)
		(fp_line
			(start 0.120396 0.2794)
			(end -0.12065 0.2794)
			(stroke
				(width 0.1)
				(type default)
			)
			(layer "F.Fab")
		)
		(fp_line
			(start 0.120396 0.3048)
			(end 0.120396 0.2794)
			(stroke
				(width 0.1)
				(type default)
			)
			(layer "F.Fab")
		)
		(fp_line
			(start 0.12065 -0.3048)
			(end 0.67945 -0.3048)
			(stroke
				(width 0.1)
				(type default)
			)
			(layer "F.Fab")
		)
		(fp_line
			(start 0.12065 -0.2794)
			(end 0.12065 -0.3048)
			(stroke
				(width 0.1)
				(type default)
			)
			(layer "F.Fab")
		)
		(fp_line
			(start 0.67945 -0.3048)
			(end 0.67945 0.3048)
			(stroke
				(width 0.1)
				(type default)
			)
			(layer "F.Fab")
		)
		(fp_line
			(start 0.67945 0.3048)
			(end 0.120396 0.3048)
			(stroke
				(width 0.1)
				(type default)
			)
			(layer "F.Fab")
		)
		(pad "1" smd rect
			(at -0.40005 0 180)
			(size 0.4572 0.508)
			(layers "F.Cu" "F.Mask" "F.Paste")
			(net "P52V_HS1_TEMP")
		)
		(pad "2" smd rect
			(at 0.40005 0 180)
			(size 0.4572 0.508)
			(layers "F.Cu" "F.Mask" "F.Paste")
			(net "P52V_HS1_TEMP_R")
		)
	)
	(footprint ""
		(layer "F.Cu")
		(at 44.713906 -130.175)
		(property "Reference" "PC75"
			(at 0 0 0)
			(layer "F.SilkS")
			(hide yes)
			(effects
				(font
					(size 1.27 1.27)
				)
			)
		)
		(property "Value" ""
			(at 0 0 0)
			(layer "F.Fab")
			(effects
				(font
					(size 1.27 1.27)
				)
			)
		)
		(duplicate_pad_numbers_are_jumpers no)
		(fp_line
			(start -2.2098 -0.9398)
			(end 2.2098 -0.9398)
			(stroke
				(width 0.1524)
				(type default)
			)
			(layer "F.SilkS")
		)
		(fp_line
			(start -2.2098 0.9398)
			(end -2.2098 -0.9398)
			(stroke
				(width 0.1524)
				(type default)
			)
			(layer "F.SilkS")
		)
		(fp_line
			(start 2.2098 -0.9398)
			(end 2.2098 0.9398)
			(stroke
				(width 0.1524)
				(type default)
			)
			(layer "F.SilkS")
		)
		(fp_line
			(start 2.2098 0.9398)
			(end -2.2098 0.9398)
			(stroke
				(width 0.1524)
				(type default)
			)
			(layer "F.SilkS")
		)
		(fp_line
			(start -1.700022 -0.899922)
			(end 1.700022 -0.899922)
			(stroke
				(width 0.1)
				(type default)
			)
			(layer "F.Fab")
		)
		(fp_line
			(start -1.700022 0.899922)
			(end -1.700022 -0.899922)
			(stroke
				(width 0.1)
				(type default)
			)
			(layer "F.Fab")
		)
		(fp_line
			(start 1.700022 -0.899922)
			(end 1.700022 0.899922)
			(stroke
				(width 0.1)
				(type default)
			)
			(layer "F.Fab")
		)
		(fp_line
			(start 1.700022 0.899922)
			(end -1.700022 0.899922)
			(stroke
				(width 0.1)
				(type default)
			)
			(layer "F.Fab")
		)
		(pad "1" smd rect
			(at -1.4732 0 180)
			(size 1.1684 1.5748)
			(layers "F.Cu" "F.Mask" "F.Paste")
			(net "P52V_HS_FILTER")
		)
		(pad "2" smd rect
			(at 1.4732 0 180)
			(size 1.1684 1.5748)
			(layers "F.Cu" "F.Mask" "F.Paste")
			(net "GND")
		)
	)
	(footprint ""
		(layer "F.Cu")
		(at 311.410096 -44.304966)
		(property "Reference" "H25"
			(at -1.9812 -4.079748 0)
			(unlocked yes)
			(layer "B.SilkS")
			(effects
				(font
					(size 0.7874 0.5842)
					(thickness 0.1524)
				)
				(justify left mirror)
			)
		)
		(property "Value" ""
			(at 0 0 0)
			(layer "F.Fab")
			(effects
				(font
					(size 1.27 1.27)
				)
			)
		)
		(duplicate_pad_numbers_are_jumpers no)
		(pad "1" thru_hole circle
			(at 0 0)
			(size 8.001 8.001)
			(drill 4.2418)
			(layers "*.Cu" "*.Mask")
			(remove_unused_layers no)
			(net "H25_TP")
			(clearance -1.6256)
			(padstack
				(mode front_inner_back)
				(layer "Inner"
					(shape circle)
					(size 6.0198 6.0198)
					(clearance -0.635)
				)
				(layer "B.Cu"
					(shape circle)
					(size 8.001 8.001)
					(clearance -1.6256)
				)
			)
		)
		(zone
			(layers "F.Cu" "B.Cu" "In1.Cu" "In2.Cu" "In3.Cu" "In4.Cu" "In5.Cu" "In6.Cu"
				"In7.Cu" "In8.Cu"
			)
			(hatch none 0.5)
			(connect_pads
				(clearance 0)
			)
			(min_thickness 0.25)
			(keepout
				(tracks not_allowed)
				(vias allowed)
				(pads allowed)
				(copperpour not_allowed)
				(footprints allowed)
			)
			(placement
				(enabled no)
				(sheetname "")
			)
			(fill
				(thermal_gap 0.5)
				(thermal_bridge_width 0.5)
				(island_removal_mode 0)
			)
			(polygon
				(pts
					(arc
						(start 314.920122 -44.304966)
						(mid 307.90007 -44.304966)
						(end 314.920122 -44.304966)
					)
				)
			)
		)
	)
	(footprint ""
		(layer "F.Cu")
		(at 280.924 -49.276 90)
		(property "Reference" "PC9"
			(at 0 0 90)
			(layer "F.SilkS")
			(hide yes)
			(effects
				(font
					(size 1.27 1.27)
				)
			)
		)
		(property "Value" ""
			(at 0 0 90)
			(layer "F.Fab")
			(effects
				(font
					(size 1.27 1.27)
				)
			)
		)
		(duplicate_pad_numbers_are_jumpers no)
		(fp_line
			(start 0.7874 -0.4064)
			(end 0.7874 0.4064)
			(stroke
				(width 0.1524)
				(type default)
			)
			(layer "F.SilkS")
		)
		(fp_line
			(start -0.7874 -0.4064)
			(end 0.7874 -0.4064)
			(stroke
				(width 0.1524)
				(type default)
			)
			(layer "F.SilkS")
		)
		(fp_line
			(start 0.7874 0.4064)
			(end -0.7874 0.4064)
			(stroke
				(width 0.1524)
				(type default)
			)
			(layer "F.SilkS")
		)
		(fp_line
			(start -0.7874 0.4064)
			(end -0.7874 -0.4064)
			(stroke
				(width 0.1524)
				(type default)
			)
			(layer "F.SilkS")
		)
		(fp_line
			(start -0.12065 -0.305054)
			(end -0.12065 -0.2794)
			(stroke
				(width 0.1)
				(type default)
			)
			(layer "F.Fab")
		)
		(fp_line
			(start -0.67945 -0.305054)
			(end -0.12065 -0.305054)
			(stroke
				(width 0.1)
				(type default)
			)
			(layer "F.Fab")
		)
		(fp_line
			(start 0.67945 -0.3048)
			(end 0.67945 0.3048)
			(stroke
				(width 0.1)
				(type default)
			)
			(layer "F.Fab")
		)
		(fp_line
			(start 0.12065 -0.3048)
			(end 0.67945 -0.3048)
			(stroke
				(width 0.1)
				(type default)
			)
			(layer "F.Fab")
		)
		(fp_line
			(start 0.12065 -0.2794)
			(end 0.12065 -0.3048)
			(stroke
				(width 0.1)
				(type default)
			)
			(layer "F.Fab")
		)
		(fp_line
			(start -0.12065 -0.2794)
			(end 0.12065 -0.2794)
			(stroke
				(width 0.1)
				(type default)
			)
			(layer "F.Fab")
		)
		(fp_line
			(start 0.120396 0.2794)
			(end -0.12065 0.2794)
			(stroke
				(width 0.1)
				(type default)
			)
			(layer "F.Fab")
		)
		(fp_line
			(start -0.12065 0.2794)
			(end -0.12065 0.3048)
			(stroke
				(width 0.1)
				(type default)
			)
			(layer "F.Fab")
		)
		(fp_line
			(start 0.67945 0.3048)
			(end 0.120396 0.3048)
			(stroke
				(width 0.1)
				(type default)
			)
			(layer "F.Fab")
		)
		(fp_line
			(start 0.120396 0.3048)
			(end 0.120396 0.2794)
			(stroke
				(width 0.1)
				(type default)
			)
			(layer "F.Fab")
		)
		(fp_line
			(start -0.12065 0.3048)
			(end -0.67945 0.3048)
			(stroke
				(width 0.1)
				(type default)
			)
			(layer "F.Fab")
		)
		(fp_line
			(start -0.67945 0.3048)
			(end -0.67945 -0.305054)
			(stroke
				(width 0.1)
				(type default)
			)
			(layer "F.Fab")
		)
		(pad "1" smd circle
			(at -0.40005 0 90)
			(size 0 0)
			(layers "F.Cu" "F.Mask" "F.Paste")
			(net "P52V_HS1_RND")
		)
		(pad "2" smd circle
			(at 0.40005 0 90)
			(size 0 0)
			(layers "F.Cu" "F.Mask" "F.Paste")
			(net "GND_FIELD_SIGNAL")
		)
	)
	(footprint ""
		(layer "F.Cu")
		(at 60.452 -62.865)
		(property "Reference" "PC84"
			(at 0 0 0)
			(layer "F.SilkS")
			(hide yes)
			(effects
				(font
					(size 1.27 1.27)
				)
			)
		)
		(property "Value" ""
			(at 0 0 0)
			(layer "F.Fab")
			(effects
				(font
					(size 1.27 1.27)
				)
			)
		)
		(duplicate_pad_numbers_are_jumpers no)
		(fp_line
			(start -0.7874 -0.4064)
			(end 0.7874 -0.4064)
			(stroke
				(width 0.1524)
				(type default)
			)
			(layer "F.SilkS")
		)
		(fp_line
			(start -0.7874 0.4064)
			(end -0.7874 -0.4064)
			(stroke
				(width 0.1524)
				(type default)
			)
			(layer "F.SilkS")
		)
		(fp_line
			(start 0.7874 -0.4064)
			(end 0.7874 0.4064)
			(stroke
				(width 0.1524)
				(type default)
			)
			(layer "F.SilkS")
		)
		(fp_line
			(start 0.7874 0.4064)
			(end -0.7874 0.4064)
			(stroke
				(width 0.1524)
				(type default)
			)
			(layer "F.SilkS")
		)
		(fp_line
			(start -0.6858 -0.3048)
			(end -0.1016 -0.3048)
			(stroke
				(width 0.1)
				(type default)
			)
			(layer "F.Fab")
		)
		(fp_line
			(start -0.6858 0.3048)
			(end -0.6858 -0.3048)
			(stroke
				(width 0.1)
				(type default)
			)
			(layer "F.Fab")
		)
		(fp_line
			(start -0.1016 -0.3048)
			(end -0.1016 -0.2794)
			(stroke
				(width 0.1)
				(type default)
			)
			(layer "F.Fab")
		)
		(fp_line
			(start -0.1016 -0.2794)
			(end 0.1016 -0.2794)
			(stroke
				(width 0.1)
				(type default)
			)
			(layer "F.Fab")
		)
		(fp_line
			(start -0.1016 0.2794)
			(end -0.1016 0.3048)
			(stroke
				(width 0.1)
				(type default)
			)
			(layer "F.Fab")
		)
		(fp_line
			(start -0.1016 0.3048)
			(end -0.6858 0.3048)
			(stroke
				(width 0.1)
				(type default)
			)
			(layer "F.Fab")
		)
		(fp_line
			(start 0.1016 -0.3048)
			(end 0.6858 -0.3048)
			(stroke
				(width 0.1)
				(type default)
			)
			(layer "F.Fab")
		)
		(fp_line
			(start 0.1016 -0.2794)
			(end 0.1016 -0.3048)
			(stroke
				(width 0.1)
				(type default)
			)
			(layer "F.Fab")
		)
		(fp_line
			(start 0.1016 0.2794)
			(end -0.1016 0.2794)
			(stroke
				(width 0.1)
				(type default)
			)
			(layer "F.Fab")
		)
		(fp_line
			(start 0.1016 0.3048)
			(end 0.1016 0.2794)
			(stroke
				(width 0.1)
				(type default)
			)
			(layer "F.Fab")
		)
		(fp_line
			(start 0.6858 -0.3048)
			(end 0.6858 0.3048)
			(stroke
				(width 0.1)
				(type default)
			)
			(layer "F.Fab")
		)
		(fp_line
			(start 0.6858 0.3048)
			(end 0.1016 0.3048)
			(stroke
				(width 0.1)
				(type default)
			)
			(layer "F.Fab")
		)
		(pad "1" smd rect
			(at -0.40005 0 180)
			(size 0.4572 0.508)
			(layers "F.Cu" "F.Mask" "F.Paste")
			(net "P12V_BRICK")
		)
		(pad "2" smd rect
			(at 0.40005 0 180)
			(size 0.4572 0.508)
			(layers "F.Cu" "F.Mask" "F.Paste")
			(net "GND")
		)
	)
	(footprint ""
		(layer "F.Cu")
		(at 169.291 -60.96)
		(property "Reference" "PC41"
			(at -1.27 -3.52933 0)
			(unlocked yes)
			(layer "F.SilkS")
			(effects
				(font
					(size 0.7874 0.5842)
					(thickness 0.1524)
				)
				(justify left)
			)
		)
		(property "Value" ""
			(at 0 0 0)
			(layer "F.Fab")
			(effects
				(font
					(size 1.27 1.27)
				)
			)
		)
		(duplicate_pad_numbers_are_jumpers no)
		(fp_line
			(start 5.2578 2.499868)
			(end -5.2578 2.499868)
			(stroke
				(width 0.1524)
				(type default)
			)
			(layer "F.SilkS")
		)
		(fp_circle
			(center 0 2.499868)
			(end 5.2578 2.499868)
			(stroke
				(width 0.1524)
				(type default)
			)
			(fill no)
			(layer "F.SilkS")
		)
		(fp_poly
			(pts
				(arc
					(start 5.2578 2.499868)
					(mid 0 7.757922)
					(end -5.2578 2.499868)
				)
			)
			(stroke
				(width 0)
				(type default)
			)
			(fill yes)
			(layer "F.SilkS")
		)
		(fp_circle
			(center 0 2.499868)
			(end 5.2578 2.499868)
			(stroke
				(width 0.1)
				(type default)
			)
			(fill no)
			(layer "F.Fab")
		)
		(pad "1" thru_hole rect
			(at 0 0 270)
			(size 1.524 1.524)
			(drill 1.016)
			(layers "*.Cu" "*.Mask")
			(remove_unused_layers no)
			(net "P12V_BRICK")
			(clearance 0)
			(padstack
				(mode front_inner_back)
				(layer "Inner"
					(shape circle)
					(size 1.524 1.524)
					(clearance 0)
				)
				(layer "B.Cu"
					(shape rect)
					(size 1.524 1.524)
					(clearance 0)
				)
			)
		)
		(pad "2" thru_hole circle
			(at 0 4.99999 270)
			(size 1.524 1.524)
			(drill 1.016)
			(layers "*.Cu" "*.Mask")
			(remove_unused_layers no)
			(net "GND")
			(clearance 0)
		)
	)
	(footprint ""
		(layer "F.Cu")
		(at 32.004 -65.659 180)
		(property "Reference" "D5"
			(at 4.1656 2.25933 0)
			(unlocked yes)
			(layer "F.SilkS")
			(effects
				(font
					(size 0.7874 0.5842)
					(thickness 0.1524)
				)
				(justify left)
			)
		)
		(property "Value" ""
			(at 0 0 180)
			(layer "F.Fab")
			(effects
				(font
					(size 1.27 1.27)
				)
			)
		)
		(duplicate_pad_numbers_are_jumpers no)
		(fp_line
			(start 4.107942 1.459992)
			(end -3.400044 1.459992)
			(stroke
				(width 0.1524)
				(type default)
			)
			(layer "F.SilkS")
		)
		(fp_line
			(start 4.107942 -1.459992)
			(end 4.107942 1.459992)
			(stroke
				(width 0.1524)
				(type default)
			)
			(layer "F.SilkS")
		)
		(fp_line
			(start -3.400044 1.459992)
			(end -3.400044 -1.459992)
			(stroke
				(width 0.1524)
				(type default)
			)
			(layer "F.SilkS")
		)
		(fp_line
			(start -3.400044 -1.459992)
			(end 4.107942 -1.459992)
			(stroke
				(width 0.1524)
				(type default)
			)
			(layer "F.SilkS")
		)
		(fp_poly
			(pts
				(xy 4.107942 -1.459992) (xy 4.107942 1.459992) (xy 3.308096 1.459992) (xy 3.308096 -1.459992)
			)
			(stroke
				(width 0)
				(type default)
			)
			(fill yes)
			(layer "F.SilkS")
		)
		(fp_line
			(start 2.29997 1.459992)
			(end -2.29997 1.459992)
			(stroke
				(width 0.1)
				(type default)
			)
			(layer "F.Fab")
		)
		(fp_line
			(start 2.29997 -1.459992)
			(end 2.29997 1.459992)
			(stroke
				(width 0.1)
				(type default)
			)
			(layer "F.Fab")
		)
		(fp_line
			(start -2.29997 1.459992)
			(end -2.29997 -1.459992)
			(stroke
				(width 0.1)
				(type default)
			)
			(layer "F.Fab")
		)
		(fp_line
			(start -2.29997 -1.459992)
			(end 2.29997 -1.459992)
			(stroke
				(width 0.1)
				(type default)
			)
			(layer "F.Fab")
		)
		(fp_text user "-"
			(at 6.1976 0.09525 0)
			(unlocked yes)
			(layer "F.SilkS")
			(effects
				(font
					(size 1.905 1.4224)
					(thickness 0.1524)
				)
				(justify left)
			)
		)
		(fp_text user "+"
			(at -4.8514 0.92075 180)
			(unlocked yes)
			(layer "F.SilkS")
			(effects
				(font
					(size 1.905 1.4224)
					(thickness 0.1524)
				)
				(justify left)
			)
		)
		(fp_text user "-"
			(at 5.4102 0.29845 0)
			(unlocked yes)
			(layer "F.Fab")
			(effects
				(font
					(size 1.905 1.4224)
					(thickness 0.1524)
				)
				(justify left)
			)
		)
		(fp_text user "+"
			(at -4.7752 -0.12065 180)
			(unlocked yes)
			(layer "F.Fab")
			(effects
				(font
					(size 1.905 1.4224)
					(thickness 0.1524)
				)
				(justify left)
			)
		)
		(pad "A" smd rect
			(at -1.999996 0 270)
			(size 1.7018 2.5146)
			(layers "F.Cu" "F.Mask" "F.Paste")
			(net "GND")
		)
		(pad "C" smd rect
			(at 1.999996 0 270)
			(size 1.7018 2.5146)
			(layers "F.Cu" "F.Mask" "F.Paste")
			(net "P12V_HPDB")
		)
	)
	(footprint ""
		(layer "F.Cu")
		(at 129.999994 -11.999976 -90)
		(property "Reference" "H4"
			(at -6.261354 11.508994 0)
			(unlocked yes)
			(layer "F.SilkS")
			(effects
				(font
					(size 0.7874 0.5842)
					(thickness 0.1524)
				)
				(justify left)
			)
		)
		(property "Value" ""
			(at 0 0 270)
			(layer "F.Fab")
			(effects
				(font
					(size 1.27 1.27)
				)
			)
		)
		(duplicate_pad_numbers_are_jumpers no)
		(pad "1" thru_hole oval
			(at 0 0 270)
			(size 10.0076 32.004)
			(drill 3.0226
				(offset 0 10.999978)
			)
			(layers "*.Cu" "*.Mask")
			(remove_unused_layers no)
			(net "GND")
			(clearance -1.995678)
			(padstack
				(mode front_inner_back)
				(layer "Inner"
					(shape circle)
					(size 0 0)
					(clearance 0)
				)
				(layer "B.Cu"
					(shape oval)
					(size 10.0076 32.004)
					(offset 0 10.999978)
					(clearance -1.995678)
				)
			)
		)
	)
	(footprint ""
		(layer "F.Cu")
		(at 48.768 -17.78)
		(property "Reference" "ME3"
			(at 0 0 0)
			(layer "F.SilkS")
			(hide yes)
			(effects
				(font
					(size 1.27 1.27)
				)
			)
		)
		(property "Value" ""
			(at 0 0 0)
			(layer "F.Fab")
			(effects
				(font
					(size 1.27 1.27)
				)
			)
		)
		(duplicate_pad_numbers_are_jumpers no)
		(fp_line
			(start 0.089408 -2.660396)
			(end 1.561846 -4.072636)
			(stroke
				(width 0.1)
				(type default)
			)
			(layer "F.SilkS")
		)
		(fp_line
			(start 0.089408 -2.660396)
			(end 1.561846 -4.072636)
			(stroke
				(width 0.1)
				(type default)
			)
			(layer "F.SilkS")
		)
		(fp_line
			(start 0.098806 -2.611628)
			(end 1.482344 -3.938778)
			(stroke
				(width 0.1)
				(type default)
			)
			(layer "F.SilkS")
		)
		(fp_line
			(start 0.098806 -2.611628)
			(end 1.482344 -3.938778)
			(stroke
				(width 0.1)
				(type default)
			)
			(layer "F.SilkS")
		)
		(fp_line
			(start 0.108204 -2.563114)
			(end 1.4224 -3.823716)
			(stroke
				(width 0.1)
				(type default)
			)
			(layer "F.SilkS")
		)
		(fp_line
			(start 0.108204 -2.563114)
			(end 1.4224 -3.823716)
			(stroke
				(width 0.1)
				(type default)
			)
			(layer "F.SilkS")
		)
		(fp_line
			(start 0.117602 -2.514346)
			(end 1.38557 -3.730498)
			(stroke
				(width 0.1)
				(type default)
			)
			(layer "F.SilkS")
		)
		(fp_line
			(start 0.117602 -2.514346)
			(end 1.38557 -3.730498)
			(stroke
				(width 0.1)
				(type default)
			)
			(layer "F.SilkS")
		)
		(fp_line
			(start 0.127254 -2.465832)
			(end 1.360932 -3.649218)
			(stroke
				(width 0.1)
				(type default)
			)
			(layer "F.SilkS")
		)
		(fp_line
			(start 0.127254 -2.465832)
			(end 1.360932 -3.649218)
			(stroke
				(width 0.1)
				(type default)
			)
			(layer "F.SilkS")
		)
		(fp_line
			(start 0.139954 -2.420366)
			(end 1.336548 -3.568192)
			(stroke
				(width 0.1)
				(type default)
			)
			(layer "F.SilkS")
		)
		(fp_line
			(start 0.139954 -2.420366)
			(end 1.336548 -3.568192)
			(stroke
				(width 0.1)
				(type default)
			)
			(layer "F.SilkS")
		)
		(fp_line
			(start 0.152908 -2.3749)
			(end 1.31445 -3.489198)
			(stroke
				(width 0.1)
				(type default)
			)
			(layer "F.SilkS")
		)
		(fp_line
			(start 0.152908 -2.3749)
			(end 1.31445 -3.489198)
			(stroke
				(width 0.1)
				(type default)
			)
			(layer "F.SilkS")
		)
		(fp_line
			(start 0.165608 -2.329434)
			(end 1.307592 -3.424936)
			(stroke
				(width 0.1)
				(type default)
			)
			(layer "F.SilkS")
		)
		(fp_line
			(start 0.165608 -2.329434)
			(end 1.307592 -3.424936)
			(stroke
				(width 0.1)
				(type default)
			)
			(layer "F.SilkS")
		)
		(fp_line
			(start 0.178562 -2.284222)
			(end 1.300988 -3.360674)
			(stroke
				(width 0.1)
				(type default)
			)
			(layer "F.SilkS")
		)
		(fp_line
			(start 0.178562 -2.284222)
			(end 1.300988 -3.360674)
			(stroke
				(width 0.1)
				(type default)
			)
			(layer "F.SilkS")
		)
		(fp_line
			(start 0.191516 -2.238756)
			(end 1.29413 -3.296412)
			(stroke
				(width 0.1)
				(type default)
			)
			(layer "F.SilkS")
		)
		(fp_line
			(start 0.191516 -2.238756)
			(end 1.29413 -3.296412)
			(stroke
				(width 0.1)
				(type default)
			)
			(layer "F.SilkS")
		)
		(fp_line
			(start 0.205994 -2.195068)
			(end 1.287526 -3.232404)
			(stroke
				(width 0.1)
				(type default)
			)
			(layer "F.SilkS")
		)
		(fp_line
			(start 0.205994 -2.195068)
			(end 1.287526 -3.232404)
			(stroke
				(width 0.1)
				(type default)
			)
			(layer "F.SilkS")
		)
		(fp_line
			(start 0.222504 -2.153158)
			(end 1.2827 -3.170174)
			(stroke
				(width 0.1)
				(type default)
			)
			(layer "F.SilkS")
		)
		(fp_line
			(start 0.222504 -2.153158)
			(end 1.2827 -3.170174)
			(stroke
				(width 0.1)
				(type default)
			)
			(layer "F.SilkS")
		)
		(fp_line
			(start 0.239268 -2.111502)
			(end 1.287018 -3.11658)
			(stroke
				(width 0.1)
				(type default)
			)
			(layer "F.SilkS")
		)
		(fp_line
			(start 0.239268 -2.111502)
			(end 1.287018 -3.11658)
			(stroke
				(width 0.1)
				(type default)
			)
			(layer "F.SilkS")
		)
		(fp_line
			(start 0.256032 -2.069846)
			(end 1.291082 -3.062732)
			(stroke
				(width 0.1)
				(type default)
			)
			(layer "F.SilkS")
		)
		(fp_line
			(start 0.256032 -2.069846)
			(end 1.291082 -3.062732)
			(stroke
				(width 0.1)
				(type default)
			)
			(layer "F.SilkS")
		)
		(fp_line
			(start 0.272796 -2.02819)
			(end 1.295146 -3.009138)
			(stroke
				(width 0.1)
				(type default)
			)
			(layer "F.SilkS")
		)
		(fp_line
			(start 0.272796 -2.02819)
			(end 1.295146 -3.009138)
			(stroke
				(width 0.1)
				(type default)
			)
			(layer "F.SilkS")
		)
		(fp_line
			(start 0.289306 -1.986534)
			(end 1.299464 -2.955544)
			(stroke
				(width 0.1)
				(type default)
			)
			(layer "F.SilkS")
		)
		(fp_line
			(start 0.289306 -1.986534)
			(end 1.299464 -2.955544)
			(stroke
				(width 0.1)
				(type default)
			)
			(layer "F.SilkS")
		)
		(fp_line
			(start 0.307086 -1.94564)
			(end 1.303528 -2.901696)
			(stroke
				(width 0.1)
				(type default)
			)
			(layer "F.SilkS")
		)
		(fp_line
			(start 0.307086 -1.94564)
			(end 1.303528 -2.901696)
			(stroke
				(width 0.1)
				(type default)
			)
			(layer "F.SilkS")
		)
		(fp_line
			(start 0.327914 -1.908048)
			(end 1.31318 -2.853182)
			(stroke
				(width 0.1)
				(type default)
			)
			(layer "F.SilkS")
		)
		(fp_line
			(start 0.327914 -1.908048)
			(end 1.31318 -2.853182)
			(stroke
				(width 0.1)
				(type default)
			)
			(layer "F.SilkS")
		)
		(fp_line
			(start 0.348996 -1.870456)
			(end 1.325118 -2.8067)
			(stroke
				(width 0.1)
				(type default)
			)
			(layer "F.SilkS")
		)
		(fp_line
			(start 0.348996 -1.870456)
			(end 1.325118 -2.8067)
			(stroke
				(width 0.1)
				(type default)
			)
			(layer "F.SilkS")
		)
		(fp_line
			(start 0.369824 -1.832864)
			(end 1.336802 -2.760472)
			(stroke
				(width 0.1)
				(type default)
			)
			(layer "F.SilkS")
		)
		(fp_line
			(start 0.369824 -1.832864)
			(end 1.336802 -2.760472)
			(stroke
				(width 0.1)
				(type default)
			)
			(layer "F.SilkS")
		)
		(fp_line
			(start 0.390906 -1.795272)
			(end 1.348486 -2.714244)
			(stroke
				(width 0.1)
				(type default)
			)
			(layer "F.SilkS")
		)
		(fp_line
			(start 0.390906 -1.795272)
			(end 1.348486 -2.714244)
			(stroke
				(width 0.1)
				(type default)
			)
			(layer "F.SilkS")
		)
		(fp_line
			(start 0.411988 -1.75768)
			(end 1.360424 -2.667508)
			(stroke
				(width 0.1)
				(type default)
			)
			(layer "F.SilkS")
		)
		(fp_line
			(start 0.411988 -1.75768)
			(end 1.360424 -2.667508)
			(stroke
				(width 0.1)
				(type default)
			)
			(layer "F.SilkS")
		)
		(fp_line
			(start 0.432816 -1.720088)
			(end 1.372362 -2.62128)
			(stroke
				(width 0.1)
				(type default)
			)
			(layer "F.SilkS")
		)
		(fp_line
			(start 0.432816 -1.720088)
			(end 1.372362 -2.62128)
			(stroke
				(width 0.1)
				(type default)
			)
			(layer "F.SilkS")
		)
		(fp_line
			(start 0.456184 -1.684782)
			(end 1.387856 -2.578608)
			(stroke
				(width 0.1)
				(type default)
			)
			(layer "F.SilkS")
		)
		(fp_line
			(start 0.456184 -1.684782)
			(end 1.387856 -2.578608)
			(stroke
				(width 0.1)
				(type default)
			)
			(layer "F.SilkS")
		)
		(fp_line
			(start 0.481838 -1.651762)
			(end 1.40589 -2.538222)
			(stroke
				(width 0.1)
				(type default)
			)
			(layer "F.SilkS")
		)
		(fp_line
			(start 0.481838 -1.651762)
			(end 1.40589 -2.538222)
			(stroke
				(width 0.1)
				(type default)
			)
			(layer "F.SilkS")
		)
		(fp_line
			(start 0.507746 -1.618742)
			(end 1.423924 -2.497836)
			(stroke
				(width 0.1)
				(type default)
			)
			(layer "F.SilkS")
		)
		(fp_line
			(start 0.507746 -1.618742)
			(end 1.423924 -2.497836)
			(stroke
				(width 0.1)
				(type default)
			)
			(layer "F.SilkS")
		)
		(fp_line
			(start 0.5334 -1.585722)
			(end 1.441958 -2.457196)
			(stroke
				(width 0.1)
				(type default)
			)
			(layer "F.SilkS")
		)
		(fp_line
			(start 0.5334 -1.585722)
			(end 1.441958 -2.457196)
			(stroke
				(width 0.1)
				(type default)
			)
			(layer "F.SilkS")
		)
		(fp_line
			(start 0.559054 -1.552702)
			(end 1.459992 -2.41681)
			(stroke
				(width 0.1)
				(type default)
			)
			(layer "F.SilkS")
		)
		(fp_line
			(start 0.559054 -1.552702)
			(end 1.459992 -2.41681)
			(stroke
				(width 0.1)
				(type default)
			)
			(layer "F.SilkS")
		)
		(fp_line
			(start 0.584962 -1.519682)
			(end 1.477772 -2.376424)
			(stroke
				(width 0.1)
				(type default)
			)
			(layer "F.SilkS")
		)
		(fp_line
			(start 0.584962 -1.519682)
			(end 1.477772 -2.376424)
			(stroke
				(width 0.1)
				(type default)
			)
			(layer "F.SilkS")
		)
		(fp_line
			(start 0.610616 -1.486916)
			(end 1.496568 -2.336546)
			(stroke
				(width 0.1)
				(type default)
			)
			(layer "F.SilkS")
		)
		(fp_line
			(start 0.610616 -1.486916)
			(end 1.496568 -2.336546)
			(stroke
				(width 0.1)
				(type default)
			)
			(layer "F.SilkS")
		)
		(fp_line
			(start 0.637794 -1.455166)
			(end 1.52019 -2.301494)
			(stroke
				(width 0.1)
				(type default)
			)
			(layer "F.SilkS")
		)
		(fp_line
			(start 0.637794 -1.455166)
			(end 1.52019 -2.301494)
			(stroke
				(width 0.1)
				(type default)
			)
			(layer "F.SilkS")
		)
		(fp_line
			(start 0.668274 -1.426464)
			(end 1.543558 -2.266188)
			(stroke
				(width 0.1)
				(type default)
			)
			(layer "F.SilkS")
		)
		(fp_line
			(start 0.668274 -1.426464)
			(end 1.543558 -2.266188)
			(stroke
				(width 0.1)
				(type default)
			)
			(layer "F.SilkS")
		)
		(fp_line
			(start 0.6985 -1.397762)
			(end 1.56718 -2.231136)
			(stroke
				(width 0.1)
				(type default)
			)
			(layer "F.SilkS")
		)
		(fp_line
			(start 0.6985 -1.397762)
			(end 1.56718 -2.231136)
			(stroke
				(width 0.1)
				(type default)
			)
			(layer "F.SilkS")
		)
		(fp_line
			(start 0.728726 -1.36906)
			(end 1.590802 -2.196084)
			(stroke
				(width 0.1)
				(type default)
			)
			(layer "F.SilkS")
		)
		(fp_line
			(start 0.728726 -1.36906)
			(end 1.590802 -2.196084)
			(stroke
				(width 0.1)
				(type default)
			)
			(layer "F.SilkS")
		)
		(fp_line
			(start 0.758952 -1.340358)
			(end 1.61417 -2.160778)
			(stroke
				(width 0.1)
				(type default)
			)
			(layer "F.SilkS")
		)
		(fp_line
			(start 0.758952 -1.340358)
			(end 1.61417 -2.160778)
			(stroke
				(width 0.1)
				(type default)
			)
			(layer "F.SilkS")
		)
		(fp_line
			(start 0.789178 -1.31191)
			(end 1.637792 -2.125726)
			(stroke
				(width 0.1)
				(type default)
			)
			(layer "F.SilkS")
		)
		(fp_line
			(start 0.789178 -1.31191)
			(end 1.637792 -2.125726)
			(stroke
				(width 0.1)
				(type default)
			)
			(layer "F.SilkS")
		)
		(fp_line
			(start 0.819404 -1.282954)
			(end 1.663954 -2.09296)
			(stroke
				(width 0.1)
				(type default)
			)
			(layer "F.SilkS")
		)
		(fp_line
			(start 0.819404 -1.282954)
			(end 1.663954 -2.09296)
			(stroke
				(width 0.1)
				(type default)
			)
			(layer "F.SilkS")
		)
		(fp_line
			(start 0.851408 -1.25603)
			(end 1.69291 -2.063242)
			(stroke
				(width 0.1)
				(type default)
			)
			(layer "F.SilkS")
		)
		(fp_line
			(start 0.851408 -1.25603)
			(end 1.69291 -2.063242)
			(stroke
				(width 0.1)
				(type default)
			)
			(layer "F.SilkS")
		)
		(fp_line
			(start 0.885698 -1.230884)
			(end 1.72212 -2.03327)
			(stroke
				(width 0.1)
				(type default)
			)
			(layer "F.SilkS")
		)
		(fp_line
			(start 0.885698 -1.230884)
			(end 1.72212 -2.03327)
			(stroke
				(width 0.1)
				(type default)
			)
			(layer "F.SilkS")
		)
		(fp_line
			(start 0.919734 -1.206246)
			(end 1.751076 -2.003552)
			(stroke
				(width 0.1)
				(type default)
			)
			(layer "F.SilkS")
		)
		(fp_line
			(start 0.919734 -1.206246)
			(end 1.751076 -2.003552)
			(stroke
				(width 0.1)
				(type default)
			)
			(layer "F.SilkS")
		)
		(fp_line
			(start 0.954024 -1.1811)
			(end 1.780032 -1.973834)
			(stroke
				(width 0.1)
				(type default)
			)
			(layer "F.SilkS")
		)
		(fp_line
			(start 0.954024 -1.1811)
			(end 1.780032 -1.973834)
			(stroke
				(width 0.1)
				(type default)
			)
			(layer "F.SilkS")
		)
		(fp_line
			(start 0.988314 -1.156462)
			(end 1.809242 -1.943862)
			(stroke
				(width 0.1)
				(type default)
			)
			(layer "F.SilkS")
		)
		(fp_line
			(start 0.988314 -1.156462)
			(end 1.809242 -1.943862)
			(stroke
				(width 0.1)
				(type default)
			)
			(layer "F.SilkS")
		)
		(fp_line
			(start 1.02235 -1.13157)
			(end 1.838452 -1.914144)
			(stroke
				(width 0.1)
				(type default)
			)
			(layer "F.SilkS")
		)
		(fp_line
			(start 1.02235 -1.13157)
			(end 1.838452 -1.914144)
			(stroke
				(width 0.1)
				(type default)
			)
			(layer "F.SilkS")
		)
		(fp_line
			(start 1.05664 -1.106678)
			(end 1.872488 -1.889252)
			(stroke
				(width 0.1)
				(type default)
			)
			(layer "F.SilkS")
		)
		(fp_line
			(start 1.05664 -1.106678)
			(end 1.872488 -1.889252)
			(stroke
				(width 0.1)
				(type default)
			)
			(layer "F.SilkS")
		)
		(fp_line
			(start 1.09347 -1.084326)
			(end 1.907794 -1.865376)
			(stroke
				(width 0.1)
				(type default)
			)
			(layer "F.SilkS")
		)
		(fp_line
			(start 1.09347 -1.084326)
			(end 1.907794 -1.865376)
			(stroke
				(width 0.1)
				(type default)
			)
			(layer "F.SilkS")
		)
		(fp_line
			(start 1.131824 -1.063498)
			(end 1.9431 -1.8415)
			(stroke
				(width 0.1)
				(type default)
			)
			(layer "F.SilkS")
		)
		(fp_line
			(start 1.131824 -1.063498)
			(end 1.9431 -1.8415)
			(stroke
				(width 0.1)
				(type default)
			)
			(layer "F.SilkS")
		)
		(fp_line
			(start 1.133856 -5.220462)
			(end 0.47117 -4.5847)
			(stroke
				(width 0.1)
				(type default)
			)
			(layer "F.SilkS")
		)
		(fp_line
			(start 1.133856 -5.220462)
			(end 0.47117 -4.5847)
			(stroke
				(width 0.1)
				(type default)
			)
			(layer "F.SilkS")
		)
		(fp_line
			(start 1.170178 -1.042416)
			(end 1.978406 -1.817624)
			(stroke
				(width 0.1)
				(type default)
			)
			(layer "F.SilkS")
		)
		(fp_line
			(start 1.170178 -1.042416)
			(end 1.978406 -1.817624)
			(stroke
				(width 0.1)
				(type default)
			)
			(layer "F.SilkS")
		)
		(fp_line
			(start 1.208532 -1.021334)
			(end 2.013458 -1.793748)
			(stroke
				(width 0.1)
				(type default)
			)
			(layer "F.SilkS")
		)
		(fp_line
			(start 1.208532 -1.021334)
			(end 2.013458 -1.793748)
			(stroke
				(width 0.1)
				(type default)
			)
			(layer "F.SilkS")
		)
		(fp_line
			(start 1.246886 -1.000506)
			(end 2.048764 -1.769872)
			(stroke
				(width 0.1)
				(type default)
			)
			(layer "F.SilkS")
		)
		(fp_line
			(start 1.246886 -1.000506)
			(end 2.048764 -1.769872)
			(stroke
				(width 0.1)
				(type default)
			)
			(layer "F.SilkS")
		)
		(fp_line
			(start 1.28524 -0.979424)
			(end 2.087626 -1.749298)
			(stroke
				(width 0.1)
				(type default)
			)
			(layer "F.SilkS")
		)
		(fp_line
			(start 1.28524 -0.979424)
			(end 2.087626 -1.749298)
			(stroke
				(width 0.1)
				(type default)
			)
			(layer "F.SilkS")
		)
		(fp_line
			(start 1.293368 -5.315966)
			(end 0.37465 -4.434332)
			(stroke
				(width 0.1)
				(type default)
			)
			(layer "F.SilkS")
		)
		(fp_line
			(start 1.293368 -5.315966)
			(end 0.37465 -4.434332)
			(stroke
				(width 0.1)
				(type default)
			)
			(layer "F.SilkS")
		)
		(fp_line
			(start 1.323594 -0.958596)
			(end 2.130552 -1.732788)
			(stroke
				(width 0.1)
				(type default)
			)
			(layer "F.SilkS")
		)
		(fp_line
			(start 1.323594 -0.958596)
			(end 2.130552 -1.732788)
			(stroke
				(width 0.1)
				(type default)
			)
			(layer "F.SilkS")
		)
		(fp_line
			(start 1.366266 -0.941832)
			(end 2.173478 -1.716024)
			(stroke
				(width 0.1)
				(type default)
			)
			(layer "F.SilkS")
		)
		(fp_line
			(start 1.366266 -0.941832)
			(end 2.173478 -1.716024)
			(stroke
				(width 0.1)
				(type default)
			)
			(layer "F.SilkS")
		)
		(fp_line
			(start 1.408684 -0.924814)
			(end 2.21615 -1.699514)
			(stroke
				(width 0.1)
				(type default)
			)
			(layer "F.SilkS")
		)
		(fp_line
			(start 1.408684 -0.924814)
			(end 2.21615 -1.699514)
			(stroke
				(width 0.1)
				(type default)
			)
			(layer "F.SilkS")
		)
		(fp_line
			(start 1.41224 -5.3721)
			(end 0.302768 -4.307586)
			(stroke
				(width 0.1)
				(type default)
			)
			(layer "F.SilkS")
		)
		(fp_line
			(start 1.41224 -5.3721)
			(end 0.302768 -4.307586)
			(stroke
				(width 0.1)
				(type default)
			)
			(layer "F.SilkS")
		)
		(fp_line
			(start 1.451356 -0.90805)
			(end 2.259076 -1.68275)
			(stroke
				(width 0.1)
				(type default)
			)
			(layer "F.SilkS")
		)
		(fp_line
			(start 1.451356 -0.90805)
			(end 2.259076 -1.68275)
			(stroke
				(width 0.1)
				(type default)
			)
			(layer "F.SilkS")
		)
		(fp_line
			(start 1.493774 -0.891032)
			(end 2.301748 -1.66624)
			(stroke
				(width 0.1)
				(type default)
			)
			(layer "F.SilkS")
		)
		(fp_line
			(start 1.493774 -0.891032)
			(end 2.301748 -1.66624)
			(stroke
				(width 0.1)
				(type default)
			)
			(layer "F.SilkS")
		)
		(fp_line
			(start 1.52781 -5.425186)
			(end 0.256794 -4.205732)
			(stroke
				(width 0.1)
				(type default)
			)
			(layer "F.SilkS")
		)
		(fp_line
			(start 1.52781 -5.425186)
			(end 0.256794 -4.205732)
			(stroke
				(width 0.1)
				(type default)
			)
			(layer "F.SilkS")
		)
		(fp_line
			(start 1.536446 -0.874268)
			(end 2.351024 -1.655826)
			(stroke
				(width 0.1)
				(type default)
			)
			(layer "F.SilkS")
		)
		(fp_line
			(start 1.536446 -0.874268)
			(end 2.351024 -1.655826)
			(stroke
				(width 0.1)
				(type default)
			)
			(layer "F.SilkS")
		)
		(fp_line
			(start 1.578864 -0.857504)
			(end 2.404364 -1.649222)
			(stroke
				(width 0.1)
				(type default)
			)
			(layer "F.SilkS")
		)
		(fp_line
			(start 1.578864 -0.857504)
			(end 2.404364 -1.649222)
			(stroke
				(width 0.1)
				(type default)
			)
			(layer "F.SilkS")
		)
		(fp_line
			(start 1.62306 -5.458714)
			(end 0.211328 -4.10464)
			(stroke
				(width 0.1)
				(type default)
			)
			(layer "F.SilkS")
		)
		(fp_line
			(start 1.62306 -5.458714)
			(end 0.211328 -4.10464)
			(stroke
				(width 0.1)
				(type default)
			)
			(layer "F.SilkS")
		)
		(fp_line
			(start 1.623314 -0.842264)
			(end 2.457704 -1.642618)
			(stroke
				(width 0.1)
				(type default)
			)
			(layer "F.SilkS")
		)
		(fp_line
			(start 1.623314 -0.842264)
			(end 2.457704 -1.642618)
			(stroke
				(width 0.1)
				(type default)
			)
			(layer "F.SilkS")
		)
		(fp_line
			(start 1.67005 -0.829564)
			(end 2.511044 -1.636014)
			(stroke
				(width 0.1)
				(type default)
			)
			(layer "F.SilkS")
		)
		(fp_line
			(start 1.67005 -0.829564)
			(end 2.511044 -1.636014)
			(stroke
				(width 0.1)
				(type default)
			)
			(layer "F.SilkS")
		)
		(fp_line
			(start 1.716786 -0.816356)
			(end 2.56413 -1.62941)
			(stroke
				(width 0.1)
				(type default)
			)
			(layer "F.SilkS")
		)
		(fp_line
			(start 1.716786 -0.816356)
			(end 2.56413 -1.62941)
			(stroke
				(width 0.1)
				(type default)
			)
			(layer "F.SilkS")
		)
		(fp_line
			(start 1.717802 -5.492242)
			(end 0.181356 -4.018026)
			(stroke
				(width 0.1)
				(type default)
			)
			(layer "F.SilkS")
		)
		(fp_line
			(start 1.717802 -5.492242)
			(end 0.181356 -4.018026)
			(stroke
				(width 0.1)
				(type default)
			)
			(layer "F.SilkS")
		)
		(fp_line
			(start 1.763522 -0.803656)
			(end 2.624582 -1.629664)
			(stroke
				(width 0.1)
				(type default)
			)
			(layer "F.SilkS")
		)
		(fp_line
			(start 1.763522 -0.803656)
			(end 2.624582 -1.629664)
			(stroke
				(width 0.1)
				(type default)
			)
			(layer "F.SilkS")
		)
		(fp_line
			(start 1.805686 -5.518658)
			(end 0.1524 -3.932682)
			(stroke
				(width 0.1)
				(type default)
			)
			(layer "F.SilkS")
		)
		(fp_line
			(start 1.805686 -5.518658)
			(end 0.1524 -3.932682)
			(stroke
				(width 0.1)
				(type default)
			)
			(layer "F.SilkS")
		)
		(fp_line
			(start 1.810512 -0.790956)
			(end 2.692654 -1.637284)
			(stroke
				(width 0.1)
				(type default)
			)
			(layer "F.SilkS")
		)
		(fp_line
			(start 1.810512 -0.790956)
			(end 2.692654 -1.637284)
			(stroke
				(width 0.1)
				(type default)
			)
			(layer "F.SilkS")
		)
		(fp_line
			(start 1.856994 -0.777748)
			(end 2.760726 -1.64465)
			(stroke
				(width 0.1)
				(type default)
			)
			(layer "F.SilkS")
		)
		(fp_line
			(start 1.856994 -0.777748)
			(end 2.760726 -1.64465)
			(stroke
				(width 0.1)
				(type default)
			)
			(layer "F.SilkS")
		)
		(fp_line
			(start 1.886458 -5.538216)
			(end 0.128016 -3.851402)
			(stroke
				(width 0.1)
				(type default)
			)
			(layer "F.SilkS")
		)
		(fp_line
			(start 1.886458 -5.538216)
			(end 0.128016 -3.851402)
			(stroke
				(width 0.1)
				(type default)
			)
			(layer "F.SilkS")
		)
		(fp_line
			(start 1.90373 -0.765048)
			(end 2.828544 -1.65227)
			(stroke
				(width 0.1)
				(type default)
			)
			(layer "F.SilkS")
		)
		(fp_line
			(start 1.90373 -0.765048)
			(end 2.828544 -1.65227)
			(stroke
				(width 0.1)
				(type default)
			)
			(layer "F.SilkS")
		)
		(fp_line
			(start 1.954276 -0.75565)
			(end 2.906014 -1.66878)
			(stroke
				(width 0.1)
				(type default)
			)
			(layer "F.SilkS")
		)
		(fp_line
			(start 1.954276 -0.75565)
			(end 2.906014 -1.66878)
			(stroke
				(width 0.1)
				(type default)
			)
			(layer "F.SilkS")
		)
		(fp_line
			(start 1.966722 -5.557774)
			(end 0.110236 -3.776726)
			(stroke
				(width 0.1)
				(type default)
			)
			(layer "F.SilkS")
		)
		(fp_line
			(start 1.966722 -5.557774)
			(end 0.110236 -3.776726)
			(stroke
				(width 0.1)
				(type default)
			)
			(layer "F.SilkS")
		)
		(fp_line
			(start 2.00533 -0.74676)
			(end 3.000248 -1.701546)
			(stroke
				(width 0.1)
				(type default)
			)
			(layer "F.SilkS")
		)
		(fp_line
			(start 2.00533 -0.74676)
			(end 3.000248 -1.701546)
			(stroke
				(width 0.1)
				(type default)
			)
			(layer "F.SilkS")
		)
		(fp_line
			(start 2.04597 -5.576062)
			(end 0.092456 -3.70205)
			(stroke
				(width 0.1)
				(type default)
			)
			(layer "F.SilkS")
		)
		(fp_line
			(start 2.04597 -5.576062)
			(end 0.092456 -3.70205)
			(stroke
				(width 0.1)
				(type default)
			)
			(layer "F.SilkS")
		)
		(fp_line
			(start 2.05613 -0.73787)
			(end 3.094228 -1.733804)
			(stroke
				(width 0.1)
				(type default)
			)
			(layer "F.SilkS")
		)
		(fp_line
			(start 2.05613 -0.73787)
			(end 3.094228 -1.733804)
			(stroke
				(width 0.1)
				(type default)
			)
			(layer "F.SilkS")
		)
		(fp_line
			(start 2.10693 -0.72898)
			(end 3.238246 -1.814322)
			(stroke
				(width 0.1)
				(type default)
			)
			(layer "F.SilkS")
		)
		(fp_line
			(start 2.10693 -0.72898)
			(end 3.238246 -1.814322)
			(stroke
				(width 0.1)
				(type default)
			)
			(layer "F.SilkS")
		)
		(fp_line
			(start 2.116328 -5.585968)
			(end 0.07874 -3.631184)
			(stroke
				(width 0.1)
				(type default)
			)
			(layer "F.SilkS")
		)
		(fp_line
			(start 2.116328 -5.585968)
			(end 0.07874 -3.631184)
			(stroke
				(width 0.1)
				(type default)
			)
			(layer "F.SilkS")
		)
		(fp_line
			(start 2.18694 -5.595874)
			(end 0.069342 -3.564382)
			(stroke
				(width 0.1)
				(type default)
			)
			(layer "F.SilkS")
		)
		(fp_line
			(start 2.18694 -5.595874)
			(end 0.069342 -3.564382)
			(stroke
				(width 0.1)
				(type default)
			)
			(layer "F.SilkS")
		)
		(fp_line
			(start 2.208784 -0.710946)
			(end 5.142484 -3.52552)
			(stroke
				(width 0.1)
				(type default)
			)
			(layer "F.SilkS")
		)
		(fp_line
			(start 2.208784 -0.710946)
			(end 5.142484 -3.52552)
			(stroke
				(width 0.1)
				(type default)
			)
			(layer "F.SilkS")
		)
		(fp_line
			(start 2.257552 -5.60578)
			(end 0.059944 -3.49758)
			(stroke
				(width 0.1)
				(type default)
			)
			(layer "F.SilkS")
		)
		(fp_line
			(start 2.257552 -5.60578)
			(end 0.059944 -3.49758)
			(stroke
				(width 0.1)
				(type default)
			)
			(layer "F.SilkS")
		)
		(fp_line
			(start 2.2606 -0.703326)
			(end 5.147564 -3.472942)
			(stroke
				(width 0.1)
				(type default)
			)
			(layer "F.SilkS")
		)
		(fp_line
			(start 2.2606 -0.703326)
			(end 5.147564 -3.472942)
			(stroke
				(width 0.1)
				(type default)
			)
			(layer "F.SilkS")
		)
		(fp_line
			(start 2.315464 -0.698246)
			(end 5.152898 -3.42011)
			(stroke
				(width 0.1)
				(type default)
			)
			(layer "F.SilkS")
		)
		(fp_line
			(start 2.315464 -0.698246)
			(end 5.152898 -3.42011)
			(stroke
				(width 0.1)
				(type default)
			)
			(layer "F.SilkS")
		)
		(fp_line
			(start 2.32791 -5.615686)
			(end 0.051308 -3.431794)
			(stroke
				(width 0.1)
				(type default)
			)
			(layer "F.SilkS")
		)
		(fp_line
			(start 2.32791 -5.615686)
			(end 0.051308 -3.431794)
			(stroke
				(width 0.1)
				(type default)
			)
			(layer "F.SilkS")
		)
		(fp_line
			(start 2.370328 -0.693166)
			(end 5.156708 -3.366262)
			(stroke
				(width 0.1)
				(type default)
			)
			(layer "F.SilkS")
		)
		(fp_line
			(start 2.370328 -0.693166)
			(end 5.156708 -3.366262)
			(stroke
				(width 0.1)
				(type default)
			)
			(layer "F.SilkS")
		)
		(fp_line
			(start 2.390902 -5.61848)
			(end 0.048514 -3.371342)
			(stroke
				(width 0.1)
				(type default)
			)
			(layer "F.SilkS")
		)
		(fp_line
			(start 2.390902 -5.61848)
			(end 0.048514 -3.371342)
			(stroke
				(width 0.1)
				(type default)
			)
			(layer "F.SilkS")
		)
		(fp_line
			(start 2.424938 -0.687832)
			(end 5.158994 -3.310382)
			(stroke
				(width 0.1)
				(type default)
			)
			(layer "F.SilkS")
		)
		(fp_line
			(start 2.424938 -0.687832)
			(end 5.158994 -3.310382)
			(stroke
				(width 0.1)
				(type default)
			)
			(layer "F.SilkS")
		)
		(fp_line
			(start 2.454148 -5.621274)
			(end 0.04572 -3.31089)
			(stroke
				(width 0.1)
				(type default)
			)
			(layer "F.SilkS")
		)
		(fp_line
			(start 2.454148 -5.621274)
			(end 0.04572 -3.31089)
			(stroke
				(width 0.1)
				(type default)
			)
			(layer "F.SilkS")
		)
		(fp_line
			(start 2.479802 -0.682752)
			(end 5.16001 -3.25374)
			(stroke
				(width 0.1)
				(type default)
			)
			(layer "F.SilkS")
		)
		(fp_line
			(start 2.479802 -0.682752)
			(end 5.16001 -3.25374)
			(stroke
				(width 0.1)
				(type default)
			)
			(layer "F.SilkS")
		)
		(fp_line
			(start 2.517394 -5.624322)
			(end 0.042926 -3.250438)
			(stroke
				(width 0.1)
				(type default)
			)
			(layer "F.SilkS")
		)
		(fp_line
			(start 2.517394 -5.624322)
			(end 0.042926 -3.250438)
			(stroke
				(width 0.1)
				(type default)
			)
			(layer "F.SilkS")
		)
		(fp_line
			(start 2.534666 -0.677672)
			(end 5.15747 -3.193796)
			(stroke
				(width 0.1)
				(type default)
			)
			(layer "F.SilkS")
		)
		(fp_line
			(start 2.534666 -0.677672)
			(end 5.15747 -3.193796)
			(stroke
				(width 0.1)
				(type default)
			)
			(layer "F.SilkS")
		)
		(fp_line
			(start 2.580386 -5.626862)
			(end 0.041656 -3.19151)
			(stroke
				(width 0.1)
				(type default)
			)
			(layer "F.SilkS")
		)
		(fp_line
			(start 2.580386 -5.626862)
			(end 0.041656 -3.19151)
			(stroke
				(width 0.1)
				(type default)
			)
			(layer "F.SilkS")
		)
		(fp_line
			(start 2.589276 -0.672338)
			(end 5.15493 -3.133598)
			(stroke
				(width 0.1)
				(type default)
			)
			(layer "F.SilkS")
		)
		(fp_line
			(start 2.589276 -0.672338)
			(end 5.15493 -3.133598)
			(stroke
				(width 0.1)
				(type default)
			)
			(layer "F.SilkS")
		)
		(fp_line
			(start 2.64287 -5.629148)
			(end 0.042672 -3.135122)
			(stroke
				(width 0.1)
				(type default)
			)
			(layer "F.SilkS")
		)
		(fp_line
			(start 2.64287 -5.629148)
			(end 0.042672 -3.135122)
			(stroke
				(width 0.1)
				(type default)
			)
			(layer "F.SilkS")
		)
		(fp_line
			(start 2.646426 -0.669544)
			(end 5.15239 -3.073146)
			(stroke
				(width 0.1)
				(type default)
			)
			(layer "F.SilkS")
		)
		(fp_line
			(start 2.646426 -0.669544)
			(end 5.15239 -3.073146)
			(stroke
				(width 0.1)
				(type default)
			)
			(layer "F.SilkS")
		)
		(fp_line
			(start 2.700528 -5.626862)
			(end 0.04445 -3.078734)
			(stroke
				(width 0.1)
				(type default)
			)
			(layer "F.SilkS")
		)
		(fp_line
			(start 2.700528 -5.626862)
			(end 0.04445 -3.078734)
			(stroke
				(width 0.1)
				(type default)
			)
			(layer "F.SilkS")
		)
		(fp_line
			(start 2.704846 -0.66802)
			(end 5.14985 -3.013202)
			(stroke
				(width 0.1)
				(type default)
			)
			(layer "F.SilkS")
		)
		(fp_line
			(start 2.704846 -0.66802)
			(end 5.14985 -3.013202)
			(stroke
				(width 0.1)
				(type default)
			)
			(layer "F.SilkS")
		)
		(fp_line
			(start 2.75844 -5.62483)
			(end 0.048006 -3.024632)
			(stroke
				(width 0.1)
				(type default)
			)
			(layer "F.SilkS")
		)
		(fp_line
			(start 2.75844 -5.62483)
			(end 0.048006 -3.024632)
			(stroke
				(width 0.1)
				(type default)
			)
			(layer "F.SilkS")
		)
		(fp_line
			(start 2.76352 -0.666242)
			(end 5.14731 -2.953258)
			(stroke
				(width 0.1)
				(type default)
			)
			(layer "F.SilkS")
		)
		(fp_line
			(start 2.76352 -0.666242)
			(end 5.14731 -2.953258)
			(stroke
				(width 0.1)
				(type default)
			)
			(layer "F.SilkS")
		)
		(fp_line
			(start 2.816098 -5.622544)
			(end 0.051562 -2.970276)
			(stroke
				(width 0.1)
				(type default)
			)
			(layer "F.SilkS")
		)
		(fp_line
			(start 2.816098 -5.622544)
			(end 0.051562 -2.970276)
			(stroke
				(width 0.1)
				(type default)
			)
			(layer "F.SilkS")
		)
		(fp_line
			(start 2.82194 -0.664718)
			(end 5.145024 -2.89306)
			(stroke
				(width 0.1)
				(type default)
			)
			(layer "F.SilkS")
		)
		(fp_line
			(start 2.82194 -0.664718)
			(end 5.145024 -2.89306)
			(stroke
				(width 0.1)
				(type default)
			)
			(layer "F.SilkS")
		)
		(fp_line
			(start 2.87401 -5.620258)
			(end 0.054864 -2.91592)
			(stroke
				(width 0.1)
				(type default)
			)
			(layer "F.SilkS")
		)
		(fp_line
			(start 2.87401 -5.620258)
			(end 0.054864 -2.91592)
			(stroke
				(width 0.1)
				(type default)
			)
			(layer "F.SilkS")
		)
		(fp_line
			(start 2.88036 -0.662686)
			(end 5.13588 -2.826512)
			(stroke
				(width 0.1)
				(type default)
			)
			(layer "F.SilkS")
		)
		(fp_line
			(start 2.88036 -0.662686)
			(end 5.13588 -2.826512)
			(stroke
				(width 0.1)
				(type default)
			)
			(layer "F.SilkS")
		)
		(fp_line
			(start 2.92989 -5.616194)
			(end 0.061468 -2.864358)
			(stroke
				(width 0.1)
				(type default)
			)
			(layer "F.SilkS")
		)
		(fp_line
			(start 2.92989 -5.616194)
			(end 0.061468 -2.864358)
			(stroke
				(width 0.1)
				(type default)
			)
			(layer "F.SilkS")
		)
		(fp_line
			(start 2.93878 -0.661416)
			(end 5.126736 -2.760218)
			(stroke
				(width 0.1)
				(type default)
			)
			(layer "F.SilkS")
		)
		(fp_line
			(start 2.93878 -0.661416)
			(end 5.126736 -2.760218)
			(stroke
				(width 0.1)
				(type default)
			)
			(layer "F.SilkS")
		)
		(fp_line
			(start 2.98323 -5.609336)
			(end 0.067818 -2.812542)
			(stroke
				(width 0.1)
				(type default)
			)
			(layer "F.SilkS")
		)
		(fp_line
			(start 2.98323 -5.609336)
			(end 0.067818 -2.812542)
			(stroke
				(width 0.1)
				(type default)
			)
			(layer "F.SilkS")
		)
		(fp_line
			(start 2.9972 -0.659638)
			(end 5.117592 -2.69367)
			(stroke
				(width 0.1)
				(type default)
			)
			(layer "F.SilkS")
		)
		(fp_line
			(start 2.9972 -0.659638)
			(end 5.117592 -2.69367)
			(stroke
				(width 0.1)
				(type default)
			)
			(layer "F.SilkS")
		)
		(fp_line
			(start 3.03657 -5.602732)
			(end 0.073914 -2.76098)
			(stroke
				(width 0.1)
				(type default)
			)
			(layer "F.SilkS")
		)
		(fp_line
			(start 3.03657 -5.602732)
			(end 0.073914 -2.76098)
			(stroke
				(width 0.1)
				(type default)
			)
			(layer "F.SilkS")
		)
		(fp_line
			(start 3.048 -0.651002)
			(end 5.108194 -2.627122)
			(stroke
				(width 0.1)
				(type default)
			)
			(layer "F.SilkS")
		)
		(fp_line
			(start 3.048 -0.651002)
			(end 5.108194 -2.627122)
			(stroke
				(width 0.1)
				(type default)
			)
			(layer "F.SilkS")
		)
		(fp_line
			(start 3.089656 -5.596382)
			(end 0.080264 -2.709418)
			(stroke
				(width 0.1)
				(type default)
			)
			(layer "F.SilkS")
		)
		(fp_line
			(start 3.089656 -5.596382)
			(end 0.080264 -2.709418)
			(stroke
				(width 0.1)
				(type default)
			)
			(layer "F.SilkS")
		)
		(fp_line
			(start 3.094482 -0.637286)
			(end 5.09905 -2.560574)
			(stroke
				(width 0.1)
				(type default)
			)
			(layer "F.SilkS")
		)
		(fp_line
			(start 3.094482 -0.637286)
			(end 5.09905 -2.560574)
			(stroke
				(width 0.1)
				(type default)
			)
			(layer "F.SilkS")
		)
		(fp_line
			(start 3.13944 -0.622808)
			(end 5.081524 -2.485898)
			(stroke
				(width 0.1)
				(type default)
			)
			(layer "F.SilkS")
		)
		(fp_line
			(start 3.13944 -0.622808)
			(end 5.081524 -2.485898)
			(stroke
				(width 0.1)
				(type default)
			)
			(layer "F.SilkS")
		)
		(fp_line
			(start 3.14325 -5.589778)
			(end 1.972818 -4.467098)
			(stroke
				(width 0.1)
				(type default)
			)
			(layer "F.SilkS")
		)
		(fp_line
			(start 3.14325 -5.589778)
			(end 1.972818 -4.467098)
			(stroke
				(width 0.1)
				(type default)
			)
			(layer "F.SilkS")
		)
		(fp_line
			(start 3.184144 -0.60833)
			(end 5.061966 -2.409698)
			(stroke
				(width 0.1)
				(type default)
			)
			(layer "F.SilkS")
		)
		(fp_line
			(start 3.184144 -0.60833)
			(end 5.061966 -2.409698)
			(stroke
				(width 0.1)
				(type default)
			)
			(layer "F.SilkS")
		)
		(fp_line
			(start 3.19405 -5.580888)
			(end 2.123694 -4.553966)
			(stroke
				(width 0.1)
				(type default)
			)
			(layer "F.SilkS")
		)
		(fp_line
			(start 3.19405 -5.580888)
			(end 2.123694 -4.553966)
			(stroke
				(width 0.1)
				(type default)
			)
			(layer "F.SilkS")
		)
		(fp_line
			(start 3.22834 -0.592836)
			(end 5.042408 -2.33299)
			(stroke
				(width 0.1)
				(type default)
			)
			(layer "F.SilkS")
		)
		(fp_line
			(start 3.22834 -0.592836)
			(end 5.042408 -2.33299)
			(stroke
				(width 0.1)
				(type default)
			)
			(layer "F.SilkS")
		)
		(fp_line
			(start 3.243072 -5.57022)
			(end 2.217166 -4.586224)
			(stroke
				(width 0.1)
				(type default)
			)
			(layer "F.SilkS")
		)
		(fp_line
			(start 3.243072 -5.57022)
			(end 2.217166 -4.586224)
			(stroke
				(width 0.1)
				(type default)
			)
			(layer "F.SilkS")
		)
		(fp_line
			(start 3.272536 -0.577342)
			(end 5.02285 -2.256536)
			(stroke
				(width 0.1)
				(type default)
			)
			(layer "F.SilkS")
		)
		(fp_line
			(start 3.272536 -0.577342)
			(end 5.02285 -2.256536)
			(stroke
				(width 0.1)
				(type default)
			)
			(layer "F.SilkS")
		)
		(fp_line
			(start 3.292094 -5.559552)
			(end 2.310892 -4.618228)
			(stroke
				(width 0.1)
				(type default)
			)
			(layer "F.SilkS")
		)
		(fp_line
			(start 3.292094 -5.559552)
			(end 2.310892 -4.618228)
			(stroke
				(width 0.1)
				(type default)
			)
			(layer "F.SilkS")
		)
		(fp_line
			(start 3.316224 -0.561848)
			(end 4.990338 -2.167636)
			(stroke
				(width 0.1)
				(type default)
			)
			(layer "F.SilkS")
		)
		(fp_line
			(start 3.316224 -0.561848)
			(end 4.990338 -2.167636)
			(stroke
				(width 0.1)
				(type default)
			)
			(layer "F.SilkS")
		)
		(fp_line
			(start 3.34137 -5.549138)
			(end 2.389632 -4.636262)
			(stroke
				(width 0.1)
				(type default)
			)
			(layer "F.SilkS")
		)
		(fp_line
			(start 3.34137 -5.549138)
			(end 2.389632 -4.636262)
			(stroke
				(width 0.1)
				(type default)
			)
			(layer "F.SilkS")
		)
		(fp_line
			(start 3.359912 -0.545846)
			(end 4.953254 -2.074418)
			(stroke
				(width 0.1)
				(type default)
			)
			(layer "F.SilkS")
		)
		(fp_line
			(start 3.359912 -0.545846)
			(end 4.953254 -2.074418)
			(stroke
				(width 0.1)
				(type default)
			)
			(layer "F.SilkS")
		)
		(fp_line
			(start 3.390392 -5.53847)
			(end 2.458212 -4.644136)
			(stroke
				(width 0.1)
				(type default)
			)
			(layer "F.SilkS")
		)
		(fp_line
			(start 3.390392 -5.53847)
			(end 2.458212 -4.644136)
			(stroke
				(width 0.1)
				(type default)
			)
			(layer "F.SilkS")
		)
		(fp_line
			(start 3.4036 -0.530098)
			(end 4.915916 -1.980946)
			(stroke
				(width 0.1)
				(type default)
			)
			(layer "F.SilkS")
		)
		(fp_line
			(start 3.4036 -0.530098)
			(end 4.915916 -1.980946)
			(stroke
				(width 0.1)
				(type default)
			)
			(layer "F.SilkS")
		)
		(fp_line
			(start 3.437382 -5.52577)
			(end 2.526538 -4.65201)
			(stroke
				(width 0.1)
				(type default)
			)
			(layer "F.SilkS")
		)
		(fp_line
			(start 3.437382 -5.52577)
			(end 2.526538 -4.65201)
			(stroke
				(width 0.1)
				(type default)
			)
			(layer "F.SilkS")
		)
		(fp_line
			(start 3.447034 -0.513842)
			(end 4.85267 -1.862582)
			(stroke
				(width 0.1)
				(type default)
			)
			(layer "F.SilkS")
		)
		(fp_line
			(start 3.447034 -0.513842)
			(end 4.85267 -1.862582)
			(stroke
				(width 0.1)
				(type default)
			)
			(layer "F.SilkS")
		)
		(fp_line
			(start 3.482594 -5.511292)
			(end 2.593086 -4.658106)
			(stroke
				(width 0.1)
				(type default)
			)
			(layer "F.SilkS")
		)
		(fp_line
			(start 3.482594 -5.511292)
			(end 2.593086 -4.658106)
			(stroke
				(width 0.1)
				(type default)
			)
			(layer "F.SilkS")
		)
		(fp_line
			(start 3.490468 -0.498094)
			(end 4.77901 -1.734058)
			(stroke
				(width 0.1)
				(type default)
			)
			(layer "F.SilkS")
		)
		(fp_line
			(start 3.490468 -0.498094)
			(end 4.77901 -1.734058)
			(stroke
				(width 0.1)
				(type default)
			)
			(layer "F.SilkS")
		)
		(fp_line
			(start 3.527806 -5.497068)
			(end 2.647188 -4.652264)
			(stroke
				(width 0.1)
				(type default)
			)
			(layer "F.SilkS")
		)
		(fp_line
			(start 3.527806 -5.497068)
			(end 2.647188 -4.652264)
			(stroke
				(width 0.1)
				(type default)
			)
			(layer "F.SilkS")
		)
		(fp_line
			(start 3.533648 -0.481838)
			(end 4.147312 -1.070356)
			(stroke
				(width 0.1)
				(type default)
			)
			(layer "F.SilkS")
		)
		(fp_line
			(start 3.533648 -0.481838)
			(end 4.147312 -1.070356)
			(stroke
				(width 0.1)
				(type default)
			)
			(layer "F.SilkS")
		)
		(fp_line
			(start 3.573018 -5.482844)
			(end 2.700782 -4.645914)
			(stroke
				(width 0.1)
				(type default)
			)
			(layer "F.SilkS")
		)
		(fp_line
			(start 3.573018 -5.482844)
			(end 2.700782 -4.645914)
			(stroke
				(width 0.1)
				(type default)
			)
			(layer "F.SilkS")
		)
		(fp_line
			(start 3.61823 -5.468366)
			(end 2.75463 -4.639818)
			(stroke
				(width 0.1)
				(type default)
			)
			(layer "F.SilkS")
		)
		(fp_line
			(start 3.61823 -5.468366)
			(end 2.75463 -4.639818)
			(stroke
				(width 0.1)
				(type default)
			)
			(layer "F.SilkS")
		)
		(fp_line
			(start 3.620008 -0.449072)
			(end 4.2164 -1.02108)
			(stroke
				(width 0.1)
				(type default)
			)
			(layer "F.SilkS")
		)
		(fp_line
			(start 3.620008 -0.449072)
			(end 4.2164 -1.02108)
			(stroke
				(width 0.1)
				(type default)
			)
			(layer "F.SilkS")
		)
		(fp_line
			(start 3.662426 -5.452872)
			(end 2.808478 -4.633976)
			(stroke
				(width 0.1)
				(type default)
			)
			(layer "F.SilkS")
		)
		(fp_line
			(start 3.662426 -5.452872)
			(end 2.808478 -4.633976)
			(stroke
				(width 0.1)
				(type default)
			)
			(layer "F.SilkS")
		)
		(fp_line
			(start 3.663442 -0.43307)
			(end 4.250944 -0.996696)
			(stroke
				(width 0.1)
				(type default)
			)
			(layer "F.SilkS")
		)
		(fp_line
			(start 3.663442 -0.43307)
			(end 4.250944 -0.996696)
			(stroke
				(width 0.1)
				(type default)
			)
			(layer "F.SilkS")
		)
		(fp_line
			(start 3.703828 -5.435092)
			(end 2.860548 -4.626102)
			(stroke
				(width 0.1)
				(type default)
			)
			(layer "F.SilkS")
		)
		(fp_line
			(start 3.703828 -5.435092)
			(end 2.860548 -4.626102)
			(stroke
				(width 0.1)
				(type default)
			)
			(layer "F.SilkS")
		)
		(fp_line
			(start 3.706368 -0.416814)
			(end 4.285488 -0.972058)
			(stroke
				(width 0.1)
				(type default)
			)
			(layer "F.SilkS")
		)
		(fp_line
			(start 3.706368 -0.416814)
			(end 4.285488 -0.972058)
			(stroke
				(width 0.1)
				(type default)
			)
			(layer "F.SilkS")
		)
		(fp_line
			(start 3.745484 -5.417058)
			(end 2.90449 -4.610354)
			(stroke
				(width 0.1)
				(type default)
			)
			(layer "F.SilkS")
		)
		(fp_line
			(start 3.745484 -5.417058)
			(end 2.90449 -4.610354)
			(stroke
				(width 0.1)
				(type default)
			)
			(layer "F.SilkS")
		)
		(fp_line
			(start 3.749548 -0.400304)
			(end 4.320286 -0.947674)
			(stroke
				(width 0.1)
				(type default)
			)
			(layer "F.SilkS")
		)
		(fp_line
			(start 3.749548 -0.400304)
			(end 4.320286 -0.947674)
			(stroke
				(width 0.1)
				(type default)
			)
			(layer "F.SilkS")
		)
		(fp_line
			(start 3.786886 -5.399278)
			(end 2.948432 -4.595114)
			(stroke
				(width 0.1)
				(type default)
			)
			(layer "F.SilkS")
		)
		(fp_line
			(start 3.786886 -5.399278)
			(end 2.948432 -4.595114)
			(stroke
				(width 0.1)
				(type default)
			)
			(layer "F.SilkS")
		)
		(fp_line
			(start 3.792474 -0.383794)
			(end 4.35483 -0.923036)
			(stroke
				(width 0.1)
				(type default)
			)
			(layer "F.SilkS")
		)
		(fp_line
			(start 3.792474 -0.383794)
			(end 4.35483 -0.923036)
			(stroke
				(width 0.1)
				(type default)
			)
			(layer "F.SilkS")
		)
		(fp_line
			(start 3.828288 -5.381498)
			(end 2.992628 -4.57962)
			(stroke
				(width 0.1)
				(type default)
			)
			(layer "F.SilkS")
		)
		(fp_line
			(start 3.828288 -5.381498)
			(end 2.992628 -4.57962)
			(stroke
				(width 0.1)
				(type default)
			)
			(layer "F.SilkS")
		)
		(fp_line
			(start 3.8354 -0.36703)
			(end 4.389374 -0.898398)
			(stroke
				(width 0.1)
				(type default)
			)
			(layer "F.SilkS")
		)
		(fp_line
			(start 3.8354 -0.36703)
			(end 4.389374 -0.898398)
			(stroke
				(width 0.1)
				(type default)
			)
			(layer "F.SilkS")
		)
		(fp_line
			(start 3.870198 -5.363464)
			(end 3.036824 -4.56438)
			(stroke
				(width 0.1)
				(type default)
			)
			(layer "F.SilkS")
		)
		(fp_line
			(start 3.870198 -5.363464)
			(end 3.036824 -4.56438)
			(stroke
				(width 0.1)
				(type default)
			)
			(layer "F.SilkS")
		)
		(fp_line
			(start 3.878326 -0.35052)
			(end 4.423918 -0.874014)
			(stroke
				(width 0.1)
				(type default)
			)
			(layer "F.SilkS")
		)
		(fp_line
			(start 3.878326 -0.35052)
			(end 4.423918 -0.874014)
			(stroke
				(width 0.1)
				(type default)
			)
			(layer "F.SilkS")
		)
		(fp_line
			(start 3.908552 -5.34289)
			(end 3.080766 -4.548886)
			(stroke
				(width 0.1)
				(type default)
			)
			(layer "F.SilkS")
		)
		(fp_line
			(start 3.908552 -5.34289)
			(end 3.080766 -4.548886)
			(stroke
				(width 0.1)
				(type default)
			)
			(layer "F.SilkS")
		)
		(fp_line
			(start 3.921252 -0.33401)
			(end 4.458462 -0.849376)
			(stroke
				(width 0.1)
				(type default)
			)
			(layer "F.SilkS")
		)
		(fp_line
			(start 3.921252 -0.33401)
			(end 4.458462 -0.849376)
			(stroke
				(width 0.1)
				(type default)
			)
			(layer "F.SilkS")
		)
		(fp_line
			(start 3.946652 -5.321808)
			(end 3.12039 -4.529074)
			(stroke
				(width 0.1)
				(type default)
			)
			(layer "F.SilkS")
		)
		(fp_line
			(start 3.946652 -5.321808)
			(end 3.12039 -4.529074)
			(stroke
				(width 0.1)
				(type default)
			)
			(layer "F.SilkS")
		)
		(fp_line
			(start 3.964178 -0.3175)
			(end 4.493006 -0.824738)
			(stroke
				(width 0.1)
				(type default)
			)
			(layer "F.SilkS")
		)
		(fp_line
			(start 3.964178 -0.3175)
			(end 4.493006 -0.824738)
			(stroke
				(width 0.1)
				(type default)
			)
			(layer "F.SilkS")
		)
		(fp_line
			(start 3.984752 -5.300472)
			(end 3.15722 -4.506722)
			(stroke
				(width 0.1)
				(type default)
			)
			(layer "F.SilkS")
		)
		(fp_line
			(start 3.984752 -5.300472)
			(end 3.15722 -4.506722)
			(stroke
				(width 0.1)
				(type default)
			)
			(layer "F.SilkS")
		)
		(fp_line
			(start 4.00685 -0.30099)
			(end 4.52755 -0.800608)
			(stroke
				(width 0.1)
				(type default)
			)
			(layer "F.SilkS")
		)
		(fp_line
			(start 4.00685 -0.30099)
			(end 4.52755 -0.800608)
			(stroke
				(width 0.1)
				(type default)
			)
			(layer "F.SilkS")
		)
		(fp_line
			(start 4.022852 -5.27939)
			(end 3.193796 -4.484116)
			(stroke
				(width 0.1)
				(type default)
			)
			(layer "F.SilkS")
		)
		(fp_line
			(start 4.022852 -5.27939)
			(end 3.193796 -4.484116)
			(stroke
				(width 0.1)
				(type default)
			)
			(layer "F.SilkS")
		)
		(fp_line
			(start 4.049776 -0.284226)
			(end 4.562094 -0.775716)
			(stroke
				(width 0.1)
				(type default)
			)
			(layer "F.SilkS")
		)
		(fp_line
			(start 4.049776 -0.284226)
			(end 4.562094 -0.775716)
			(stroke
				(width 0.1)
				(type default)
			)
			(layer "F.SilkS")
		)
		(fp_line
			(start 4.060952 -5.258054)
			(end 3.230372 -4.461256)
			(stroke
				(width 0.1)
				(type default)
			)
			(layer "F.SilkS")
		)
		(fp_line
			(start 4.060952 -5.258054)
			(end 3.230372 -4.461256)
			(stroke
				(width 0.1)
				(type default)
			)
			(layer "F.SilkS")
		)
		(fp_line
			(start 4.092448 -0.267462)
			(end 4.596892 -0.751332)
			(stroke
				(width 0.1)
				(type default)
			)
			(layer "F.SilkS")
		)
		(fp_line
			(start 4.092448 -0.267462)
			(end 4.596892 -0.751332)
			(stroke
				(width 0.1)
				(type default)
			)
			(layer "F.SilkS")
		)
		(fp_line
			(start 4.09829 -5.23621)
			(end 3.266948 -4.438904)
			(stroke
				(width 0.1)
				(type default)
			)
			(layer "F.SilkS")
		)
		(fp_line
			(start 4.09829 -5.23621)
			(end 3.266948 -4.438904)
			(stroke
				(width 0.1)
				(type default)
			)
			(layer "F.SilkS")
		)
		(fp_line
			(start 4.133088 -5.21208)
			(end 3.303524 -4.416044)
			(stroke
				(width 0.1)
				(type default)
			)
			(layer "F.SilkS")
		)
		(fp_line
			(start 4.133088 -5.21208)
			(end 3.303524 -4.416044)
			(stroke
				(width 0.1)
				(type default)
			)
			(layer "F.SilkS")
		)
		(fp_line
			(start 4.135374 -0.250698)
			(end 4.631436 -0.726694)
			(stroke
				(width 0.1)
				(type default)
			)
			(layer "F.SilkS")
		)
		(fp_line
			(start 4.135374 -0.250698)
			(end 4.631436 -0.726694)
			(stroke
				(width 0.1)
				(type default)
			)
			(layer "F.SilkS")
		)
		(fp_line
			(start 4.16814 -5.187696)
			(end 3.337052 -4.390644)
			(stroke
				(width 0.1)
				(type default)
			)
			(layer "F.SilkS")
		)
		(fp_line
			(start 4.16814 -5.187696)
			(end 3.337052 -4.390644)
			(stroke
				(width 0.1)
				(type default)
			)
			(layer "F.SilkS")
		)
		(fp_line
			(start 4.178046 -0.234188)
			(end 4.66598 -0.702056)
			(stroke
				(width 0.1)
				(type default)
			)
			(layer "F.SilkS")
		)
		(fp_line
			(start 4.178046 -0.234188)
			(end 4.66598 -0.702056)
			(stroke
				(width 0.1)
				(type default)
			)
			(layer "F.SilkS")
		)
		(fp_line
			(start 4.181856 -1.045718)
			(end 3.576828 -0.465582)
			(stroke
				(width 0.1)
				(type default)
			)
			(layer "F.SilkS")
		)
		(fp_line
			(start 4.181856 -1.045718)
			(end 3.576828 -0.465582)
			(stroke
				(width 0.1)
				(type default)
			)
			(layer "F.SilkS")
		)
		(fp_line
			(start 4.202938 -5.163312)
			(end 3.367532 -4.362196)
			(stroke
				(width 0.1)
				(type default)
			)
			(layer "F.SilkS")
		)
		(fp_line
			(start 4.202938 -5.163312)
			(end 3.367532 -4.362196)
			(stroke
				(width 0.1)
				(type default)
			)
			(layer "F.SilkS")
		)
		(fp_line
			(start 4.220718 -0.217678)
			(end 4.700524 -0.677926)
			(stroke
				(width 0.1)
				(type default)
			)
			(layer "F.SilkS")
		)
		(fp_line
			(start 4.220718 -0.217678)
			(end 4.700524 -0.677926)
			(stroke
				(width 0.1)
				(type default)
			)
			(layer "F.SilkS")
		)
		(fp_line
			(start 4.237736 -5.139182)
			(end 3.397504 -4.33324)
			(stroke
				(width 0.1)
				(type default)
			)
			(layer "F.SilkS")
		)
		(fp_line
			(start 4.237736 -5.139182)
			(end 3.397504 -4.33324)
			(stroke
				(width 0.1)
				(type default)
			)
			(layer "F.SilkS")
		)
		(fp_line
			(start 4.26339 -0.200406)
			(end 4.735068 -0.653034)
			(stroke
				(width 0.1)
				(type default)
			)
			(layer "F.SilkS")
		)
		(fp_line
			(start 4.26339 -0.200406)
			(end 4.735068 -0.653034)
			(stroke
				(width 0.1)
				(type default)
			)
			(layer "F.SilkS")
		)
		(fp_line
			(start 4.272534 -5.115052)
			(end 3.427984 -4.304792)
			(stroke
				(width 0.1)
				(type default)
			)
			(layer "F.SilkS")
		)
		(fp_line
			(start 4.272534 -5.115052)
			(end 3.427984 -4.304792)
			(stroke
				(width 0.1)
				(type default)
			)
			(layer "F.SilkS")
		)
		(fp_line
			(start 4.306062 -0.183896)
			(end 4.769866 -0.62865)
			(stroke
				(width 0.1)
				(type default)
			)
			(layer "F.SilkS")
		)
		(fp_line
			(start 4.306062 -0.183896)
			(end 4.769866 -0.62865)
			(stroke
				(width 0.1)
				(type default)
			)
			(layer "F.SilkS")
		)
		(fp_line
			(start 4.306316 -5.089398)
			(end 3.45821 -4.275836)
			(stroke
				(width 0.1)
				(type default)
			)
			(layer "F.SilkS")
		)
		(fp_line
			(start 4.306316 -5.089398)
			(end 3.45821 -4.275836)
			(stroke
				(width 0.1)
				(type default)
			)
			(layer "F.SilkS")
		)
		(fp_line
			(start 4.338066 -5.06222)
			(end 3.488436 -4.247388)
			(stroke
				(width 0.1)
				(type default)
			)
			(layer "F.SilkS")
		)
		(fp_line
			(start 4.338066 -5.06222)
			(end 3.488436 -4.247388)
			(stroke
				(width 0.1)
				(type default)
			)
			(layer "F.SilkS")
		)
		(fp_line
			(start 4.348734 -0.166878)
			(end 4.80441 -0.604266)
			(stroke
				(width 0.1)
				(type default)
			)
			(layer "F.SilkS")
		)
		(fp_line
			(start 4.348734 -0.166878)
			(end 4.80441 -0.604266)
			(stroke
				(width 0.1)
				(type default)
			)
			(layer "F.SilkS")
		)
		(fp_line
			(start 4.37007 -5.035296)
			(end 3.518408 -4.218432)
			(stroke
				(width 0.1)
				(type default)
			)
			(layer "F.SilkS")
		)
		(fp_line
			(start 4.37007 -5.035296)
			(end 3.518408 -4.218432)
			(stroke
				(width 0.1)
				(type default)
			)
			(layer "F.SilkS")
		)
		(fp_line
			(start 4.391406 -0.150114)
			(end 4.838954 -0.579628)
			(stroke
				(width 0.1)
				(type default)
			)
			(layer "F.SilkS")
		)
		(fp_line
			(start 4.391406 -0.150114)
			(end 4.838954 -0.579628)
			(stroke
				(width 0.1)
				(type default)
			)
			(layer "F.SilkS")
		)
		(fp_line
			(start 4.401566 -5.008118)
			(end 3.542792 -4.183888)
			(stroke
				(width 0.1)
				(type default)
			)
			(layer "F.SilkS")
		)
		(fp_line
			(start 4.401566 -5.008118)
			(end 3.542792 -4.183888)
			(stroke
				(width 0.1)
				(type default)
			)
			(layer "F.SilkS")
		)
		(fp_line
			(start 4.43357 -4.98094)
			(end 3.567176 -4.149598)
			(stroke
				(width 0.1)
				(type default)
			)
			(layer "F.SilkS")
		)
		(fp_line
			(start 4.43357 -4.98094)
			(end 3.567176 -4.149598)
			(stroke
				(width 0.1)
				(type default)
			)
			(layer "F.SilkS")
		)
		(fp_line
			(start 4.433824 -0.133604)
			(end 4.873752 -0.555244)
			(stroke
				(width 0.1)
				(type default)
			)
			(layer "F.SilkS")
		)
		(fp_line
			(start 4.433824 -0.133604)
			(end 4.873752 -0.555244)
			(stroke
				(width 0.1)
				(type default)
			)
			(layer "F.SilkS")
		)
		(fp_line
			(start 4.46532 -4.953508)
			(end 3.59156 -4.115308)
			(stroke
				(width 0.1)
				(type default)
			)
			(layer "F.SilkS")
		)
		(fp_line
			(start 4.46532 -4.953508)
			(end 3.59156 -4.115308)
			(stroke
				(width 0.1)
				(type default)
			)
			(layer "F.SilkS")
		)
		(fp_line
			(start 4.476496 -0.116332)
			(end 4.908296 -0.530352)
			(stroke
				(width 0.1)
				(type default)
			)
			(layer "F.SilkS")
		)
		(fp_line
			(start 4.476496 -0.116332)
			(end 4.908296 -0.530352)
			(stroke
				(width 0.1)
				(type default)
			)
			(layer "F.SilkS")
		)
		(fp_line
			(start 4.4958 -4.92506)
			(end 3.615944 -4.081018)
			(stroke
				(width 0.1)
				(type default)
			)
			(layer "F.SilkS")
		)
		(fp_line
			(start 4.4958 -4.92506)
			(end 3.615944 -4.081018)
			(stroke
				(width 0.1)
				(type default)
			)
			(layer "F.SilkS")
		)
		(fp_line
			(start 4.519168 -0.099822)
			(end 4.94284 -0.506222)
			(stroke
				(width 0.1)
				(type default)
			)
			(layer "F.SilkS")
		)
		(fp_line
			(start 4.519168 -0.099822)
			(end 4.94284 -0.506222)
			(stroke
				(width 0.1)
				(type default)
			)
			(layer "F.SilkS")
		)
		(fp_line
			(start 4.52374 -4.894072)
			(end 3.640328 -4.046728)
			(stroke
				(width 0.1)
				(type default)
			)
			(layer "F.SilkS")
		)
		(fp_line
			(start 4.52374 -4.894072)
			(end 3.640328 -4.046728)
			(stroke
				(width 0.1)
				(type default)
			)
			(layer "F.SilkS")
		)
		(fp_line
			(start 4.55168 -4.863338)
			(end 3.664712 -4.012438)
			(stroke
				(width 0.1)
				(type default)
			)
			(layer "F.SilkS")
		)
		(fp_line
			(start 4.55168 -4.863338)
			(end 3.664712 -4.012438)
			(stroke
				(width 0.1)
				(type default)
			)
			(layer "F.SilkS")
		)
		(fp_line
			(start 4.561586 -0.08255)
			(end 4.977384 -0.481584)
			(stroke
				(width 0.1)
				(type default)
			)
			(layer "F.SilkS")
		)
		(fp_line
			(start 4.561586 -0.08255)
			(end 4.977384 -0.481584)
			(stroke
				(width 0.1)
				(type default)
			)
			(layer "F.SilkS")
		)
		(fp_line
			(start 4.57962 -4.83235)
			(end 3.686556 -3.975608)
			(stroke
				(width 0.1)
				(type default)
			)
			(layer "F.SilkS")
		)
		(fp_line
			(start 4.57962 -4.83235)
			(end 3.686556 -3.975608)
			(stroke
				(width 0.1)
				(type default)
			)
			(layer "F.SilkS")
		)
		(fp_line
			(start 4.60756 -4.801362)
			(end 3.704844 -3.935476)
			(stroke
				(width 0.1)
				(type default)
			)
			(layer "F.SilkS")
		)
		(fp_line
			(start 4.60756 -4.801362)
			(end 3.704844 -3.935476)
			(stroke
				(width 0.1)
				(type default)
			)
			(layer "F.SilkS")
		)
		(fp_line
			(start 4.631182 -0.091948)
			(end 4.713478 -0.112776)
			(stroke
				(width 0.1)
				(type default)
			)
			(layer "F.SilkS")
		)
		(fp_line
			(start 4.631182 -0.091948)
			(end 4.713478 -0.112776)
			(stroke
				(width 0.1)
				(type default)
			)
			(layer "F.SilkS")
		)
		(fp_line
			(start 4.631182 -0.091948)
			(end 5.012182 -0.456946)
			(stroke
				(width 0.1)
				(type default)
			)
			(layer "F.SilkS")
		)
		(fp_line
			(start 4.631182 -0.091948)
			(end 5.012182 -0.456946)
			(stroke
				(width 0.1)
				(type default)
			)
			(layer "F.SilkS")
		)
		(fp_line
			(start 4.635246 -4.770374)
			(end 3.723386 -3.895598)
			(stroke
				(width 0.1)
				(type default)
			)
			(layer "F.SilkS")
		)
		(fp_line
			(start 4.635246 -4.770374)
			(end 3.723386 -3.895598)
			(stroke
				(width 0.1)
				(type default)
			)
			(layer "F.SilkS")
		)
		(fp_line
			(start 4.663186 -4.739386)
			(end 3.741928 -3.85572)
			(stroke
				(width 0.1)
				(type default)
			)
			(layer "F.SilkS")
		)
		(fp_line
			(start 4.663186 -4.739386)
			(end 3.741928 -3.85572)
			(stroke
				(width 0.1)
				(type default)
			)
			(layer "F.SilkS")
		)
		(fp_line
			(start 4.690618 -4.70789)
			(end 3.76047 -3.815588)
			(stroke
				(width 0.1)
				(type default)
			)
			(layer "F.SilkS")
		)
		(fp_line
			(start 4.690618 -4.70789)
			(end 3.76047 -3.815588)
			(stroke
				(width 0.1)
				(type default)
			)
			(layer "F.SilkS")
		)
		(fp_line
			(start 4.713478 -0.112776)
			(end 4.795266 -0.133604)
			(stroke
				(width 0.1)
				(type default)
			)
			(layer "F.SilkS")
		)
		(fp_line
			(start 4.713478 -0.112776)
			(end 4.795266 -0.133604)
			(stroke
				(width 0.1)
				(type default)
			)
			(layer "F.SilkS")
		)
		(fp_line
			(start 4.713478 -0.112776)
			(end 5.046726 -0.432562)
			(stroke
				(width 0.1)
				(type default)
			)
			(layer "F.SilkS")
		)
		(fp_line
			(start 4.713478 -0.112776)
			(end 5.046726 -0.432562)
			(stroke
				(width 0.1)
				(type default)
			)
			(layer "F.SilkS")
		)
		(fp_line
			(start 4.713732 -4.672584)
			(end 3.778758 -3.775456)
			(stroke
				(width 0.1)
				(type default)
			)
			(layer "F.SilkS")
		)
		(fp_line
			(start 4.713732 -4.672584)
			(end 3.778758 -3.775456)
			(stroke
				(width 0.1)
				(type default)
			)
			(layer "F.SilkS")
		)
		(fp_line
			(start 4.7371 -4.637278)
			(end 3.7973 -3.735578)
			(stroke
				(width 0.1)
				(type default)
			)
			(layer "F.SilkS")
		)
		(fp_line
			(start 4.7371 -4.637278)
			(end 3.7973 -3.735578)
			(stroke
				(width 0.1)
				(type default)
			)
			(layer "F.SilkS")
		)
		(fp_line
			(start 4.760214 -4.601718)
			(end 3.81 -3.689858)
			(stroke
				(width 0.1)
				(type default)
			)
			(layer "F.SilkS")
		)
		(fp_line
			(start 4.760214 -4.601718)
			(end 3.81 -3.689858)
			(stroke
				(width 0.1)
				(type default)
			)
			(layer "F.SilkS")
		)
		(fp_line
			(start 4.783582 -4.566158)
			(end 3.821938 -3.643884)
			(stroke
				(width 0.1)
				(type default)
			)
			(layer "F.SilkS")
		)
		(fp_line
			(start 4.783582 -4.566158)
			(end 3.821938 -3.643884)
			(stroke
				(width 0.1)
				(type default)
			)
			(layer "F.SilkS")
		)
		(fp_line
			(start 4.795266 -0.133604)
			(end 4.877308 -0.15494)
			(stroke
				(width 0.1)
				(type default)
			)
			(layer "F.SilkS")
		)
		(fp_line
			(start 4.795266 -0.133604)
			(end 4.877308 -0.15494)
			(stroke
				(width 0.1)
				(type default)
			)
			(layer "F.SilkS")
		)
		(fp_line
			(start 4.795266 -0.133604)
			(end 5.08127 -0.408178)
			(stroke
				(width 0.1)
				(type default)
			)
			(layer "F.SilkS")
		)
		(fp_line
			(start 4.795266 -0.133604)
			(end 5.08127 -0.408178)
			(stroke
				(width 0.1)
				(type default)
			)
			(layer "F.SilkS")
		)
		(fp_line
			(start 4.806696 -4.530852)
			(end 3.83413 -3.59791)
			(stroke
				(width 0.1)
				(type default)
			)
			(layer "F.SilkS")
		)
		(fp_line
			(start 4.806696 -4.530852)
			(end 3.83413 -3.59791)
			(stroke
				(width 0.1)
				(type default)
			)
			(layer "F.SilkS")
		)
		(fp_line
			(start 4.82981 -4.495292)
			(end 3.846068 -3.551682)
			(stroke
				(width 0.1)
				(type default)
			)
			(layer "F.SilkS")
		)
		(fp_line
			(start 4.82981 -4.495292)
			(end 3.846068 -3.551682)
			(stroke
				(width 0.1)
				(type default)
			)
			(layer "F.SilkS")
		)
		(fp_line
			(start 4.851654 -4.458462)
			(end 3.858006 -3.505454)
			(stroke
				(width 0.1)
				(type default)
			)
			(layer "F.SilkS")
		)
		(fp_line
			(start 4.851654 -4.458462)
			(end 3.858006 -3.505454)
			(stroke
				(width 0.1)
				(type default)
			)
			(layer "F.SilkS")
		)
		(fp_line
			(start 4.870958 -4.419092)
			(end 3.870198 -3.459226)
			(stroke
				(width 0.1)
				(type default)
			)
			(layer "F.SilkS")
		)
		(fp_line
			(start 4.870958 -4.419092)
			(end 3.870198 -3.459226)
			(stroke
				(width 0.1)
				(type default)
			)
			(layer "F.SilkS")
		)
		(fp_line
			(start 4.877308 -0.15494)
			(end 4.95935 -0.175514)
			(stroke
				(width 0.1)
				(type default)
			)
			(layer "F.SilkS")
		)
		(fp_line
			(start 4.877308 -0.15494)
			(end 4.95935 -0.175514)
			(stroke
				(width 0.1)
				(type default)
			)
			(layer "F.SilkS")
		)
		(fp_line
			(start 4.877308 -0.15494)
			(end 5.115814 -0.383794)
			(stroke
				(width 0.1)
				(type default)
			)
			(layer "F.SilkS")
		)
		(fp_line
			(start 4.877308 -0.15494)
			(end 5.115814 -0.383794)
			(stroke
				(width 0.1)
				(type default)
			)
			(layer "F.SilkS")
		)
		(fp_line
			(start 4.889754 -4.379722)
			(end 3.878072 -3.409188)
			(stroke
				(width 0.1)
				(type default)
			)
			(layer "F.SilkS")
		)
		(fp_line
			(start 4.889754 -4.379722)
			(end 3.878072 -3.409188)
			(stroke
				(width 0.1)
				(type default)
			)
			(layer "F.SilkS")
		)
		(fp_line
			(start 4.908804 -4.340098)
			(end 3.88239 -3.355848)
			(stroke
				(width 0.1)
				(type default)
			)
			(layer "F.SilkS")
		)
		(fp_line
			(start 4.908804 -4.340098)
			(end 3.88239 -3.355848)
			(stroke
				(width 0.1)
				(type default)
			)
			(layer "F.SilkS")
		)
		(fp_line
			(start 4.927854 -4.300728)
			(end 3.886962 -3.302254)
			(stroke
				(width 0.1)
				(type default)
			)
			(layer "F.SilkS")
		)
		(fp_line
			(start 4.927854 -4.300728)
			(end 3.886962 -3.302254)
			(stroke
				(width 0.1)
				(type default)
			)
			(layer "F.SilkS")
		)
		(fp_line
			(start 4.946904 -4.261358)
			(end 3.891534 -3.248914)
			(stroke
				(width 0.1)
				(type default)
			)
			(layer "F.SilkS")
		)
		(fp_line
			(start 4.946904 -4.261358)
			(end 3.891534 -3.248914)
			(stroke
				(width 0.1)
				(type default)
			)
			(layer "F.SilkS")
		)
		(fp_line
			(start 4.95935 -0.175514)
			(end 5.041392 -0.196596)
			(stroke
				(width 0.1)
				(type default)
			)
			(layer "F.SilkS")
		)
		(fp_line
			(start 4.95935 -0.175514)
			(end 5.041392 -0.196596)
			(stroke
				(width 0.1)
				(type default)
			)
			(layer "F.SilkS")
		)
		(fp_line
			(start 4.95935 -0.175514)
			(end 5.150612 -0.359156)
			(stroke
				(width 0.1)
				(type default)
			)
			(layer "F.SilkS")
		)
		(fp_line
			(start 4.95935 -0.175514)
			(end 5.150612 -0.359156)
			(stroke
				(width 0.1)
				(type default)
			)
			(layer "F.SilkS")
		)
		(fp_line
			(start 4.965446 -4.221226)
			(end 3.895852 -3.19532)
			(stroke
				(width 0.1)
				(type default)
			)
			(layer "F.SilkS")
		)
		(fp_line
			(start 4.965446 -4.221226)
			(end 3.895852 -3.19532)
			(stroke
				(width 0.1)
				(type default)
			)
			(layer "F.SilkS")
		)
		(fp_line
			(start 4.980686 -4.1783)
			(end 3.900424 -3.14198)
			(stroke
				(width 0.1)
				(type default)
			)
			(layer "F.SilkS")
		)
		(fp_line
			(start 4.980686 -4.1783)
			(end 3.900424 -3.14198)
			(stroke
				(width 0.1)
				(type default)
			)
			(layer "F.SilkS")
		)
		(fp_line
			(start 4.995672 -4.13512)
			(end 3.899408 -3.083306)
			(stroke
				(width 0.1)
				(type default)
			)
			(layer "F.SilkS")
		)
		(fp_line
			(start 4.995672 -4.13512)
			(end 3.899408 -3.083306)
			(stroke
				(width 0.1)
				(type default)
			)
			(layer "F.SilkS")
		)
		(fp_line
			(start 5.011166 -4.09194)
			(end 3.894328 -3.020822)
			(stroke
				(width 0.1)
				(type default)
			)
			(layer "F.SilkS")
		)
		(fp_line
			(start 5.011166 -4.09194)
			(end 3.894328 -3.020822)
			(stroke
				(width 0.1)
				(type default)
			)
			(layer "F.SilkS")
		)
		(fp_line
			(start 5.026152 -4.04876)
			(end 3.889248 -2.958084)
			(stroke
				(width 0.1)
				(type default)
			)
			(layer "F.SilkS")
		)
		(fp_line
			(start 5.026152 -4.04876)
			(end 3.889248 -2.958084)
			(stroke
				(width 0.1)
				(type default)
			)
			(layer "F.SilkS")
		)
		(fp_line
			(start 5.041392 -4.00558)
			(end 3.884168 -2.8956)
			(stroke
				(width 0.1)
				(type default)
			)
			(layer "F.SilkS")
		)
		(fp_line
			(start 5.041392 -4.00558)
			(end 3.884168 -2.8956)
			(stroke
				(width 0.1)
				(type default)
			)
			(layer "F.SilkS")
		)
		(fp_line
			(start 5.041392 -0.196596)
			(end 5.12318 -0.217678)
			(stroke
				(width 0.1)
				(type default)
			)
			(layer "F.SilkS")
		)
		(fp_line
			(start 5.041392 -0.196596)
			(end 5.12318 -0.217678)
			(stroke
				(width 0.1)
				(type default)
			)
			(layer "F.SilkS")
		)
		(fp_line
			(start 5.041392 -0.196596)
			(end 5.185156 -0.334772)
			(stroke
				(width 0.1)
				(type default)
			)
			(layer "F.SilkS")
		)
		(fp_line
			(start 5.041392 -0.196596)
			(end 5.185156 -0.334772)
			(stroke
				(width 0.1)
				(type default)
			)
			(layer "F.SilkS")
		)
		(fp_line
			(start 5.0546 -3.960622)
			(end 3.879088 -2.832862)
			(stroke
				(width 0.1)
				(type default)
			)
			(layer "F.SilkS")
		)
		(fp_line
			(start 5.0546 -3.960622)
			(end 3.879088 -2.832862)
			(stroke
				(width 0.1)
				(type default)
			)
			(layer "F.SilkS")
		)
		(fp_line
			(start 5.066284 -3.91414)
			(end 3.863086 -2.75971)
			(stroke
				(width 0.1)
				(type default)
			)
			(layer "F.SilkS")
		)
		(fp_line
			(start 5.066284 -3.91414)
			(end 3.863086 -2.75971)
			(stroke
				(width 0.1)
				(type default)
			)
			(layer "F.SilkS")
		)
		(fp_line
			(start 5.078222 -3.867658)
			(end 3.843782 -2.68351)
			(stroke
				(width 0.1)
				(type default)
			)
			(layer "F.SilkS")
		)
		(fp_line
			(start 5.078222 -3.867658)
			(end 3.843782 -2.68351)
			(stroke
				(width 0.1)
				(type default)
			)
			(layer "F.SilkS")
		)
		(fp_line
			(start 5.089652 -3.821176)
			(end 3.824478 -2.607564)
			(stroke
				(width 0.1)
				(type default)
			)
			(layer "F.SilkS")
		)
		(fp_line
			(start 5.089652 -3.821176)
			(end 3.824478 -2.607564)
			(stroke
				(width 0.1)
				(type default)
			)
			(layer "F.SilkS")
		)
		(fp_line
			(start 5.101336 -3.774694)
			(end 3.802126 -2.528316)
			(stroke
				(width 0.1)
				(type default)
			)
			(layer "F.SilkS")
		)
		(fp_line
			(start 5.101336 -3.774694)
			(end 3.802126 -2.528316)
			(stroke
				(width 0.1)
				(type default)
			)
			(layer "F.SilkS")
		)
		(fp_line
			(start 5.110734 -3.72618)
			(end 3.756406 -2.426716)
			(stroke
				(width 0.1)
				(type default)
			)
			(layer "F.SilkS")
		)
		(fp_line
			(start 5.110734 -3.72618)
			(end 3.756406 -2.426716)
			(stroke
				(width 0.1)
				(type default)
			)
			(layer "F.SilkS")
		)
		(fp_line
			(start 5.11937 -3.676396)
			(end 3.710686 -2.32537)
			(stroke
				(width 0.1)
				(type default)
			)
			(layer "F.SilkS")
		)
		(fp_line
			(start 5.11937 -3.676396)
			(end 3.710686 -2.32537)
			(stroke
				(width 0.1)
				(type default)
			)
			(layer "F.SilkS")
		)
		(fp_line
			(start 5.12318 -0.217678)
			(end 5.205222 -0.238252)
			(stroke
				(width 0.1)
				(type default)
			)
			(layer "F.SilkS")
		)
		(fp_line
			(start 5.12318 -0.217678)
			(end 5.205222 -0.238252)
			(stroke
				(width 0.1)
				(type default)
			)
			(layer "F.SilkS")
		)
		(fp_line
			(start 5.12318 -0.217678)
			(end 5.219954 -0.310388)
			(stroke
				(width 0.1)
				(type default)
			)
			(layer "F.SilkS")
		)
		(fp_line
			(start 5.12318 -0.217678)
			(end 5.219954 -0.310388)
			(stroke
				(width 0.1)
				(type default)
			)
			(layer "F.SilkS")
		)
		(fp_line
			(start 5.127498 -3.626612)
			(end 3.618992 -2.17932)
			(stroke
				(width 0.1)
				(type default)
			)
			(layer "F.SilkS")
		)
		(fp_line
			(start 5.127498 -3.626612)
			(end 3.618992 -2.17932)
			(stroke
				(width 0.1)
				(type default)
			)
			(layer "F.SilkS")
		)
		(fp_line
			(start 5.13588 -3.576828)
			(end 2.15773 -0.719836)
			(stroke
				(width 0.1)
				(type default)
			)
			(layer "F.SilkS")
		)
		(fp_line
			(start 5.13588 -3.576828)
			(end 2.15773 -0.719836)
			(stroke
				(width 0.1)
				(type default)
			)
			(layer "F.SilkS")
		)
		(fp_line
			(start 5.205222 -0.238252)
			(end 5.254752 -0.28575)
			(stroke
				(width 0.1)
				(type default)
			)
			(layer "F.SilkS")
		)
		(fp_line
			(start 5.205222 -0.238252)
			(end 5.254752 -0.28575)
			(stroke
				(width 0.1)
				(type default)
			)
			(layer "F.SilkS")
		)
		(fp_line
			(start 5.287264 -0.259588)
			(end 5.205222 -0.238252)
			(stroke
				(width 0.1)
				(type default)
			)
			(layer "F.SilkS")
		)
		(fp_line
			(start 5.287264 -0.259588)
			(end 5.205222 -0.238252)
			(stroke
				(width 0.1)
				(type default)
			)
			(layer "F.SilkS")
		)
		(fp_line
			(start 5.287264 -0.259588)
			(end 5.289296 -0.261366)
			(stroke
				(width 0.1)
				(type default)
			)
			(layer "F.SilkS")
		)
		(fp_line
			(start 5.287264 -0.259588)
			(end 5.289296 -0.261366)
			(stroke
				(width 0.1)
				(type default)
			)
			(layer "F.SilkS")
		)
		(fp_line
			(start 5.507482 -2.281682)
			(end 6.825488 -3.54584)
			(stroke
				(width 0.1)
				(type default)
			)
			(layer "F.SilkS")
		)
		(fp_line
			(start 5.507482 -2.281682)
			(end 6.825488 -3.54584)
			(stroke
				(width 0.1)
				(type default)
			)
			(layer "F.SilkS")
		)
		(fp_line
			(start 5.50799 -2.224278)
			(end 6.81355 -3.476498)
			(stroke
				(width 0.1)
				(type default)
			)
			(layer "F.SilkS")
		)
		(fp_line
			(start 5.50799 -2.224278)
			(end 6.81355 -3.476498)
			(stroke
				(width 0.1)
				(type default)
			)
			(layer "F.SilkS")
		)
		(fp_line
			(start 5.508498 -2.167128)
			(end 6.801104 -3.407156)
			(stroke
				(width 0.1)
				(type default)
			)
			(layer "F.SilkS")
		)
		(fp_line
			(start 5.508498 -2.167128)
			(end 6.801104 -3.407156)
			(stroke
				(width 0.1)
				(type default)
			)
			(layer "F.SilkS")
		)
		(fp_line
			(start 5.508752 -2.109724)
			(end 6.788912 -3.337814)
			(stroke
				(width 0.1)
				(type default)
			)
			(layer "F.SilkS")
		)
		(fp_line
			(start 5.508752 -2.109724)
			(end 6.788912 -3.337814)
			(stroke
				(width 0.1)
				(type default)
			)
			(layer "F.SilkS")
		)
		(fp_line
			(start 5.50926 -2.052574)
			(end 6.776974 -3.268472)
			(stroke
				(width 0.1)
				(type default)
			)
			(layer "F.SilkS")
		)
		(fp_line
			(start 5.50926 -2.052574)
			(end 6.776974 -3.268472)
			(stroke
				(width 0.1)
				(type default)
			)
			(layer "F.SilkS")
		)
		(fp_line
			(start 5.509768 -1.99517)
			(end 6.764782 -3.19913)
			(stroke
				(width 0.1)
				(type default)
			)
			(layer "F.SilkS")
		)
		(fp_line
			(start 5.509768 -1.99517)
			(end 6.764782 -3.19913)
			(stroke
				(width 0.1)
				(type default)
			)
			(layer "F.SilkS")
		)
		(fp_line
			(start 5.510276 -1.937766)
			(end 6.75259 -3.129534)
			(stroke
				(width 0.1)
				(type default)
			)
			(layer "F.SilkS")
		)
		(fp_line
			(start 5.510276 -1.937766)
			(end 6.75259 -3.129534)
			(stroke
				(width 0.1)
				(type default)
			)
			(layer "F.SilkS")
		)
		(fp_line
			(start 5.518912 -1.88849)
			(end 6.740144 -3.060192)
			(stroke
				(width 0.1)
				(type default)
			)
			(layer "F.SilkS")
		)
		(fp_line
			(start 5.518912 -1.88849)
			(end 6.740144 -3.060192)
			(stroke
				(width 0.1)
				(type default)
			)
			(layer "F.SilkS")
		)
		(fp_line
			(start 5.527802 -1.839214)
			(end 6.728206 -2.99085)
			(stroke
				(width 0.1)
				(type default)
			)
			(layer "F.SilkS")
		)
		(fp_line
			(start 5.527802 -1.839214)
			(end 6.728206 -2.99085)
			(stroke
				(width 0.1)
				(type default)
			)
			(layer "F.SilkS")
		)
		(fp_line
			(start 5.536438 -1.789938)
			(end 6.716014 -2.921254)
			(stroke
				(width 0.1)
				(type default)
			)
			(layer "F.SilkS")
		)
		(fp_line
			(start 5.536438 -1.789938)
			(end 6.716014 -2.921254)
			(stroke
				(width 0.1)
				(type default)
			)
			(layer "F.SilkS")
		)
		(fp_line
			(start 5.545582 -1.740916)
			(end 6.703822 -2.852166)
			(stroke
				(width 0.1)
				(type default)
			)
			(layer "F.SilkS")
		)
		(fp_line
			(start 5.545582 -1.740916)
			(end 6.703822 -2.852166)
			(stroke
				(width 0.1)
				(type default)
			)
			(layer "F.SilkS")
		)
		(fp_line
			(start 5.554218 -1.69164)
			(end 6.695186 -2.786126)
			(stroke
				(width 0.1)
				(type default)
			)
			(layer "F.SilkS")
		)
		(fp_line
			(start 5.554218 -1.69164)
			(end 6.695186 -2.786126)
			(stroke
				(width 0.1)
				(type default)
			)
			(layer "F.SilkS")
		)
		(fp_line
			(start 5.563108 -1.642364)
			(end 6.68655 -2.720086)
			(stroke
				(width 0.1)
				(type default)
			)
			(layer "F.SilkS")
		)
		(fp_line
			(start 5.563108 -1.642364)
			(end 6.68655 -2.720086)
			(stroke
				(width 0.1)
				(type default)
			)
			(layer "F.SilkS")
		)
		(fp_line
			(start 5.573522 -1.594612)
			(end 6.678168 -2.6543)
			(stroke
				(width 0.1)
				(type default)
			)
			(layer "F.SilkS")
		)
		(fp_line
			(start 5.573522 -1.594612)
			(end 6.678168 -2.6543)
			(stroke
				(width 0.1)
				(type default)
			)
			(layer "F.SilkS")
		)
		(fp_line
			(start 5.58038 -2.870962)
			(end 5.568188 -2.801366)
			(stroke
				(width 0.1)
				(type default)
			)
			(layer "F.SilkS")
		)
		(fp_line
			(start 5.58038 -2.870962)
			(end 5.568188 -2.801366)
			(stroke
				(width 0.1)
				(type default)
			)
			(layer "F.SilkS")
		)
		(fp_line
			(start 5.591048 -1.553718)
			(end 6.669532 -2.58826)
			(stroke
				(width 0.1)
				(type default)
			)
			(layer "F.SilkS")
		)
		(fp_line
			(start 5.591048 -1.553718)
			(end 6.669532 -2.58826)
			(stroke
				(width 0.1)
				(type default)
			)
			(layer "F.SilkS")
		)
		(fp_line
			(start 5.592572 -2.940304)
			(end 5.58038 -2.870962)
			(stroke
				(width 0.1)
				(type default)
			)
			(layer "F.SilkS")
		)
		(fp_line
			(start 5.592572 -2.940304)
			(end 5.58038 -2.870962)
			(stroke
				(width 0.1)
				(type default)
			)
			(layer "F.SilkS")
		)
		(fp_line
			(start 5.604764 -3.009646)
			(end 5.592572 -2.940304)
			(stroke
				(width 0.1)
				(type default)
			)
			(layer "F.SilkS")
		)
		(fp_line
			(start 5.604764 -3.009646)
			(end 5.592572 -2.940304)
			(stroke
				(width 0.1)
				(type default)
			)
			(layer "F.SilkS")
		)
		(fp_line
			(start 5.60832 -1.51257)
			(end 6.669024 -2.530094)
			(stroke
				(width 0.1)
				(type default)
			)
			(layer "F.SilkS")
		)
		(fp_line
			(start 5.60832 -1.51257)
			(end 6.669024 -2.530094)
			(stroke
				(width 0.1)
				(type default)
			)
			(layer "F.SilkS")
		)
		(fp_line
			(start 5.616956 -3.079242)
			(end 5.604764 -3.009646)
			(stroke
				(width 0.1)
				(type default)
			)
			(layer "F.SilkS")
		)
		(fp_line
			(start 5.616956 -3.079242)
			(end 5.604764 -3.009646)
			(stroke
				(width 0.1)
				(type default)
			)
			(layer "F.SilkS")
		)
		(fp_line
			(start 5.625846 -1.471676)
			(end 6.668516 -2.471928)
			(stroke
				(width 0.1)
				(type default)
			)
			(layer "F.SilkS")
		)
		(fp_line
			(start 5.625846 -1.471676)
			(end 6.668516 -2.471928)
			(stroke
				(width 0.1)
				(type default)
			)
			(layer "F.SilkS")
		)
		(fp_line
			(start 5.629148 -3.148584)
			(end 5.616956 -3.079242)
			(stroke
				(width 0.1)
				(type default)
			)
			(layer "F.SilkS")
		)
		(fp_line
			(start 5.629148 -3.148584)
			(end 5.616956 -3.079242)
			(stroke
				(width 0.1)
				(type default)
			)
			(layer "F.SilkS")
		)
		(fp_line
			(start 5.64134 -3.217926)
			(end 5.629148 -3.148584)
			(stroke
				(width 0.1)
				(type default)
			)
			(layer "F.SilkS")
		)
		(fp_line
			(start 5.64134 -3.217926)
			(end 5.629148 -3.148584)
			(stroke
				(width 0.1)
				(type default)
			)
			(layer "F.SilkS")
		)
		(fp_line
			(start 5.643118 -1.430528)
			(end 6.668008 -2.413762)
			(stroke
				(width 0.1)
				(type default)
			)
			(layer "F.SilkS")
		)
		(fp_line
			(start 5.643118 -1.430528)
			(end 6.668008 -2.413762)
			(stroke
				(width 0.1)
				(type default)
			)
			(layer "F.SilkS")
		)
		(fp_line
			(start 5.653532 -3.287268)
			(end 5.64134 -3.217926)
			(stroke
				(width 0.1)
				(type default)
			)
			(layer "F.SilkS")
		)
		(fp_line
			(start 5.653532 -3.287268)
			(end 5.64134 -3.217926)
			(stroke
				(width 0.1)
				(type default)
			)
			(layer "F.SilkS")
		)
		(fp_line
			(start 5.660644 -1.389634)
			(end 6.67004 -2.357882)
			(stroke
				(width 0.1)
				(type default)
			)
			(layer "F.SilkS")
		)
		(fp_line
			(start 5.660644 -1.389634)
			(end 6.67004 -2.357882)
			(stroke
				(width 0.1)
				(type default)
			)
			(layer "F.SilkS")
		)
		(fp_line
			(start 5.665724 -3.35661)
			(end 5.653532 -3.287268)
			(stroke
				(width 0.1)
				(type default)
			)
			(layer "F.SilkS")
		)
		(fp_line
			(start 5.665724 -3.35661)
			(end 5.653532 -3.287268)
			(stroke
				(width 0.1)
				(type default)
			)
			(layer "F.SilkS")
		)
		(fp_line
			(start 5.677662 -3.425952)
			(end 5.665724 -3.35661)
			(stroke
				(width 0.1)
				(type default)
			)
			(layer "F.SilkS")
		)
		(fp_line
			(start 5.677662 -3.425952)
			(end 5.665724 -3.35661)
			(stroke
				(width 0.1)
				(type default)
			)
			(layer "F.SilkS")
		)
		(fp_line
			(start 5.677916 -1.34874)
			(end 6.678168 -2.308352)
			(stroke
				(width 0.1)
				(type default)
			)
			(layer "F.SilkS")
		)
		(fp_line
			(start 5.677916 -1.34874)
			(end 6.678168 -2.308352)
			(stroke
				(width 0.1)
				(type default)
			)
			(layer "F.SilkS")
		)
		(fp_line
			(start 5.690108 -3.495548)
			(end 5.677662 -3.425952)
			(stroke
				(width 0.1)
				(type default)
			)
			(layer "F.SilkS")
		)
		(fp_line
			(start 5.690108 -3.495548)
			(end 5.677662 -3.425952)
			(stroke
				(width 0.1)
				(type default)
			)
			(layer "F.SilkS")
		)
		(fp_line
			(start 5.697982 -1.310132)
			(end 6.68655 -2.258568)
			(stroke
				(width 0.1)
				(type default)
			)
			(layer "F.SilkS")
		)
		(fp_line
			(start 5.697982 -1.310132)
			(end 6.68655 -2.258568)
			(stroke
				(width 0.1)
				(type default)
			)
			(layer "F.SilkS")
		)
		(fp_line
			(start 5.7023 -3.56489)
			(end 5.690108 -3.495548)
			(stroke
				(width 0.1)
				(type default)
			)
			(layer "F.SilkS")
		)
		(fp_line
			(start 5.7023 -3.56489)
			(end 5.690108 -3.495548)
			(stroke
				(width 0.1)
				(type default)
			)
			(layer "F.SilkS")
		)
		(fp_line
			(start 5.714238 -3.634232)
			(end 5.7023 -3.56489)
			(stroke
				(width 0.1)
				(type default)
			)
			(layer "F.SilkS")
		)
		(fp_line
			(start 5.714238 -3.634232)
			(end 5.7023 -3.56489)
			(stroke
				(width 0.1)
				(type default)
			)
			(layer "F.SilkS")
		)
		(fp_line
			(start 5.724398 -1.27762)
			(end 6.694932 -2.20853)
			(stroke
				(width 0.1)
				(type default)
			)
			(layer "F.SilkS")
		)
		(fp_line
			(start 5.724398 -1.27762)
			(end 6.694932 -2.20853)
			(stroke
				(width 0.1)
				(type default)
			)
			(layer "F.SilkS")
		)
		(fp_line
			(start 5.72643 -3.703828)
			(end 5.714238 -3.634232)
			(stroke
				(width 0.1)
				(type default)
			)
			(layer "F.SilkS")
		)
		(fp_line
			(start 5.72643 -3.703828)
			(end 5.714238 -3.634232)
			(stroke
				(width 0.1)
				(type default)
			)
			(layer "F.SilkS")
		)
		(fp_line
			(start 5.738876 -3.772916)
			(end 5.72643 -3.703828)
			(stroke
				(width 0.1)
				(type default)
			)
			(layer "F.SilkS")
		)
		(fp_line
			(start 5.738876 -3.772916)
			(end 5.72643 -3.703828)
			(stroke
				(width 0.1)
				(type default)
			)
			(layer "F.SilkS")
		)
		(fp_line
			(start 5.750306 -1.244854)
			(end 6.710934 -2.166366)
			(stroke
				(width 0.1)
				(type default)
			)
			(layer "F.SilkS")
		)
		(fp_line
			(start 5.750306 -1.244854)
			(end 6.710934 -2.166366)
			(stroke
				(width 0.1)
				(type default)
			)
			(layer "F.SilkS")
		)
		(fp_line
			(start 5.751068 -3.842512)
			(end 5.738876 -3.772916)
			(stroke
				(width 0.1)
				(type default)
			)
			(layer "F.SilkS")
		)
		(fp_line
			(start 5.751068 -3.842512)
			(end 5.738876 -3.772916)
			(stroke
				(width 0.1)
				(type default)
			)
			(layer "F.SilkS")
		)
		(fp_line
			(start 5.763006 -3.911854)
			(end 5.751068 -3.842512)
			(stroke
				(width 0.1)
				(type default)
			)
			(layer "F.SilkS")
		)
		(fp_line
			(start 5.763006 -3.911854)
			(end 5.751068 -3.842512)
			(stroke
				(width 0.1)
				(type default)
			)
			(layer "F.SilkS")
		)
		(fp_line
			(start 5.775198 -3.98145)
			(end 5.763006 -3.911854)
			(stroke
				(width 0.1)
				(type default)
			)
			(layer "F.SilkS")
		)
		(fp_line
			(start 5.775198 -3.98145)
			(end 5.763006 -3.911854)
			(stroke
				(width 0.1)
				(type default)
			)
			(layer "F.SilkS")
		)
		(fp_line
			(start 5.776468 -1.212342)
			(end 6.728714 -2.125726)
			(stroke
				(width 0.1)
				(type default)
			)
			(layer "F.SilkS")
		)
		(fp_line
			(start 5.776468 -1.212342)
			(end 6.728714 -2.125726)
			(stroke
				(width 0.1)
				(type default)
			)
			(layer "F.SilkS")
		)
		(fp_line
			(start 5.78739 -4.050538)
			(end 5.775198 -3.98145)
			(stroke
				(width 0.1)
				(type default)
			)
			(layer "F.SilkS")
		)
		(fp_line
			(start 5.78739 -4.050538)
			(end 5.775198 -3.98145)
			(stroke
				(width 0.1)
				(type default)
			)
			(layer "F.SilkS")
		)
		(fp_line
			(start 5.799582 -4.11988)
			(end 5.78739 -4.050538)
			(stroke
				(width 0.1)
				(type default)
			)
			(layer "F.SilkS")
		)
		(fp_line
			(start 5.799582 -4.11988)
			(end 5.78739 -4.050538)
			(stroke
				(width 0.1)
				(type default)
			)
			(layer "F.SilkS")
		)
		(fp_line
			(start 5.80263 -1.179576)
			(end 6.746494 -2.084832)
			(stroke
				(width 0.1)
				(type default)
			)
			(layer "F.SilkS")
		)
		(fp_line
			(start 5.80263 -1.179576)
			(end 6.746494 -2.084832)
			(stroke
				(width 0.1)
				(type default)
			)
			(layer "F.SilkS")
		)
		(fp_line
			(start 5.811774 -4.189476)
			(end 5.799582 -4.11988)
			(stroke
				(width 0.1)
				(type default)
			)
			(layer "F.SilkS")
		)
		(fp_line
			(start 5.811774 -4.189476)
			(end 5.799582 -4.11988)
			(stroke
				(width 0.1)
				(type default)
			)
			(layer "F.SilkS")
		)
		(fp_line
			(start 5.823966 -4.258818)
			(end 5.811774 -4.189476)
			(stroke
				(width 0.1)
				(type default)
			)
			(layer "F.SilkS")
		)
		(fp_line
			(start 5.823966 -4.258818)
			(end 5.811774 -4.189476)
			(stroke
				(width 0.1)
				(type default)
			)
			(layer "F.SilkS")
		)
		(fp_line
			(start 5.828792 -1.147064)
			(end 6.769608 -2.049272)
			(stroke
				(width 0.1)
				(type default)
			)
			(layer "F.SilkS")
		)
		(fp_line
			(start 5.828792 -1.147064)
			(end 6.769608 -2.049272)
			(stroke
				(width 0.1)
				(type default)
			)
			(layer "F.SilkS")
		)
		(fp_line
			(start 5.836158 -4.328414)
			(end 5.823966 -4.258818)
			(stroke
				(width 0.1)
				(type default)
			)
			(layer "F.SilkS")
		)
		(fp_line
			(start 5.836158 -4.328414)
			(end 5.823966 -4.258818)
			(stroke
				(width 0.1)
				(type default)
			)
			(layer "F.SilkS")
		)
		(fp_line
			(start 5.84835 -4.397502)
			(end 5.836158 -4.328414)
			(stroke
				(width 0.1)
				(type default)
			)
			(layer "F.SilkS")
		)
		(fp_line
			(start 5.84835 -4.397502)
			(end 5.836158 -4.328414)
			(stroke
				(width 0.1)
				(type default)
			)
			(layer "F.SilkS")
		)
		(fp_line
			(start 5.854954 -1.114298)
			(end 6.79704 -2.018284)
			(stroke
				(width 0.1)
				(type default)
			)
			(layer "F.SilkS")
		)
		(fp_line
			(start 5.854954 -1.114298)
			(end 6.79704 -2.018284)
			(stroke
				(width 0.1)
				(type default)
			)
			(layer "F.SilkS")
		)
		(fp_line
			(start 5.860542 -4.467098)
			(end 5.84835 -4.397502)
			(stroke
				(width 0.1)
				(type default)
			)
			(layer "F.SilkS")
		)
		(fp_line
			(start 5.860542 -4.467098)
			(end 5.84835 -4.397502)
			(stroke
				(width 0.1)
				(type default)
			)
			(layer "F.SilkS")
		)
		(fp_line
			(start 5.872734 -4.53644)
			(end 5.860542 -4.467098)
			(stroke
				(width 0.1)
				(type default)
			)
			(layer "F.SilkS")
		)
		(fp_line
			(start 5.872734 -4.53644)
			(end 5.860542 -4.467098)
			(stroke
				(width 0.1)
				(type default)
			)
			(layer "F.SilkS")
		)
		(fp_line
			(start 5.872734 -4.53644)
			(end 5.884926 -4.605782)
			(stroke
				(width 0.1)
				(type default)
			)
			(layer "F.SilkS")
		)
		(fp_line
			(start 5.872734 -4.53644)
			(end 5.884926 -4.605782)
			(stroke
				(width 0.1)
				(type default)
			)
			(layer "F.SilkS")
		)
		(fp_line
			(start 5.884926 -4.605782)
			(end 5.897118 -4.675124)
			(stroke
				(width 0.1)
				(type default)
			)
			(layer "F.SilkS")
		)
		(fp_line
			(start 5.884926 -4.605782)
			(end 5.897118 -4.675124)
			(stroke
				(width 0.1)
				(type default)
			)
			(layer "F.SilkS")
		)
		(fp_line
			(start 5.884926 -1.085342)
			(end 6.824726 -1.987042)
			(stroke
				(width 0.1)
				(type default)
			)
			(layer "F.SilkS")
		)
		(fp_line
			(start 5.884926 -1.085342)
			(end 6.824726 -1.987042)
			(stroke
				(width 0.1)
				(type default)
			)
			(layer "F.SilkS")
		)
		(fp_line
			(start 5.897118 -4.675124)
			(end 5.90931 -4.74472)
			(stroke
				(width 0.1)
				(type default)
			)
			(layer "F.SilkS")
		)
		(fp_line
			(start 5.897118 -4.675124)
			(end 5.90931 -4.74472)
			(stroke
				(width 0.1)
				(type default)
			)
			(layer "F.SilkS")
		)
		(fp_line
			(start 5.90931 -4.74472)
			(end 5.921502 -4.814062)
			(stroke
				(width 0.1)
				(type default)
			)
			(layer "F.SilkS")
		)
		(fp_line
			(start 5.90931 -4.74472)
			(end 5.921502 -4.814062)
			(stroke
				(width 0.1)
				(type default)
			)
			(layer "F.SilkS")
		)
		(fp_line
			(start 5.919978 -1.061212)
			(end 6.856222 -1.95961)
			(stroke
				(width 0.1)
				(type default)
			)
			(layer "F.SilkS")
		)
		(fp_line
			(start 5.919978 -1.061212)
			(end 6.856222 -1.95961)
			(stroke
				(width 0.1)
				(type default)
			)
			(layer "F.SilkS")
		)
		(fp_line
			(start 5.921502 -4.814062)
			(end 5.933694 -4.883404)
			(stroke
				(width 0.1)
				(type default)
			)
			(layer "F.SilkS")
		)
		(fp_line
			(start 5.921502 -4.814062)
			(end 5.933694 -4.883404)
			(stroke
				(width 0.1)
				(type default)
			)
			(layer "F.SilkS")
		)
		(fp_line
			(start 5.933694 -4.883404)
			(end 5.945886 -4.952746)
			(stroke
				(width 0.1)
				(type default)
			)
			(layer "F.SilkS")
		)
		(fp_line
			(start 5.933694 -4.883404)
			(end 5.945886 -4.952746)
			(stroke
				(width 0.1)
				(type default)
			)
			(layer "F.SilkS")
		)
		(fp_line
			(start 5.945886 -4.952746)
			(end 5.958078 -5.022088)
			(stroke
				(width 0.1)
				(type default)
			)
			(layer "F.SilkS")
		)
		(fp_line
			(start 5.945886 -4.952746)
			(end 5.958078 -5.022088)
			(stroke
				(width 0.1)
				(type default)
			)
			(layer "F.SilkS")
		)
		(fp_line
			(start 5.955284 -1.03759)
			(end 6.894068 -1.93802)
			(stroke
				(width 0.1)
				(type default)
			)
			(layer "F.SilkS")
		)
		(fp_line
			(start 5.955284 -1.03759)
			(end 6.894068 -1.93802)
			(stroke
				(width 0.1)
				(type default)
			)
			(layer "F.SilkS")
		)
		(fp_line
			(start 5.958078 -5.022088)
			(end 5.97027 -5.091684)
			(stroke
				(width 0.1)
				(type default)
			)
			(layer "F.SilkS")
		)
		(fp_line
			(start 5.958078 -5.022088)
			(end 5.97027 -5.091684)
			(stroke
				(width 0.1)
				(type default)
			)
			(layer "F.SilkS")
		)
		(fp_line
			(start 5.97027 -5.091684)
			(end 5.982208 -5.161026)
			(stroke
				(width 0.1)
				(type default)
			)
			(layer "F.SilkS")
		)
		(fp_line
			(start 5.97027 -5.091684)
			(end 5.982208 -5.161026)
			(stroke
				(width 0.1)
				(type default)
			)
			(layer "F.SilkS")
		)
		(fp_line
			(start 5.98424 -5.171694)
			(end 5.982208 -5.161026)
			(stroke
				(width 0.1)
				(type default)
			)
			(layer "F.SilkS")
		)
		(fp_line
			(start 5.98424 -5.171694)
			(end 5.982208 -5.161026)
			(stroke
				(width 0.1)
				(type default)
			)
			(layer "F.SilkS")
		)
		(fp_line
			(start 5.99059 -1.013714)
			(end 6.93166 -1.91643)
			(stroke
				(width 0.1)
				(type default)
			)
			(layer "F.SilkS")
		)
		(fp_line
			(start 5.99059 -1.013714)
			(end 6.93166 -1.91643)
			(stroke
				(width 0.1)
				(type default)
			)
			(layer "F.SilkS")
		)
		(fp_line
			(start 5.993638 -5.171694)
			(end 5.982208 -5.161026)
			(stroke
				(width 0.1)
				(type default)
			)
			(layer "F.SilkS")
		)
		(fp_line
			(start 5.993638 -5.171694)
			(end 5.982208 -5.161026)
			(stroke
				(width 0.1)
				(type default)
			)
			(layer "F.SilkS")
		)
		(fp_line
			(start 5.993638 -5.171694)
			(end 5.98424 -5.171694)
			(stroke
				(width 0.1)
				(type default)
			)
			(layer "F.SilkS")
		)
		(fp_line
			(start 5.993638 -5.171694)
			(end 5.98424 -5.171694)
			(stroke
				(width 0.1)
				(type default)
			)
			(layer "F.SilkS")
		)
		(fp_line
			(start 6.025642 -0.989584)
			(end 6.973062 -1.898396)
			(stroke
				(width 0.1)
				(type default)
			)
			(layer "F.SilkS")
		)
		(fp_line
			(start 6.025642 -0.989584)
			(end 6.973062 -1.898396)
			(stroke
				(width 0.1)
				(type default)
			)
			(layer "F.SilkS")
		)
		(fp_line
			(start 6.053582 -5.171694)
			(end 5.97027 -5.091684)
			(stroke
				(width 0.1)
				(type default)
			)
			(layer "F.SilkS")
		)
		(fp_line
			(start 6.053582 -5.171694)
			(end 5.97027 -5.091684)
			(stroke
				(width 0.1)
				(type default)
			)
			(layer "F.SilkS")
		)
		(fp_line
			(start 6.053582 -5.171694)
			(end 5.993638 -5.171694)
			(stroke
				(width 0.1)
				(type default)
			)
			(layer "F.SilkS")
		)
		(fp_line
			(start 6.053582 -5.171694)
			(end 5.993638 -5.171694)
			(stroke
				(width 0.1)
				(type default)
			)
			(layer "F.SilkS")
		)
		(fp_line
			(start 6.060948 -0.965962)
			(end 7.020306 -1.88595)
			(stroke
				(width 0.1)
				(type default)
			)
			(layer "F.SilkS")
		)
		(fp_line
			(start 6.060948 -0.965962)
			(end 7.020306 -1.88595)
			(stroke
				(width 0.1)
				(type default)
			)
			(layer "F.SilkS")
		)
		(fp_line
			(start 6.096254 -0.942086)
			(end 7.06755 -1.873504)
			(stroke
				(width 0.1)
				(type default)
			)
			(layer "F.SilkS")
		)
		(fp_line
			(start 6.096254 -0.942086)
			(end 7.06755 -1.873504)
			(stroke
				(width 0.1)
				(type default)
			)
			(layer "F.SilkS")
		)
		(fp_line
			(start 6.11378 -5.171694)
			(end 5.958078 -5.022088)
			(stroke
				(width 0.1)
				(type default)
			)
			(layer "F.SilkS")
		)
		(fp_line
			(start 6.11378 -5.171694)
			(end 5.958078 -5.022088)
			(stroke
				(width 0.1)
				(type default)
			)
			(layer "F.SilkS")
		)
		(fp_line
			(start 6.11378 -5.171694)
			(end 6.053582 -5.171694)
			(stroke
				(width 0.1)
				(type default)
			)
			(layer "F.SilkS")
		)
		(fp_line
			(start 6.11378 -5.171694)
			(end 6.053582 -5.171694)
			(stroke
				(width 0.1)
				(type default)
			)
			(layer "F.SilkS")
		)
		(fp_line
			(start 6.136132 -0.922528)
			(end 7.118604 -1.865122)
			(stroke
				(width 0.1)
				(type default)
			)
			(layer "F.SilkS")
		)
		(fp_line
			(start 6.136132 -0.922528)
			(end 7.118604 -1.865122)
			(stroke
				(width 0.1)
				(type default)
			)
			(layer "F.SilkS")
		)
		(fp_line
			(start 6.173978 -5.171694)
			(end 5.945886 -4.952746)
			(stroke
				(width 0.1)
				(type default)
			)
			(layer "F.SilkS")
		)
		(fp_line
			(start 6.173978 -5.171694)
			(end 5.945886 -4.952746)
			(stroke
				(width 0.1)
				(type default)
			)
			(layer "F.SilkS")
		)
		(fp_line
			(start 6.173978 -5.171694)
			(end 6.11378 -5.171694)
			(stroke
				(width 0.1)
				(type default)
			)
			(layer "F.SilkS")
		)
		(fp_line
			(start 6.173978 -5.171694)
			(end 6.11378 -5.171694)
			(stroke
				(width 0.1)
				(type default)
			)
			(layer "F.SilkS")
		)
		(fp_line
			(start 6.180836 -0.907796)
			(end 7.174738 -1.861058)
			(stroke
				(width 0.1)
				(type default)
			)
			(layer "F.SilkS")
		)
		(fp_line
			(start 6.180836 -0.907796)
			(end 7.174738 -1.861058)
			(stroke
				(width 0.1)
				(type default)
			)
			(layer "F.SilkS")
		)
		(fp_line
			(start 6.225794 -0.89281)
			(end 7.231126 -1.857248)
			(stroke
				(width 0.1)
				(type default)
			)
			(layer "F.SilkS")
		)
		(fp_line
			(start 6.225794 -0.89281)
			(end 7.231126 -1.857248)
			(stroke
				(width 0.1)
				(type default)
			)
			(layer "F.SilkS")
		)
		(fp_line
			(start 6.234176 -5.171694)
			(end 5.933694 -4.883404)
			(stroke
				(width 0.1)
				(type default)
			)
			(layer "F.SilkS")
		)
		(fp_line
			(start 6.234176 -5.171694)
			(end 5.933694 -4.883404)
			(stroke
				(width 0.1)
				(type default)
			)
			(layer "F.SilkS")
		)
		(fp_line
			(start 6.234176 -5.171694)
			(end 6.173978 -5.171694)
			(stroke
				(width 0.1)
				(type default)
			)
			(layer "F.SilkS")
		)
		(fp_line
			(start 6.234176 -5.171694)
			(end 6.173978 -5.171694)
			(stroke
				(width 0.1)
				(type default)
			)
			(layer "F.SilkS")
		)
		(fp_line
			(start 6.270752 -0.878332)
			(end 7.291832 -1.857756)
			(stroke
				(width 0.1)
				(type default)
			)
			(layer "F.SilkS")
		)
		(fp_line
			(start 6.270752 -0.878332)
			(end 7.291832 -1.857756)
			(stroke
				(width 0.1)
				(type default)
			)
			(layer "F.SilkS")
		)
		(fp_line
			(start 6.294374 -5.171694)
			(end 5.921502 -4.814062)
			(stroke
				(width 0.1)
				(type default)
			)
			(layer "F.SilkS")
		)
		(fp_line
			(start 6.294374 -5.171694)
			(end 5.921502 -4.814062)
			(stroke
				(width 0.1)
				(type default)
			)
			(layer "F.SilkS")
		)
		(fp_line
			(start 6.294374 -5.171694)
			(end 6.234176 -5.171694)
			(stroke
				(width 0.1)
				(type default)
			)
			(layer "F.SilkS")
		)
		(fp_line
			(start 6.294374 -5.171694)
			(end 6.234176 -5.171694)
			(stroke
				(width 0.1)
				(type default)
			)
			(layer "F.SilkS")
		)
		(fp_line
			(start 6.315456 -0.8636)
			(end 7.356348 -1.862074)
			(stroke
				(width 0.1)
				(type default)
			)
			(layer "F.SilkS")
		)
		(fp_line
			(start 6.315456 -0.8636)
			(end 7.356348 -1.862074)
			(stroke
				(width 0.1)
				(type default)
			)
			(layer "F.SilkS")
		)
		(fp_line
			(start 6.354318 -5.171694)
			(end 5.90931 -4.74472)
			(stroke
				(width 0.1)
				(type default)
			)
			(layer "F.SilkS")
		)
		(fp_line
			(start 6.354318 -5.171694)
			(end 5.90931 -4.74472)
			(stroke
				(width 0.1)
				(type default)
			)
			(layer "F.SilkS")
		)
		(fp_line
			(start 6.354318 -5.171694)
			(end 6.294374 -5.171694)
			(stroke
				(width 0.1)
				(type default)
			)
			(layer "F.SilkS")
		)
		(fp_line
			(start 6.354318 -5.171694)
			(end 6.294374 -5.171694)
			(stroke
				(width 0.1)
				(type default)
			)
			(layer "F.SilkS")
		)
		(fp_line
			(start 6.36016 -0.848868)
			(end 7.421118 -1.866392)
			(stroke
				(width 0.1)
				(type default)
			)
			(layer "F.SilkS")
		)
		(fp_line
			(start 6.36016 -0.848868)
			(end 7.421118 -1.866392)
			(stroke
				(width 0.1)
				(type default)
			)
			(layer "F.SilkS")
		)
		(fp_line
			(start 6.405118 -0.833882)
			(end 7.500366 -1.884934)
			(stroke
				(width 0.1)
				(type default)
			)
			(layer "F.SilkS")
		)
		(fp_line
			(start 6.405118 -0.833882)
			(end 7.500366 -1.884934)
			(stroke
				(width 0.1)
				(type default)
			)
			(layer "F.SilkS")
		)
		(fp_line
			(start 6.41477 -5.171694)
			(end 5.897118 -4.675124)
			(stroke
				(width 0.1)
				(type default)
			)
			(layer "F.SilkS")
		)
		(fp_line
			(start 6.41477 -5.171694)
			(end 5.897118 -4.675124)
			(stroke
				(width 0.1)
				(type default)
			)
			(layer "F.SilkS")
		)
		(fp_line
			(start 6.41477 -5.171694)
			(end 6.354318 -5.171694)
			(stroke
				(width 0.1)
				(type default)
			)
			(layer "F.SilkS")
		)
		(fp_line
			(start 6.41477 -5.171694)
			(end 6.354318 -5.171694)
			(stroke
				(width 0.1)
				(type default)
			)
			(layer "F.SilkS")
		)
		(fp_line
			(start 6.455664 -0.824738)
			(end 7.582662 -1.906016)
			(stroke
				(width 0.1)
				(type default)
			)
			(layer "F.SilkS")
		)
		(fp_line
			(start 6.455664 -0.824738)
			(end 7.582662 -1.906016)
			(stroke
				(width 0.1)
				(type default)
			)
			(layer "F.SilkS")
		)
		(fp_line
			(start 6.474714 -5.171694)
			(end 5.884926 -4.605782)
			(stroke
				(width 0.1)
				(type default)
			)
			(layer "F.SilkS")
		)
		(fp_line
			(start 6.474714 -5.171694)
			(end 5.884926 -4.605782)
			(stroke
				(width 0.1)
				(type default)
			)
			(layer "F.SilkS")
		)
		(fp_line
			(start 6.474714 -5.171694)
			(end 6.41477 -5.171694)
			(stroke
				(width 0.1)
				(type default)
			)
			(layer "F.SilkS")
		)
		(fp_line
			(start 6.474714 -5.171694)
			(end 6.41477 -5.171694)
			(stroke
				(width 0.1)
				(type default)
			)
			(layer "F.SilkS")
		)
		(fp_line
			(start 6.510528 -0.819912)
			(end 7.699756 -1.96088)
			(stroke
				(width 0.1)
				(type default)
			)
			(layer "F.SilkS")
		)
		(fp_line
			(start 6.510528 -0.819912)
			(end 7.699756 -1.96088)
			(stroke
				(width 0.1)
				(type default)
			)
			(layer "F.SilkS")
		)
		(fp_line
			(start 6.534912 -5.171694)
			(end 5.872734 -4.53644)
			(stroke
				(width 0.1)
				(type default)
			)
			(layer "F.SilkS")
		)
		(fp_line
			(start 6.534912 -5.171694)
			(end 5.872734 -4.53644)
			(stroke
				(width 0.1)
				(type default)
			)
			(layer "F.SilkS")
		)
		(fp_line
			(start 6.534912 -5.171694)
			(end 6.474714 -5.171694)
			(stroke
				(width 0.1)
				(type default)
			)
			(layer "F.SilkS")
		)
		(fp_line
			(start 6.534912 -5.171694)
			(end 6.474714 -5.171694)
			(stroke
				(width 0.1)
				(type default)
			)
			(layer "F.SilkS")
		)
		(fp_line
			(start 6.59511 -5.171694)
			(end 5.860542 -4.467098)
			(stroke
				(width 0.1)
				(type default)
			)
			(layer "F.SilkS")
		)
		(fp_line
			(start 6.59511 -5.171694)
			(end 5.860542 -4.467098)
			(stroke
				(width 0.1)
				(type default)
			)
			(layer "F.SilkS")
		)
		(fp_line
			(start 6.59511 -5.171694)
			(end 6.534912 -5.171694)
			(stroke
				(width 0.1)
				(type default)
			)
			(layer "F.SilkS")
		)
		(fp_line
			(start 6.59511 -5.171694)
			(end 6.534912 -5.171694)
			(stroke
				(width 0.1)
				(type default)
			)
			(layer "F.SilkS")
		)
		(fp_line
			(start 6.620256 -0.809498)
			(end 9.404096 -3.480054)
			(stroke
				(width 0.1)
				(type default)
			)
			(layer "F.SilkS")
		)
		(fp_line
			(start 6.620256 -0.809498)
			(end 9.404096 -3.480054)
			(stroke
				(width 0.1)
				(type default)
			)
			(layer "F.SilkS")
		)
		(fp_line
			(start 6.655308 -5.171694)
			(end 5.84835 -4.397502)
			(stroke
				(width 0.1)
				(type default)
			)
			(layer "F.SilkS")
		)
		(fp_line
			(start 6.655308 -5.171694)
			(end 5.84835 -4.397502)
			(stroke
				(width 0.1)
				(type default)
			)
			(layer "F.SilkS")
		)
		(fp_line
			(start 6.655308 -5.171694)
			(end 6.59511 -5.171694)
			(stroke
				(width 0.1)
				(type default)
			)
			(layer "F.SilkS")
		)
		(fp_line
			(start 6.655308 -5.171694)
			(end 6.59511 -5.171694)
			(stroke
				(width 0.1)
				(type default)
			)
			(layer "F.SilkS")
		)
		(fp_line
			(start 6.67512 -0.804672)
			(end 9.391904 -3.410712)
			(stroke
				(width 0.1)
				(type default)
			)
			(layer "F.SilkS")
		)
		(fp_line
			(start 6.67512 -0.804672)
			(end 9.391904 -3.410712)
			(stroke
				(width 0.1)
				(type default)
			)
			(layer "F.SilkS")
		)
		(fp_line
			(start 6.703822 -2.852166)
			(end 6.716014 -2.921254)
			(stroke
				(width 0.1)
				(type default)
			)
			(layer "F.SilkS")
		)
		(fp_line
			(start 6.703822 -2.852166)
			(end 6.716014 -2.921254)
			(stroke
				(width 0.1)
				(type default)
			)
			(layer "F.SilkS")
		)
		(fp_line
			(start 6.715506 -5.171694)
			(end 5.836158 -4.328414)
			(stroke
				(width 0.1)
				(type default)
			)
			(layer "F.SilkS")
		)
		(fp_line
			(start 6.715506 -5.171694)
			(end 5.836158 -4.328414)
			(stroke
				(width 0.1)
				(type default)
			)
			(layer "F.SilkS")
		)
		(fp_line
			(start 6.715506 -5.171694)
			(end 6.655308 -5.171694)
			(stroke
				(width 0.1)
				(type default)
			)
			(layer "F.SilkS")
		)
		(fp_line
			(start 6.715506 -5.171694)
			(end 6.655308 -5.171694)
			(stroke
				(width 0.1)
				(type default)
			)
			(layer "F.SilkS")
		)
		(fp_line
			(start 6.716014 -2.921254)
			(end 6.728206 -2.99085)
			(stroke
				(width 0.1)
				(type default)
			)
			(layer "F.SilkS")
		)
		(fp_line
			(start 6.716014 -2.921254)
			(end 6.728206 -2.99085)
			(stroke
				(width 0.1)
				(type default)
			)
			(layer "F.SilkS")
		)
		(fp_line
			(start 6.728206 -2.99085)
			(end 6.740144 -3.060192)
			(stroke
				(width 0.1)
				(type default)
			)
			(layer "F.SilkS")
		)
		(fp_line
			(start 6.728206 -2.99085)
			(end 6.740144 -3.060192)
			(stroke
				(width 0.1)
				(type default)
			)
			(layer "F.SilkS")
		)
		(fp_line
			(start 6.729984 -0.799592)
			(end 9.379712 -3.34137)
			(stroke
				(width 0.1)
				(type default)
			)
			(layer "F.SilkS")
		)
		(fp_line
			(start 6.729984 -0.799592)
			(end 9.379712 -3.34137)
			(stroke
				(width 0.1)
				(type default)
			)
			(layer "F.SilkS")
		)
		(fp_line
			(start 6.740144 -3.060192)
			(end 6.75259 -3.129534)
			(stroke
				(width 0.1)
				(type default)
			)
			(layer "F.SilkS")
		)
		(fp_line
			(start 6.740144 -3.060192)
			(end 6.75259 -3.129534)
			(stroke
				(width 0.1)
				(type default)
			)
			(layer "F.SilkS")
		)
		(fp_line
			(start 6.75259 -3.129534)
			(end 6.764782 -3.19913)
			(stroke
				(width 0.1)
				(type default)
			)
			(layer "F.SilkS")
		)
		(fp_line
			(start 6.75259 -3.129534)
			(end 6.764782 -3.19913)
			(stroke
				(width 0.1)
				(type default)
			)
			(layer "F.SilkS")
		)
		(fp_line
			(start 6.764782 -3.19913)
			(end 6.776974 -3.268472)
			(stroke
				(width 0.1)
				(type default)
			)
			(layer "F.SilkS")
		)
		(fp_line
			(start 6.764782 -3.19913)
			(end 6.776974 -3.268472)
			(stroke
				(width 0.1)
				(type default)
			)
			(layer "F.SilkS")
		)
		(fp_line
			(start 6.77545 -5.171694)
			(end 5.823966 -4.258818)
			(stroke
				(width 0.1)
				(type default)
			)
			(layer "F.SilkS")
		)
		(fp_line
			(start 6.77545 -5.171694)
			(end 5.823966 -4.258818)
			(stroke
				(width 0.1)
				(type default)
			)
			(layer "F.SilkS")
		)
		(fp_line
			(start 6.77545 -5.171694)
			(end 6.715506 -5.171694)
			(stroke
				(width 0.1)
				(type default)
			)
			(layer "F.SilkS")
		)
		(fp_line
			(start 6.77545 -5.171694)
			(end 6.715506 -5.171694)
			(stroke
				(width 0.1)
				(type default)
			)
			(layer "F.SilkS")
		)
		(fp_line
			(start 6.776974 -3.268472)
			(end 6.788912 -3.337814)
			(stroke
				(width 0.1)
				(type default)
			)
			(layer "F.SilkS")
		)
		(fp_line
			(start 6.776974 -3.268472)
			(end 6.788912 -3.337814)
			(stroke
				(width 0.1)
				(type default)
			)
			(layer "F.SilkS")
		)
		(fp_line
			(start 6.784848 -0.794258)
			(end 9.36752 -3.272028)
			(stroke
				(width 0.1)
				(type default)
			)
			(layer "F.SilkS")
		)
		(fp_line
			(start 6.784848 -0.794258)
			(end 9.36752 -3.272028)
			(stroke
				(width 0.1)
				(type default)
			)
			(layer "F.SilkS")
		)
		(fp_line
			(start 6.788912 -3.337814)
			(end 6.801104 -3.407156)
			(stroke
				(width 0.1)
				(type default)
			)
			(layer "F.SilkS")
		)
		(fp_line
			(start 6.788912 -3.337814)
			(end 6.801104 -3.407156)
			(stroke
				(width 0.1)
				(type default)
			)
			(layer "F.SilkS")
		)
		(fp_line
			(start 6.801104 -3.407156)
			(end 6.81355 -3.476498)
			(stroke
				(width 0.1)
				(type default)
			)
			(layer "F.SilkS")
		)
		(fp_line
			(start 6.801104 -3.407156)
			(end 6.81355 -3.476498)
			(stroke
				(width 0.1)
				(type default)
			)
			(layer "F.SilkS")
		)
		(fp_line
			(start 6.825488 -3.54584)
			(end 6.81355 -3.476498)
			(stroke
				(width 0.1)
				(type default)
			)
			(layer "F.SilkS")
		)
		(fp_line
			(start 6.825488 -3.54584)
			(end 6.81355 -3.476498)
			(stroke
				(width 0.1)
				(type default)
			)
			(layer "F.SilkS")
		)
		(fp_line
			(start 6.825488 -3.54584)
			(end 6.83768 -3.615436)
			(stroke
				(width 0.1)
				(type default)
			)
			(layer "F.SilkS")
		)
		(fp_line
			(start 6.825488 -3.54584)
			(end 6.83768 -3.615436)
			(stroke
				(width 0.1)
				(type default)
			)
			(layer "F.SilkS")
		)
		(fp_line
			(start 6.835648 -5.171694)
			(end 5.811774 -4.189476)
			(stroke
				(width 0.1)
				(type default)
			)
			(layer "F.SilkS")
		)
		(fp_line
			(start 6.835648 -5.171694)
			(end 5.811774 -4.189476)
			(stroke
				(width 0.1)
				(type default)
			)
			(layer "F.SilkS")
		)
		(fp_line
			(start 6.835648 -5.171694)
			(end 6.77545 -5.171694)
			(stroke
				(width 0.1)
				(type default)
			)
			(layer "F.SilkS")
		)
		(fp_line
			(start 6.835648 -5.171694)
			(end 6.77545 -5.171694)
			(stroke
				(width 0.1)
				(type default)
			)
			(layer "F.SilkS")
		)
		(fp_line
			(start 6.83768 -3.615436)
			(end 5.509514 -2.341372)
			(stroke
				(width 0.1)
				(type default)
			)
			(layer "F.SilkS")
		)
		(fp_line
			(start 6.83768 -3.615436)
			(end 5.509514 -2.341372)
			(stroke
				(width 0.1)
				(type default)
			)
			(layer "F.SilkS")
		)
		(fp_line
			(start 6.83768 -3.615436)
			(end 6.849872 -3.684778)
			(stroke
				(width 0.1)
				(type default)
			)
			(layer "F.SilkS")
		)
		(fp_line
			(start 6.83768 -3.615436)
			(end 6.849872 -3.684778)
			(stroke
				(width 0.1)
				(type default)
			)
			(layer "F.SilkS")
		)
		(fp_line
			(start 6.848348 -0.797814)
			(end 9.355328 -3.202432)
			(stroke
				(width 0.1)
				(type default)
			)
			(layer "F.SilkS")
		)
		(fp_line
			(start 6.848348 -0.797814)
			(end 9.355328 -3.202432)
			(stroke
				(width 0.1)
				(type default)
			)
			(layer "F.SilkS")
		)
		(fp_line
			(start 6.849872 -3.684778)
			(end 5.517642 -2.40665)
			(stroke
				(width 0.1)
				(type default)
			)
			(layer "F.SilkS")
		)
		(fp_line
			(start 6.849872 -3.684778)
			(end 5.517642 -2.40665)
			(stroke
				(width 0.1)
				(type default)
			)
			(layer "F.SilkS")
		)
		(fp_line
			(start 6.849872 -3.684778)
			(end 6.862318 -3.75412)
			(stroke
				(width 0.1)
				(type default)
			)
			(layer "F.SilkS")
		)
		(fp_line
			(start 6.849872 -3.684778)
			(end 6.862318 -3.75412)
			(stroke
				(width 0.1)
				(type default)
			)
			(layer "F.SilkS")
		)
		(fp_line
			(start 6.862318 -3.75412)
			(end 5.525516 -2.471928)
			(stroke
				(width 0.1)
				(type default)
			)
			(layer "F.SilkS")
		)
		(fp_line
			(start 6.862318 -3.75412)
			(end 5.525516 -2.471928)
			(stroke
				(width 0.1)
				(type default)
			)
			(layer "F.SilkS")
		)
		(fp_line
			(start 6.862318 -3.75412)
			(end 6.874256 -3.823716)
			(stroke
				(width 0.1)
				(type default)
			)
			(layer "F.SilkS")
		)
		(fp_line
			(start 6.862318 -3.75412)
			(end 6.874256 -3.823716)
			(stroke
				(width 0.1)
				(type default)
			)
			(layer "F.SilkS")
		)
		(fp_line
			(start 6.874256 -3.823716)
			(end 5.53339 -2.537206)
			(stroke
				(width 0.1)
				(type default)
			)
			(layer "F.SilkS")
		)
		(fp_line
			(start 6.874256 -3.823716)
			(end 5.53339 -2.537206)
			(stroke
				(width 0.1)
				(type default)
			)
			(layer "F.SilkS")
		)
		(fp_line
			(start 6.874256 -3.823716)
			(end 6.886448 -3.893058)
			(stroke
				(width 0.1)
				(type default)
			)
			(layer "F.SilkS")
		)
		(fp_line
			(start 6.874256 -3.823716)
			(end 6.886448 -3.893058)
			(stroke
				(width 0.1)
				(type default)
			)
			(layer "F.SilkS")
		)
		(fp_line
			(start 6.886448 -3.893058)
			(end 5.541264 -2.602738)
			(stroke
				(width 0.1)
				(type default)
			)
			(layer "F.SilkS")
		)
		(fp_line
			(start 6.886448 -3.893058)
			(end 5.541264 -2.602738)
			(stroke
				(width 0.1)
				(type default)
			)
			(layer "F.SilkS")
		)
		(fp_line
			(start 6.886448 -3.893058)
			(end 6.89864 -3.9624)
			(stroke
				(width 0.1)
				(type default)
			)
			(layer "F.SilkS")
		)
		(fp_line
			(start 6.886448 -3.893058)
			(end 6.89864 -3.9624)
			(stroke
				(width 0.1)
				(type default)
			)
			(layer "F.SilkS")
		)
		(fp_line
			(start 6.895846 -5.171694)
			(end 5.799582 -4.11988)
			(stroke
				(width 0.1)
				(type default)
			)
			(layer "F.SilkS")
		)
		(fp_line
			(start 6.895846 -5.171694)
			(end 5.799582 -4.11988)
			(stroke
				(width 0.1)
				(type default)
			)
			(layer "F.SilkS")
		)
		(fp_line
			(start 6.895846 -5.171694)
			(end 6.835648 -5.171694)
			(stroke
				(width 0.1)
				(type default)
			)
			(layer "F.SilkS")
		)
		(fp_line
			(start 6.895846 -5.171694)
			(end 6.835648 -5.171694)
			(stroke
				(width 0.1)
				(type default)
			)
			(layer "F.SilkS")
		)
		(fp_line
			(start 6.89864 -3.9624)
			(end 5.549392 -2.668016)
			(stroke
				(width 0.1)
				(type default)
			)
			(layer "F.SilkS")
		)
		(fp_line
			(start 6.89864 -3.9624)
			(end 5.549392 -2.668016)
			(stroke
				(width 0.1)
				(type default)
			)
			(layer "F.SilkS")
		)
		(fp_line
			(start 6.89864 -3.9624)
			(end 6.910832 -4.031742)
			(stroke
				(width 0.1)
				(type default)
			)
			(layer "F.SilkS")
		)
		(fp_line
			(start 6.89864 -3.9624)
			(end 6.910832 -4.031742)
			(stroke
				(width 0.1)
				(type default)
			)
			(layer "F.SilkS")
		)
		(fp_line
			(start 6.910832 -4.031742)
			(end 5.557266 -2.733294)
			(stroke
				(width 0.1)
				(type default)
			)
			(layer "F.SilkS")
		)
		(fp_line
			(start 6.910832 -4.031742)
			(end 5.557266 -2.733294)
			(stroke
				(width 0.1)
				(type default)
			)
			(layer "F.SilkS")
		)
		(fp_line
			(start 6.910832 -4.031742)
			(end 6.923024 -4.101084)
			(stroke
				(width 0.1)
				(type default)
			)
			(layer "F.SilkS")
		)
		(fp_line
			(start 6.910832 -4.031742)
			(end 6.923024 -4.101084)
			(stroke
				(width 0.1)
				(type default)
			)
			(layer "F.SilkS")
		)
		(fp_line
			(start 6.914896 -0.80391)
			(end 9.343136 -3.13309)
			(stroke
				(width 0.1)
				(type default)
			)
			(layer "F.SilkS")
		)
		(fp_line
			(start 6.914896 -0.80391)
			(end 9.343136 -3.13309)
			(stroke
				(width 0.1)
				(type default)
			)
			(layer "F.SilkS")
		)
		(fp_line
			(start 6.923024 -4.101084)
			(end 5.568188 -2.801366)
			(stroke
				(width 0.1)
				(type default)
			)
			(layer "F.SilkS")
		)
		(fp_line
			(start 6.923024 -4.101084)
			(end 5.568188 -2.801366)
			(stroke
				(width 0.1)
				(type default)
			)
			(layer "F.SilkS")
		)
		(fp_line
			(start 6.923024 -4.101084)
			(end 6.935216 -4.170426)
			(stroke
				(width 0.1)
				(type default)
			)
			(layer "F.SilkS")
		)
		(fp_line
			(start 6.923024 -4.101084)
			(end 6.935216 -4.170426)
			(stroke
				(width 0.1)
				(type default)
			)
			(layer "F.SilkS")
		)
		(fp_line
			(start 6.935216 -4.170426)
			(end 5.58038 -2.870962)
			(stroke
				(width 0.1)
				(type default)
			)
			(layer "F.SilkS")
		)
		(fp_line
			(start 6.935216 -4.170426)
			(end 5.58038 -2.870962)
			(stroke
				(width 0.1)
				(type default)
			)
			(layer "F.SilkS")
		)
		(fp_line
			(start 6.935216 -4.170426)
			(end 6.947408 -4.240022)
			(stroke
				(width 0.1)
				(type default)
			)
			(layer "F.SilkS")
		)
		(fp_line
			(start 6.935216 -4.170426)
			(end 6.947408 -4.240022)
			(stroke
				(width 0.1)
				(type default)
			)
			(layer "F.SilkS")
		)
		(fp_line
			(start 6.947408 -4.240022)
			(end 5.592572 -2.940304)
			(stroke
				(width 0.1)
				(type default)
			)
			(layer "F.SilkS")
		)
		(fp_line
			(start 6.947408 -4.240022)
			(end 5.592572 -2.940304)
			(stroke
				(width 0.1)
				(type default)
			)
			(layer "F.SilkS")
		)
		(fp_line
			(start 6.947408 -4.240022)
			(end 6.9596 -4.309364)
			(stroke
				(width 0.1)
				(type default)
			)
			(layer "F.SilkS")
		)
		(fp_line
			(start 6.947408 -4.240022)
			(end 6.9596 -4.309364)
			(stroke
				(width 0.1)
				(type default)
			)
			(layer "F.SilkS")
		)
		(fp_line
			(start 6.956044 -5.171694)
			(end 5.78739 -4.050538)
			(stroke
				(width 0.1)
				(type default)
			)
			(layer "F.SilkS")
		)
		(fp_line
			(start 6.956044 -5.171694)
			(end 5.78739 -4.050538)
			(stroke
				(width 0.1)
				(type default)
			)
			(layer "F.SilkS")
		)
		(fp_line
			(start 6.956044 -5.171694)
			(end 6.895846 -5.171694)
			(stroke
				(width 0.1)
				(type default)
			)
			(layer "F.SilkS")
		)
		(fp_line
			(start 6.956044 -5.171694)
			(end 6.895846 -5.171694)
			(stroke
				(width 0.1)
				(type default)
			)
			(layer "F.SilkS")
		)
		(fp_line
			(start 6.9596 -4.309364)
			(end 5.604764 -3.009646)
			(stroke
				(width 0.1)
				(type default)
			)
			(layer "F.SilkS")
		)
		(fp_line
			(start 6.9596 -4.309364)
			(end 5.604764 -3.009646)
			(stroke
				(width 0.1)
				(type default)
			)
			(layer "F.SilkS")
		)
		(fp_line
			(start 6.9596 -4.309364)
			(end 6.971792 -4.378706)
			(stroke
				(width 0.1)
				(type default)
			)
			(layer "F.SilkS")
		)
		(fp_line
			(start 6.9596 -4.309364)
			(end 6.971792 -4.378706)
			(stroke
				(width 0.1)
				(type default)
			)
			(layer "F.SilkS")
		)
		(fp_line
			(start 6.971792 -4.378706)
			(end 5.616956 -3.079242)
			(stroke
				(width 0.1)
				(type default)
			)
			(layer "F.SilkS")
		)
		(fp_line
			(start 6.971792 -4.378706)
			(end 5.616956 -3.079242)
			(stroke
				(width 0.1)
				(type default)
			)
			(layer "F.SilkS")
		)
		(fp_line
			(start 6.971792 -4.378706)
			(end 6.983984 -4.448302)
			(stroke
				(width 0.1)
				(type default)
			)
			(layer "F.SilkS")
		)
		(fp_line
			(start 6.971792 -4.378706)
			(end 6.983984 -4.448302)
			(stroke
				(width 0.1)
				(type default)
			)
			(layer "F.SilkS")
		)
		(fp_line
			(start 6.981444 -0.809752)
			(end 9.330944 -3.063748)
			(stroke
				(width 0.1)
				(type default)
			)
			(layer "F.SilkS")
		)
		(fp_line
			(start 6.981444 -0.809752)
			(end 9.330944 -3.063748)
			(stroke
				(width 0.1)
				(type default)
			)
			(layer "F.SilkS")
		)
		(fp_line
			(start 6.983984 -4.448302)
			(end 5.629148 -3.148584)
			(stroke
				(width 0.1)
				(type default)
			)
			(layer "F.SilkS")
		)
		(fp_line
			(start 6.983984 -4.448302)
			(end 5.629148 -3.148584)
			(stroke
				(width 0.1)
				(type default)
			)
			(layer "F.SilkS")
		)
		(fp_line
			(start 6.983984 -4.448302)
			(end 6.996176 -4.51739)
			(stroke
				(width 0.1)
				(type default)
			)
			(layer "F.SilkS")
		)
		(fp_line
			(start 6.983984 -4.448302)
			(end 6.996176 -4.51739)
			(stroke
				(width 0.1)
				(type default)
			)
			(layer "F.SilkS")
		)
		(fp_line
			(start 6.996176 -4.51739)
			(end 5.64134 -3.217926)
			(stroke
				(width 0.1)
				(type default)
			)
			(layer "F.SilkS")
		)
		(fp_line
			(start 6.996176 -4.51739)
			(end 5.64134 -3.217926)
			(stroke
				(width 0.1)
				(type default)
			)
			(layer "F.SilkS")
		)
		(fp_line
			(start 6.996176 -4.51739)
			(end 7.008368 -4.586986)
			(stroke
				(width 0.1)
				(type default)
			)
			(layer "F.SilkS")
		)
		(fp_line
			(start 6.996176 -4.51739)
			(end 7.008368 -4.586986)
			(stroke
				(width 0.1)
				(type default)
			)
			(layer "F.SilkS")
		)
		(fp_line
			(start 7.008368 -4.586986)
			(end 5.653532 -3.287268)
			(stroke
				(width 0.1)
				(type default)
			)
			(layer "F.SilkS")
		)
		(fp_line
			(start 7.008368 -4.586986)
			(end 5.653532 -3.287268)
			(stroke
				(width 0.1)
				(type default)
			)
			(layer "F.SilkS")
		)
		(fp_line
			(start 7.008368 -4.586986)
			(end 7.02056 -4.656328)
			(stroke
				(width 0.1)
				(type default)
			)
			(layer "F.SilkS")
		)
		(fp_line
			(start 7.008368 -4.586986)
			(end 7.02056 -4.656328)
			(stroke
				(width 0.1)
				(type default)
			)
			(layer "F.SilkS")
		)
		(fp_line
			(start 7.016242 -5.171694)
			(end 5.775198 -3.98145)
			(stroke
				(width 0.1)
				(type default)
			)
			(layer "F.SilkS")
		)
		(fp_line
			(start 7.016242 -5.171694)
			(end 5.775198 -3.98145)
			(stroke
				(width 0.1)
				(type default)
			)
			(layer "F.SilkS")
		)
		(fp_line
			(start 7.016242 -5.171694)
			(end 6.956044 -5.171694)
			(stroke
				(width 0.1)
				(type default)
			)
			(layer "F.SilkS")
		)
		(fp_line
			(start 7.016242 -5.171694)
			(end 6.956044 -5.171694)
			(stroke
				(width 0.1)
				(type default)
			)
			(layer "F.SilkS")
		)
		(fp_line
			(start 7.02056 -4.656328)
			(end 5.665724 -3.35661)
			(stroke
				(width 0.1)
				(type default)
			)
			(layer "F.SilkS")
		)
		(fp_line
			(start 7.02056 -4.656328)
			(end 5.665724 -3.35661)
			(stroke
				(width 0.1)
				(type default)
			)
			(layer "F.SilkS")
		)
		(fp_line
			(start 7.02056 -4.656328)
			(end 7.032752 -4.725924)
			(stroke
				(width 0.1)
				(type default)
			)
			(layer "F.SilkS")
		)
		(fp_line
			(start 7.02056 -4.656328)
			(end 7.032752 -4.725924)
			(stroke
				(width 0.1)
				(type default)
			)
			(layer "F.SilkS")
		)
		(fp_line
			(start 7.032752 -4.725924)
			(end 5.677662 -3.425952)
			(stroke
				(width 0.1)
				(type default)
			)
			(layer "F.SilkS")
		)
		(fp_line
			(start 7.032752 -4.725924)
			(end 5.677662 -3.425952)
			(stroke
				(width 0.1)
				(type default)
			)
			(layer "F.SilkS")
		)
		(fp_line
			(start 7.032752 -4.725924)
			(end 7.04469 -4.795012)
			(stroke
				(width 0.1)
				(type default)
			)
			(layer "F.SilkS")
		)
		(fp_line
			(start 7.032752 -4.725924)
			(end 7.04469 -4.795012)
			(stroke
				(width 0.1)
				(type default)
			)
			(layer "F.SilkS")
		)
		(fp_line
			(start 7.04469 -4.795012)
			(end 5.690108 -3.495548)
			(stroke
				(width 0.1)
				(type default)
			)
			(layer "F.SilkS")
		)
		(fp_line
			(start 7.04469 -4.795012)
			(end 5.690108 -3.495548)
			(stroke
				(width 0.1)
				(type default)
			)
			(layer "F.SilkS")
		)
		(fp_line
			(start 7.04469 -4.795012)
			(end 7.057136 -4.864354)
			(stroke
				(width 0.1)
				(type default)
			)
			(layer "F.SilkS")
		)
		(fp_line
			(start 7.04469 -4.795012)
			(end 7.057136 -4.864354)
			(stroke
				(width 0.1)
				(type default)
			)
			(layer "F.SilkS")
		)
		(fp_line
			(start 7.047992 -0.816102)
			(end 9.318752 -2.994406)
			(stroke
				(width 0.1)
				(type default)
			)
			(layer "F.SilkS")
		)
		(fp_line
			(start 7.047992 -0.816102)
			(end 9.318752 -2.994406)
			(stroke
				(width 0.1)
				(type default)
			)
			(layer "F.SilkS")
		)
		(fp_line
			(start 7.057136 -4.864354)
			(end 5.7023 -3.56489)
			(stroke
				(width 0.1)
				(type default)
			)
			(layer "F.SilkS")
		)
		(fp_line
			(start 7.057136 -4.864354)
			(end 5.7023 -3.56489)
			(stroke
				(width 0.1)
				(type default)
			)
			(layer "F.SilkS")
		)
		(fp_line
			(start 7.057136 -4.864354)
			(end 7.069328 -4.93395)
			(stroke
				(width 0.1)
				(type default)
			)
			(layer "F.SilkS")
		)
		(fp_line
			(start 7.057136 -4.864354)
			(end 7.069328 -4.93395)
			(stroke
				(width 0.1)
				(type default)
			)
			(layer "F.SilkS")
		)
		(fp_line
			(start 7.069328 -4.93395)
			(end 5.714238 -3.634232)
			(stroke
				(width 0.1)
				(type default)
			)
			(layer "F.SilkS")
		)
		(fp_line
			(start 7.069328 -4.93395)
			(end 5.714238 -3.634232)
			(stroke
				(width 0.1)
				(type default)
			)
			(layer "F.SilkS")
		)
		(fp_line
			(start 7.069328 -4.93395)
			(end 7.081266 -5.003292)
			(stroke
				(width 0.1)
				(type default)
			)
			(layer "F.SilkS")
		)
		(fp_line
			(start 7.069328 -4.93395)
			(end 7.081266 -5.003292)
			(stroke
				(width 0.1)
				(type default)
			)
			(layer "F.SilkS")
		)
		(fp_line
			(start 7.07644 -5.171694)
			(end 5.763006 -3.911854)
			(stroke
				(width 0.1)
				(type default)
			)
			(layer "F.SilkS")
		)
		(fp_line
			(start 7.07644 -5.171694)
			(end 5.763006 -3.911854)
			(stroke
				(width 0.1)
				(type default)
			)
			(layer "F.SilkS")
		)
		(fp_line
			(start 7.07644 -5.171694)
			(end 7.016242 -5.171694)
			(stroke
				(width 0.1)
				(type default)
			)
			(layer "F.SilkS")
		)
		(fp_line
			(start 7.07644 -5.171694)
			(end 7.016242 -5.171694)
			(stroke
				(width 0.1)
				(type default)
			)
			(layer "F.SilkS")
		)
		(fp_line
			(start 7.081266 -5.003292)
			(end 5.72643 -3.703828)
			(stroke
				(width 0.1)
				(type default)
			)
			(layer "F.SilkS")
		)
		(fp_line
			(start 7.081266 -5.003292)
			(end 5.72643 -3.703828)
			(stroke
				(width 0.1)
				(type default)
			)
			(layer "F.SilkS")
		)
		(fp_line
			(start 7.081266 -5.003292)
			(end 7.093458 -5.072888)
			(stroke
				(width 0.1)
				(type default)
			)
			(layer "F.SilkS")
		)
		(fp_line
			(start 7.081266 -5.003292)
			(end 7.093458 -5.072888)
			(stroke
				(width 0.1)
				(type default)
			)
			(layer "F.SilkS")
		)
		(fp_line
			(start 7.093458 -5.072888)
			(end 5.738876 -3.772916)
			(stroke
				(width 0.1)
				(type default)
			)
			(layer "F.SilkS")
		)
		(fp_line
			(start 7.093458 -5.072888)
			(end 5.738876 -3.772916)
			(stroke
				(width 0.1)
				(type default)
			)
			(layer "F.SilkS")
		)
		(fp_line
			(start 7.093458 -5.072888)
			(end 7.10565 -5.141976)
			(stroke
				(width 0.1)
				(type default)
			)
			(layer "F.SilkS")
		)
		(fp_line
			(start 7.093458 -5.072888)
			(end 7.10565 -5.141976)
			(stroke
				(width 0.1)
				(type default)
			)
			(layer "F.SilkS")
		)
		(fp_line
			(start 7.10565 -5.141976)
			(end 5.751068 -3.842512)
			(stroke
				(width 0.1)
				(type default)
			)
			(layer "F.SilkS")
		)
		(fp_line
			(start 7.10565 -5.141976)
			(end 5.751068 -3.842512)
			(stroke
				(width 0.1)
				(type default)
			)
			(layer "F.SilkS")
		)
		(fp_line
			(start 7.10565 -5.141976)
			(end 7.110984 -5.171694)
			(stroke
				(width 0.1)
				(type default)
			)
			(layer "F.SilkS")
		)
		(fp_line
			(start 7.10565 -5.141976)
			(end 7.110984 -5.171694)
			(stroke
				(width 0.1)
				(type default)
			)
			(layer "F.SilkS")
		)
		(fp_line
			(start 7.110984 -5.171694)
			(end 7.07644 -5.171694)
			(stroke
				(width 0.1)
				(type default)
			)
			(layer "F.SilkS")
		)
		(fp_line
			(start 7.110984 -5.171694)
			(end 7.07644 -5.171694)
			(stroke
				(width 0.1)
				(type default)
			)
			(layer "F.SilkS")
		)
		(fp_line
			(start 7.11454 -0.822198)
			(end 9.30656 -2.925064)
			(stroke
				(width 0.1)
				(type default)
			)
			(layer "F.SilkS")
		)
		(fp_line
			(start 7.11454 -0.822198)
			(end 9.30656 -2.925064)
			(stroke
				(width 0.1)
				(type default)
			)
			(layer "F.SilkS")
		)
		(fp_line
			(start 7.196582 -0.84328)
			(end 9.294368 -2.855468)
			(stroke
				(width 0.1)
				(type default)
			)
			(layer "F.SilkS")
		)
		(fp_line
			(start 7.196582 -0.84328)
			(end 9.294368 -2.855468)
			(stroke
				(width 0.1)
				(type default)
			)
			(layer "F.SilkS")
		)
		(fp_line
			(start 7.281418 -0.866648)
			(end 9.281922 -2.786126)
			(stroke
				(width 0.1)
				(type default)
			)
			(layer "F.SilkS")
		)
		(fp_line
			(start 7.281418 -0.866648)
			(end 9.281922 -2.786126)
			(stroke
				(width 0.1)
				(type default)
			)
			(layer "F.SilkS")
		)
		(fp_line
			(start 7.366 -0.890016)
			(end 9.269984 -2.716784)
			(stroke
				(width 0.1)
				(type default)
			)
			(layer "F.SilkS")
		)
		(fp_line
			(start 7.366 -0.890016)
			(end 9.269984 -2.716784)
			(stroke
				(width 0.1)
				(type default)
			)
			(layer "F.SilkS")
		)
		(fp_line
			(start 7.464298 -0.926846)
			(end 9.257792 -2.647188)
			(stroke
				(width 0.1)
				(type default)
			)
			(layer "F.SilkS")
		)
		(fp_line
			(start 7.464298 -0.926846)
			(end 9.257792 -2.647188)
			(stroke
				(width 0.1)
				(type default)
			)
			(layer "F.SilkS")
		)
		(fp_line
			(start 7.583678 -0.983488)
			(end 9.2456 -2.577592)
			(stroke
				(width 0.1)
				(type default)
			)
			(layer "F.SilkS")
		)
		(fp_line
			(start 7.583678 -0.983488)
			(end 9.2456 -2.577592)
			(stroke
				(width 0.1)
				(type default)
			)
			(layer "F.SilkS")
		)
		(fp_line
			(start 7.737348 -1.07315)
			(end 9.233408 -2.508504)
			(stroke
				(width 0.1)
				(type default)
			)
			(layer "F.SilkS")
		)
		(fp_line
			(start 7.737348 -1.07315)
			(end 9.233408 -2.508504)
			(stroke
				(width 0.1)
				(type default)
			)
			(layer "F.SilkS")
		)
		(fp_line
			(start 7.82066 -0.882904)
			(end 7.839456 -0.882904)
			(stroke
				(width 0.1)
				(type default)
			)
			(layer "F.SilkS")
		)
		(fp_line
			(start 7.82066 -0.882904)
			(end 7.839456 -0.882904)
			(stroke
				(width 0.1)
				(type default)
			)
			(layer "F.SilkS")
		)
		(fp_line
			(start 7.828788 -0.930148)
			(end 7.82066 -0.882904)
			(stroke
				(width 0.1)
				(type default)
			)
			(layer "F.SilkS")
		)
		(fp_line
			(start 7.828788 -0.930148)
			(end 7.82066 -0.882904)
			(stroke
				(width 0.1)
				(type default)
			)
			(layer "F.SilkS")
		)
		(fp_line
			(start 7.828788 -0.930148)
			(end 9.18464 -2.230882)
			(stroke
				(width 0.1)
				(type default)
			)
			(layer "F.SilkS")
		)
		(fp_line
			(start 7.828788 -0.930148)
			(end 9.18464 -2.230882)
			(stroke
				(width 0.1)
				(type default)
			)
			(layer "F.SilkS")
		)
		(fp_line
			(start 7.839456 -0.882904)
			(end 7.899908 -0.882904)
			(stroke
				(width 0.1)
				(type default)
			)
			(layer "F.SilkS")
		)
		(fp_line
			(start 7.839456 -0.882904)
			(end 7.899908 -0.882904)
			(stroke
				(width 0.1)
				(type default)
			)
			(layer "F.SilkS")
		)
		(fp_line
			(start 7.839456 -0.882904)
			(end 9.172194 -2.161286)
			(stroke
				(width 0.1)
				(type default)
			)
			(layer "F.SilkS")
		)
		(fp_line
			(start 7.839456 -0.882904)
			(end 9.172194 -2.161286)
			(stroke
				(width 0.1)
				(type default)
			)
			(layer "F.SilkS")
		)
		(fp_line
			(start 7.84098 -0.999744)
			(end 7.828788 -0.930148)
			(stroke
				(width 0.1)
				(type default)
			)
			(layer "F.SilkS")
		)
		(fp_line
			(start 7.84098 -0.999744)
			(end 7.828788 -0.930148)
			(stroke
				(width 0.1)
				(type default)
			)
			(layer "F.SilkS")
		)
		(fp_line
			(start 7.84098 -0.999744)
			(end 9.196832 -2.300224)
			(stroke
				(width 0.1)
				(type default)
			)
			(layer "F.SilkS")
		)
		(fp_line
			(start 7.84098 -0.999744)
			(end 9.196832 -2.300224)
			(stroke
				(width 0.1)
				(type default)
			)
			(layer "F.SilkS")
		)
		(fp_line
			(start 7.852918 -1.068832)
			(end 7.84098 -0.999744)
			(stroke
				(width 0.1)
				(type default)
			)
			(layer "F.SilkS")
		)
		(fp_line
			(start 7.852918 -1.068832)
			(end 7.84098 -0.999744)
			(stroke
				(width 0.1)
				(type default)
			)
			(layer "F.SilkS")
		)
		(fp_line
			(start 7.852918 -1.068832)
			(end 9.209024 -2.369566)
			(stroke
				(width 0.1)
				(type default)
			)
			(layer "F.SilkS")
		)
		(fp_line
			(start 7.852918 -1.068832)
			(end 9.209024 -2.369566)
			(stroke
				(width 0.1)
				(type default)
			)
			(layer "F.SilkS")
		)
		(fp_line
			(start 7.865364 -1.138428)
			(end 7.852918 -1.068832)
			(stroke
				(width 0.1)
				(type default)
			)
			(layer "F.SilkS")
		)
		(fp_line
			(start 7.865364 -1.138428)
			(end 7.852918 -1.068832)
			(stroke
				(width 0.1)
				(type default)
			)
			(layer "F.SilkS")
		)
		(fp_line
			(start 7.865364 -1.138428)
			(end 9.220962 -2.438908)
			(stroke
				(width 0.1)
				(type default)
			)
			(layer "F.SilkS")
		)
		(fp_line
			(start 7.865364 -1.138428)
			(end 9.220962 -2.438908)
			(stroke
				(width 0.1)
				(type default)
			)
			(layer "F.SilkS")
		)
		(fp_line
			(start 7.899908 -0.882904)
			(end 7.960106 -0.882904)
			(stroke
				(width 0.1)
				(type default)
			)
			(layer "F.SilkS")
		)
		(fp_line
			(start 7.899908 -0.882904)
			(end 7.960106 -0.882904)
			(stroke
				(width 0.1)
				(type default)
			)
			(layer "F.SilkS")
		)
		(fp_line
			(start 7.899908 -0.882904)
			(end 9.160002 -2.091944)
			(stroke
				(width 0.1)
				(type default)
			)
			(layer "F.SilkS")
		)
		(fp_line
			(start 7.899908 -0.882904)
			(end 9.160002 -2.091944)
			(stroke
				(width 0.1)
				(type default)
			)
			(layer "F.SilkS")
		)
		(fp_line
			(start 7.936484 -2.187702)
			(end 9.42848 -3.618992)
			(stroke
				(width 0.1)
				(type default)
			)
			(layer "F.SilkS")
		)
		(fp_line
			(start 7.936484 -2.187702)
			(end 9.42848 -3.618992)
			(stroke
				(width 0.1)
				(type default)
			)
			(layer "F.SilkS")
		)
		(fp_line
			(start 7.960106 -0.882904)
			(end 8.02005 -0.882904)
			(stroke
				(width 0.1)
				(type default)
			)
			(layer "F.SilkS")
		)
		(fp_line
			(start 7.960106 -0.882904)
			(end 8.02005 -0.882904)
			(stroke
				(width 0.1)
				(type default)
			)
			(layer "F.SilkS")
		)
		(fp_line
			(start 7.960106 -0.882904)
			(end 9.148064 -2.022602)
			(stroke
				(width 0.1)
				(type default)
			)
			(layer "F.SilkS")
		)
		(fp_line
			(start 7.960106 -0.882904)
			(end 9.148064 -2.022602)
			(stroke
				(width 0.1)
				(type default)
			)
			(layer "F.SilkS")
		)
		(fp_line
			(start 8.002778 -2.30886)
			(end 9.440672 -3.688334)
			(stroke
				(width 0.1)
				(type default)
			)
			(layer "F.SilkS")
		)
		(fp_line
			(start 8.002778 -2.30886)
			(end 9.440672 -3.688334)
			(stroke
				(width 0.1)
				(type default)
			)
			(layer "F.SilkS")
		)
		(fp_line
			(start 8.02005 -0.882904)
			(end 8.080248 -0.882904)
			(stroke
				(width 0.1)
				(type default)
			)
			(layer "F.SilkS")
		)
		(fp_line
			(start 8.02005 -0.882904)
			(end 8.080248 -0.882904)
			(stroke
				(width 0.1)
				(type default)
			)
			(layer "F.SilkS")
		)
		(fp_line
			(start 8.02005 -0.882904)
			(end 9.135872 -1.953006)
			(stroke
				(width 0.1)
				(type default)
			)
			(layer "F.SilkS")
		)
		(fp_line
			(start 8.02005 -0.882904)
			(end 9.135872 -1.953006)
			(stroke
				(width 0.1)
				(type default)
			)
			(layer "F.SilkS")
		)
		(fp_line
			(start 8.04799 -2.410206)
			(end 9.452864 -3.75793)
			(stroke
				(width 0.1)
				(type default)
			)
			(layer "F.SilkS")
		)
		(fp_line
			(start 8.04799 -2.410206)
			(end 9.452864 -3.75793)
			(stroke
				(width 0.1)
				(type default)
			)
			(layer "F.SilkS")
		)
		(fp_line
			(start 8.078724 -2.497328)
			(end 9.465056 -3.827526)
			(stroke
				(width 0.1)
				(type default)
			)
			(layer "F.SilkS")
		)
		(fp_line
			(start 8.078724 -2.497328)
			(end 9.465056 -3.827526)
			(stroke
				(width 0.1)
				(type default)
			)
			(layer "F.SilkS")
		)
		(fp_line
			(start 8.080248 -0.882904)
			(end 8.140446 -0.882904)
			(stroke
				(width 0.1)
				(type default)
			)
			(layer "F.SilkS")
		)
		(fp_line
			(start 8.080248 -0.882904)
			(end 8.140446 -0.882904)
			(stroke
				(width 0.1)
				(type default)
			)
			(layer "F.SilkS")
		)
		(fp_line
			(start 8.080248 -0.882904)
			(end 9.12368 -1.883664)
			(stroke
				(width 0.1)
				(type default)
			)
			(layer "F.SilkS")
		)
		(fp_line
			(start 8.080248 -0.882904)
			(end 9.12368 -1.883664)
			(stroke
				(width 0.1)
				(type default)
			)
			(layer "F.SilkS")
		)
		(fp_line
			(start 8.140446 -0.882904)
			(end 8.200644 -0.882904)
			(stroke
				(width 0.1)
				(type default)
			)
			(layer "F.SilkS")
		)
		(fp_line
			(start 8.140446 -0.882904)
			(end 8.200644 -0.882904)
			(stroke
				(width 0.1)
				(type default)
			)
			(layer "F.SilkS")
		)
		(fp_line
			(start 8.140446 -0.882904)
			(end 9.111234 -1.814322)
			(stroke
				(width 0.1)
				(type default)
			)
			(layer "F.SilkS")
		)
		(fp_line
			(start 8.140446 -0.882904)
			(end 9.111234 -1.814322)
			(stroke
				(width 0.1)
				(type default)
			)
			(layer "F.SilkS")
		)
		(fp_line
			(start 8.18261 -2.943352)
			(end 8.170418 -2.87401)
			(stroke
				(width 0.1)
				(type default)
			)
			(layer "F.SilkS")
		)
		(fp_line
			(start 8.18261 -2.943352)
			(end 8.170418 -2.87401)
			(stroke
				(width 0.1)
				(type default)
			)
			(layer "F.SilkS")
		)
		(fp_line
			(start 8.194802 -3.012694)
			(end 8.18261 -2.943352)
			(stroke
				(width 0.1)
				(type default)
			)
			(layer "F.SilkS")
		)
		(fp_line
			(start 8.194802 -3.012694)
			(end 8.18261 -2.943352)
			(stroke
				(width 0.1)
				(type default)
			)
			(layer "F.SilkS")
		)
		(fp_line
			(start 8.200644 -0.882904)
			(end 8.260842 -0.882904)
			(stroke
				(width 0.1)
				(type default)
			)
			(layer "F.SilkS")
		)
		(fp_line
			(start 8.200644 -0.882904)
			(end 8.260842 -0.882904)
			(stroke
				(width 0.1)
				(type default)
			)
			(layer "F.SilkS")
		)
		(fp_line
			(start 8.200644 -0.882904)
			(end 9.099042 -1.744726)
			(stroke
				(width 0.1)
				(type default)
			)
			(layer "F.SilkS")
		)
		(fp_line
			(start 8.200644 -0.882904)
			(end 9.099042 -1.744726)
			(stroke
				(width 0.1)
				(type default)
			)
			(layer "F.SilkS")
		)
		(fp_line
			(start 8.206994 -3.08229)
			(end 8.194802 -3.012694)
			(stroke
				(width 0.1)
				(type default)
			)
			(layer "F.SilkS")
		)
		(fp_line
			(start 8.206994 -3.08229)
			(end 8.194802 -3.012694)
			(stroke
				(width 0.1)
				(type default)
			)
			(layer "F.SilkS")
		)
		(fp_line
			(start 8.219186 -3.151378)
			(end 8.206994 -3.08229)
			(stroke
				(width 0.1)
				(type default)
			)
			(layer "F.SilkS")
		)
		(fp_line
			(start 8.219186 -3.151378)
			(end 8.206994 -3.08229)
			(stroke
				(width 0.1)
				(type default)
			)
			(layer "F.SilkS")
		)
		(fp_line
			(start 8.231378 -3.22072)
			(end 8.219186 -3.151378)
			(stroke
				(width 0.1)
				(type default)
			)
			(layer "F.SilkS")
		)
		(fp_line
			(start 8.231378 -3.22072)
			(end 8.219186 -3.151378)
			(stroke
				(width 0.1)
				(type default)
			)
			(layer "F.SilkS")
		)
		(fp_line
			(start 8.24357 -3.290316)
			(end 8.231378 -3.22072)
			(stroke
				(width 0.1)
				(type default)
			)
			(layer "F.SilkS")
		)
		(fp_line
			(start 8.24357 -3.290316)
			(end 8.231378 -3.22072)
			(stroke
				(width 0.1)
				(type default)
			)
			(layer "F.SilkS")
		)
		(fp_line
			(start 8.255762 -3.359658)
			(end 8.24357 -3.290316)
			(stroke
				(width 0.1)
				(type default)
			)
			(layer "F.SilkS")
		)
		(fp_line
			(start 8.255762 -3.359658)
			(end 8.24357 -3.290316)
			(stroke
				(width 0.1)
				(type default)
			)
			(layer "F.SilkS")
		)
		(fp_line
			(start 8.260842 -0.882904)
			(end 8.320786 -0.882904)
			(stroke
				(width 0.1)
				(type default)
			)
			(layer "F.SilkS")
		)
		(fp_line
			(start 8.260842 -0.882904)
			(end 8.320786 -0.882904)
			(stroke
				(width 0.1)
				(type default)
			)
			(layer "F.SilkS")
		)
		(fp_line
			(start 8.260842 -0.882904)
			(end 9.087104 -1.675384)
			(stroke
				(width 0.1)
				(type default)
			)
			(layer "F.SilkS")
		)
		(fp_line
			(start 8.260842 -0.882904)
			(end 9.087104 -1.675384)
			(stroke
				(width 0.1)
				(type default)
			)
			(layer "F.SilkS")
		)
		(fp_line
			(start 8.2677 -3.429)
			(end 8.255762 -3.359658)
			(stroke
				(width 0.1)
				(type default)
			)
			(layer "F.SilkS")
		)
		(fp_line
			(start 8.2677 -3.429)
			(end 8.255762 -3.359658)
			(stroke
				(width 0.1)
				(type default)
			)
			(layer "F.SilkS")
		)
		(fp_line
			(start 8.279892 -3.498342)
			(end 8.2677 -3.429)
			(stroke
				(width 0.1)
				(type default)
			)
			(layer "F.SilkS")
		)
		(fp_line
			(start 8.279892 -3.498342)
			(end 8.2677 -3.429)
			(stroke
				(width 0.1)
				(type default)
			)
			(layer "F.SilkS")
		)
		(fp_line
			(start 8.292084 -3.567684)
			(end 8.279892 -3.498342)
			(stroke
				(width 0.1)
				(type default)
			)
			(layer "F.SilkS")
		)
		(fp_line
			(start 8.292084 -3.567684)
			(end 8.279892 -3.498342)
			(stroke
				(width 0.1)
				(type default)
			)
			(layer "F.SilkS")
		)
		(fp_line
			(start 8.304276 -3.63728)
			(end 8.292084 -3.567684)
			(stroke
				(width 0.1)
				(type default)
			)
			(layer "F.SilkS")
		)
		(fp_line
			(start 8.304276 -3.63728)
			(end 8.292084 -3.567684)
			(stroke
				(width 0.1)
				(type default)
			)
			(layer "F.SilkS")
		)
		(fp_line
			(start 8.316468 -3.706368)
			(end 8.304276 -3.63728)
			(stroke
				(width 0.1)
				(type default)
			)
			(layer "F.SilkS")
		)
		(fp_line
			(start 8.316468 -3.706368)
			(end 8.304276 -3.63728)
			(stroke
				(width 0.1)
				(type default)
			)
			(layer "F.SilkS")
		)
		(fp_line
			(start 8.320786 -0.882904)
			(end 8.381238 -0.882904)
			(stroke
				(width 0.1)
				(type default)
			)
			(layer "F.SilkS")
		)
		(fp_line
			(start 8.320786 -0.882904)
			(end 8.381238 -0.882904)
			(stroke
				(width 0.1)
				(type default)
			)
			(layer "F.SilkS")
		)
		(fp_line
			(start 8.320786 -0.882904)
			(end 9.074912 -1.606296)
			(stroke
				(width 0.1)
				(type default)
			)
			(layer "F.SilkS")
		)
		(fp_line
			(start 8.320786 -0.882904)
			(end 9.074912 -1.606296)
			(stroke
				(width 0.1)
				(type default)
			)
			(layer "F.SilkS")
		)
		(fp_line
			(start 8.32866 -3.77571)
			(end 8.316468 -3.706368)
			(stroke
				(width 0.1)
				(type default)
			)
			(layer "F.SilkS")
		)
		(fp_line
			(start 8.32866 -3.77571)
			(end 8.316468 -3.706368)
			(stroke
				(width 0.1)
				(type default)
			)
			(layer "F.SilkS")
		)
		(fp_line
			(start 8.340852 -3.845306)
			(end 8.32866 -3.77571)
			(stroke
				(width 0.1)
				(type default)
			)
			(layer "F.SilkS")
		)
		(fp_line
			(start 8.340852 -3.845306)
			(end 8.32866 -3.77571)
			(stroke
				(width 0.1)
				(type default)
			)
			(layer "F.SilkS")
		)
		(fp_line
			(start 8.35279 -3.914648)
			(end 8.340852 -3.845306)
			(stroke
				(width 0.1)
				(type default)
			)
			(layer "F.SilkS")
		)
		(fp_line
			(start 8.35279 -3.914648)
			(end 8.340852 -3.845306)
			(stroke
				(width 0.1)
				(type default)
			)
			(layer "F.SilkS")
		)
		(fp_line
			(start 8.365236 -3.98399)
			(end 8.35279 -3.914648)
			(stroke
				(width 0.1)
				(type default)
			)
			(layer "F.SilkS")
		)
		(fp_line
			(start 8.365236 -3.98399)
			(end 8.35279 -3.914648)
			(stroke
				(width 0.1)
				(type default)
			)
			(layer "F.SilkS")
		)
		(fp_line
			(start 8.377174 -4.053332)
			(end 8.365236 -3.98399)
			(stroke
				(width 0.1)
				(type default)
			)
			(layer "F.SilkS")
		)
		(fp_line
			(start 8.377174 -4.053332)
			(end 8.365236 -3.98399)
			(stroke
				(width 0.1)
				(type default)
			)
			(layer "F.SilkS")
		)
		(fp_line
			(start 8.381238 -0.882904)
			(end 8.441182 -0.882904)
			(stroke
				(width 0.1)
				(type default)
			)
			(layer "F.SilkS")
		)
		(fp_line
			(start 8.381238 -0.882904)
			(end 8.441182 -0.882904)
			(stroke
				(width 0.1)
				(type default)
			)
			(layer "F.SilkS")
		)
		(fp_line
			(start 8.381238 -0.882904)
			(end 9.062466 -1.5367)
			(stroke
				(width 0.1)
				(type default)
			)
			(layer "F.SilkS")
		)
		(fp_line
			(start 8.381238 -0.882904)
			(end 9.062466 -1.5367)
			(stroke
				(width 0.1)
				(type default)
			)
			(layer "F.SilkS")
		)
		(fp_line
			(start 8.389366 -4.122674)
			(end 8.377174 -4.053332)
			(stroke
				(width 0.1)
				(type default)
			)
			(layer "F.SilkS")
		)
		(fp_line
			(start 8.389366 -4.122674)
			(end 8.377174 -4.053332)
			(stroke
				(width 0.1)
				(type default)
			)
			(layer "F.SilkS")
		)
		(fp_line
			(start 8.401558 -4.19227)
			(end 8.389366 -4.122674)
			(stroke
				(width 0.1)
				(type default)
			)
			(layer "F.SilkS")
		)
		(fp_line
			(start 8.401558 -4.19227)
			(end 8.389366 -4.122674)
			(stroke
				(width 0.1)
				(type default)
			)
			(layer "F.SilkS")
		)
		(fp_line
			(start 8.41375 -4.261612)
			(end 8.401558 -4.19227)
			(stroke
				(width 0.1)
				(type default)
			)
			(layer "F.SilkS")
		)
		(fp_line
			(start 8.41375 -4.261612)
			(end 8.401558 -4.19227)
			(stroke
				(width 0.1)
				(type default)
			)
			(layer "F.SilkS")
		)
		(fp_line
			(start 8.425942 -4.3307)
			(end 8.41375 -4.261612)
			(stroke
				(width 0.1)
				(type default)
			)
			(layer "F.SilkS")
		)
		(fp_line
			(start 8.425942 -4.3307)
			(end 8.41375 -4.261612)
			(stroke
				(width 0.1)
				(type default)
			)
			(layer "F.SilkS")
		)
		(fp_line
			(start 8.43788 -4.400296)
			(end 8.425942 -4.3307)
			(stroke
				(width 0.1)
				(type default)
			)
			(layer "F.SilkS")
		)
		(fp_line
			(start 8.43788 -4.400296)
			(end 8.425942 -4.3307)
			(stroke
				(width 0.1)
				(type default)
			)
			(layer "F.SilkS")
		)
		(fp_line
			(start 8.441182 -0.882904)
			(end 8.50138 -0.882904)
			(stroke
				(width 0.1)
				(type default)
			)
			(layer "F.SilkS")
		)
		(fp_line
			(start 8.441182 -0.882904)
			(end 8.50138 -0.882904)
			(stroke
				(width 0.1)
				(type default)
			)
			(layer "F.SilkS")
		)
		(fp_line
			(start 8.441182 -0.882904)
			(end 9.050274 -1.467104)
			(stroke
				(width 0.1)
				(type default)
			)
			(layer "F.SilkS")
		)
		(fp_line
			(start 8.441182 -0.882904)
			(end 9.050274 -1.467104)
			(stroke
				(width 0.1)
				(type default)
			)
			(layer "F.SilkS")
		)
		(fp_line
			(start 8.450326 -4.469638)
			(end 8.43788 -4.400296)
			(stroke
				(width 0.1)
				(type default)
			)
			(layer "F.SilkS")
		)
		(fp_line
			(start 8.450326 -4.469638)
			(end 8.43788 -4.400296)
			(stroke
				(width 0.1)
				(type default)
			)
			(layer "F.SilkS")
		)
		(fp_line
			(start 8.450326 -4.469638)
			(end 8.462264 -4.53898)
			(stroke
				(width 0.1)
				(type default)
			)
			(layer "F.SilkS")
		)
		(fp_line
			(start 8.450326 -4.469638)
			(end 8.462264 -4.53898)
			(stroke
				(width 0.1)
				(type default)
			)
			(layer "F.SilkS")
		)
		(fp_line
			(start 8.462264 -4.53898)
			(end 8.474456 -4.608322)
			(stroke
				(width 0.1)
				(type default)
			)
			(layer "F.SilkS")
		)
		(fp_line
			(start 8.462264 -4.53898)
			(end 8.474456 -4.608322)
			(stroke
				(width 0.1)
				(type default)
			)
			(layer "F.SilkS")
		)
		(fp_line
			(start 8.474456 -4.608322)
			(end 8.486648 -4.677664)
			(stroke
				(width 0.1)
				(type default)
			)
			(layer "F.SilkS")
		)
		(fp_line
			(start 8.474456 -4.608322)
			(end 8.486648 -4.677664)
			(stroke
				(width 0.1)
				(type default)
			)
			(layer "F.SilkS")
		)
		(fp_line
			(start 8.486648 -4.677664)
			(end 8.49884 -4.74726)
			(stroke
				(width 0.1)
				(type default)
			)
			(layer "F.SilkS")
		)
		(fp_line
			(start 8.486648 -4.677664)
			(end 8.49884 -4.74726)
			(stroke
				(width 0.1)
				(type default)
			)
			(layer "F.SilkS")
		)
		(fp_line
			(start 8.49884 -4.74726)
			(end 8.511032 -4.816602)
			(stroke
				(width 0.1)
				(type default)
			)
			(layer "F.SilkS")
		)
		(fp_line
			(start 8.49884 -4.74726)
			(end 8.511032 -4.816602)
			(stroke
				(width 0.1)
				(type default)
			)
			(layer "F.SilkS")
		)
		(fp_line
			(start 8.50138 -0.882904)
			(end 8.561578 -0.882904)
			(stroke
				(width 0.1)
				(type default)
			)
			(layer "F.SilkS")
		)
		(fp_line
			(start 8.50138 -0.882904)
			(end 8.561578 -0.882904)
			(stroke
				(width 0.1)
				(type default)
			)
			(layer "F.SilkS")
		)
		(fp_line
			(start 8.50138 -0.882904)
			(end 9.038082 -1.397762)
			(stroke
				(width 0.1)
				(type default)
			)
			(layer "F.SilkS")
		)
		(fp_line
			(start 8.50138 -0.882904)
			(end 9.038082 -1.397762)
			(stroke
				(width 0.1)
				(type default)
			)
			(layer "F.SilkS")
		)
		(fp_line
			(start 8.511032 -4.816602)
			(end 8.52297 -4.88569)
			(stroke
				(width 0.1)
				(type default)
			)
			(layer "F.SilkS")
		)
		(fp_line
			(start 8.511032 -4.816602)
			(end 8.52297 -4.88569)
			(stroke
				(width 0.1)
				(type default)
			)
			(layer "F.SilkS")
		)
		(fp_line
			(start 8.52297 -4.88569)
			(end 8.535416 -4.955286)
			(stroke
				(width 0.1)
				(type default)
			)
			(layer "F.SilkS")
		)
		(fp_line
			(start 8.52297 -4.88569)
			(end 8.535416 -4.955286)
			(stroke
				(width 0.1)
				(type default)
			)
			(layer "F.SilkS")
		)
		(fp_line
			(start 8.535416 -4.955286)
			(end 8.547608 -5.024628)
			(stroke
				(width 0.1)
				(type default)
			)
			(layer "F.SilkS")
		)
		(fp_line
			(start 8.535416 -4.955286)
			(end 8.547608 -5.024628)
			(stroke
				(width 0.1)
				(type default)
			)
			(layer "F.SilkS")
		)
		(fp_line
			(start 8.547608 -5.024628)
			(end 8.559546 -5.09397)
			(stroke
				(width 0.1)
				(type default)
			)
			(layer "F.SilkS")
		)
		(fp_line
			(start 8.547608 -5.024628)
			(end 8.559546 -5.09397)
			(stroke
				(width 0.1)
				(type default)
			)
			(layer "F.SilkS")
		)
		(fp_line
			(start 8.559546 -5.09397)
			(end 8.571738 -5.163312)
			(stroke
				(width 0.1)
				(type default)
			)
			(layer "F.SilkS")
		)
		(fp_line
			(start 8.559546 -5.09397)
			(end 8.571738 -5.163312)
			(stroke
				(width 0.1)
				(type default)
			)
			(layer "F.SilkS")
		)
		(fp_line
			(start 8.561578 -0.882904)
			(end 8.621522 -0.882904)
			(stroke
				(width 0.1)
				(type default)
			)
			(layer "F.SilkS")
		)
		(fp_line
			(start 8.561578 -0.882904)
			(end 8.621522 -0.882904)
			(stroke
				(width 0.1)
				(type default)
			)
			(layer "F.SilkS")
		)
		(fp_line
			(start 8.561578 -0.882904)
			(end 9.026144 -1.32842)
			(stroke
				(width 0.1)
				(type default)
			)
			(layer "F.SilkS")
		)
		(fp_line
			(start 8.561578 -0.882904)
			(end 9.026144 -1.32842)
			(stroke
				(width 0.1)
				(type default)
			)
			(layer "F.SilkS")
		)
		(fp_line
			(start 8.573262 -5.171694)
			(end 8.571738 -5.163312)
			(stroke
				(width 0.1)
				(type default)
			)
			(layer "F.SilkS")
		)
		(fp_line
			(start 8.573262 -5.171694)
			(end 8.571738 -5.163312)
			(stroke
				(width 0.1)
				(type default)
			)
			(layer "F.SilkS")
		)
		(fp_line
			(start 8.580374 -5.171694)
			(end 8.571738 -5.163312)
			(stroke
				(width 0.1)
				(type default)
			)
			(layer "F.SilkS")
		)
		(fp_line
			(start 8.580374 -5.171694)
			(end 8.571738 -5.163312)
			(stroke
				(width 0.1)
				(type default)
			)
			(layer "F.SilkS")
		)
		(fp_line
			(start 8.580374 -5.171694)
			(end 8.573262 -5.171694)
			(stroke
				(width 0.1)
				(type default)
			)
			(layer "F.SilkS")
		)
		(fp_line
			(start 8.580374 -5.171694)
			(end 8.573262 -5.171694)
			(stroke
				(width 0.1)
				(type default)
			)
			(layer "F.SilkS")
		)
		(fp_line
			(start 8.621522 -0.882904)
			(end 8.681974 -0.882904)
			(stroke
				(width 0.1)
				(type default)
			)
			(layer "F.SilkS")
		)
		(fp_line
			(start 8.621522 -0.882904)
			(end 8.681974 -0.882904)
			(stroke
				(width 0.1)
				(type default)
			)
			(layer "F.SilkS")
		)
		(fp_line
			(start 8.621522 -0.882904)
			(end 9.013952 -1.259078)
			(stroke
				(width 0.1)
				(type default)
			)
			(layer "F.SilkS")
		)
		(fp_line
			(start 8.621522 -0.882904)
			(end 9.013952 -1.259078)
			(stroke
				(width 0.1)
				(type default)
			)
			(layer "F.SilkS")
		)
		(fp_line
			(start 8.640572 -5.171694)
			(end 8.559546 -5.09397)
			(stroke
				(width 0.1)
				(type default)
			)
			(layer "F.SilkS")
		)
		(fp_line
			(start 8.640572 -5.171694)
			(end 8.559546 -5.09397)
			(stroke
				(width 0.1)
				(type default)
			)
			(layer "F.SilkS")
		)
		(fp_line
			(start 8.640572 -5.171694)
			(end 8.580374 -5.171694)
			(stroke
				(width 0.1)
				(type default)
			)
			(layer "F.SilkS")
		)
		(fp_line
			(start 8.640572 -5.171694)
			(end 8.580374 -5.171694)
			(stroke
				(width 0.1)
				(type default)
			)
			(layer "F.SilkS")
		)
		(fp_line
			(start 8.681974 -0.882904)
			(end 8.741918 -0.882904)
			(stroke
				(width 0.1)
				(type default)
			)
			(layer "F.SilkS")
		)
		(fp_line
			(start 8.681974 -0.882904)
			(end 8.741918 -0.882904)
			(stroke
				(width 0.1)
				(type default)
			)
			(layer "F.SilkS")
		)
		(fp_line
			(start 8.681974 -0.882904)
			(end 9.001506 -1.189482)
			(stroke
				(width 0.1)
				(type default)
			)
			(layer "F.SilkS")
		)
		(fp_line
			(start 8.681974 -0.882904)
			(end 9.001506 -1.189482)
			(stroke
				(width 0.1)
				(type default)
			)
			(layer "F.SilkS")
		)
		(fp_line
			(start 8.70077 -5.171694)
			(end 8.547608 -5.024628)
			(stroke
				(width 0.1)
				(type default)
			)
			(layer "F.SilkS")
		)
		(fp_line
			(start 8.70077 -5.171694)
			(end 8.547608 -5.024628)
			(stroke
				(width 0.1)
				(type default)
			)
			(layer "F.SilkS")
		)
		(fp_line
			(start 8.70077 -5.171694)
			(end 8.640572 -5.171694)
			(stroke
				(width 0.1)
				(type default)
			)
			(layer "F.SilkS")
		)
		(fp_line
			(start 8.70077 -5.171694)
			(end 8.640572 -5.171694)
			(stroke
				(width 0.1)
				(type default)
			)
			(layer "F.SilkS")
		)
		(fp_line
			(start 8.741918 -0.882904)
			(end 8.802116 -0.882904)
			(stroke
				(width 0.1)
				(type default)
			)
			(layer "F.SilkS")
		)
		(fp_line
			(start 8.741918 -0.882904)
			(end 8.802116 -0.882904)
			(stroke
				(width 0.1)
				(type default)
			)
			(layer "F.SilkS")
		)
		(fp_line
			(start 8.741918 -0.882904)
			(end 8.989314 -1.12014)
			(stroke
				(width 0.1)
				(type default)
			)
			(layer "F.SilkS")
		)
		(fp_line
			(start 8.741918 -0.882904)
			(end 8.989314 -1.12014)
			(stroke
				(width 0.1)
				(type default)
			)
			(layer "F.SilkS")
		)
		(fp_line
			(start 8.760968 -5.171694)
			(end 8.535416 -4.955286)
			(stroke
				(width 0.1)
				(type default)
			)
			(layer "F.SilkS")
		)
		(fp_line
			(start 8.760968 -5.171694)
			(end 8.535416 -4.955286)
			(stroke
				(width 0.1)
				(type default)
			)
			(layer "F.SilkS")
		)
		(fp_line
			(start 8.760968 -5.171694)
			(end 8.70077 -5.171694)
			(stroke
				(width 0.1)
				(type default)
			)
			(layer "F.SilkS")
		)
		(fp_line
			(start 8.760968 -5.171694)
			(end 8.70077 -5.171694)
			(stroke
				(width 0.1)
				(type default)
			)
			(layer "F.SilkS")
		)
		(fp_line
			(start 8.802116 -0.882904)
			(end 8.862314 -0.882904)
			(stroke
				(width 0.1)
				(type default)
			)
			(layer "F.SilkS")
		)
		(fp_line
			(start 8.802116 -0.882904)
			(end 8.862314 -0.882904)
			(stroke
				(width 0.1)
				(type default)
			)
			(layer "F.SilkS")
		)
		(fp_line
			(start 8.802116 -0.882904)
			(end 8.977122 -1.050798)
			(stroke
				(width 0.1)
				(type default)
			)
			(layer "F.SilkS")
		)
		(fp_line
			(start 8.802116 -0.882904)
			(end 8.977122 -1.050798)
			(stroke
				(width 0.1)
				(type default)
			)
			(layer "F.SilkS")
		)
		(fp_line
			(start 8.821166 -5.171694)
			(end 8.52297 -4.88569)
			(stroke
				(width 0.1)
				(type default)
			)
			(layer "F.SilkS")
		)
		(fp_line
			(start 8.821166 -5.171694)
			(end 8.52297 -4.88569)
			(stroke
				(width 0.1)
				(type default)
			)
			(layer "F.SilkS")
		)
		(fp_line
			(start 8.821166 -5.171694)
			(end 8.760968 -5.171694)
			(stroke
				(width 0.1)
				(type default)
			)
			(layer "F.SilkS")
		)
		(fp_line
			(start 8.821166 -5.171694)
			(end 8.760968 -5.171694)
			(stroke
				(width 0.1)
				(type default)
			)
			(layer "F.SilkS")
		)
		(fp_line
			(start 8.862314 -0.882904)
			(end 8.922512 -0.882904)
			(stroke
				(width 0.1)
				(type default)
			)
			(layer "F.SilkS")
		)
		(fp_line
			(start 8.862314 -0.882904)
			(end 8.922512 -0.882904)
			(stroke
				(width 0.1)
				(type default)
			)
			(layer "F.SilkS")
		)
		(fp_line
			(start 8.862314 -0.882904)
			(end 8.965184 -0.981456)
			(stroke
				(width 0.1)
				(type default)
			)
			(layer "F.SilkS")
		)
		(fp_line
			(start 8.862314 -0.882904)
			(end 8.965184 -0.981456)
			(stroke
				(width 0.1)
				(type default)
			)
			(layer "F.SilkS")
		)
		(fp_line
			(start 8.88111 -5.171694)
			(end 8.511032 -4.816602)
			(stroke
				(width 0.1)
				(type default)
			)
			(layer "F.SilkS")
		)
		(fp_line
			(start 8.88111 -5.171694)
			(end 8.511032 -4.816602)
			(stroke
				(width 0.1)
				(type default)
			)
			(layer "F.SilkS")
		)
		(fp_line
			(start 8.88111 -5.171694)
			(end 8.821166 -5.171694)
			(stroke
				(width 0.1)
				(type default)
			)
			(layer "F.SilkS")
		)
		(fp_line
			(start 8.88111 -5.171694)
			(end 8.821166 -5.171694)
			(stroke
				(width 0.1)
				(type default)
			)
			(layer "F.SilkS")
		)
		(fp_line
			(start 8.922512 -0.882904)
			(end 8.947658 -0.882904)
			(stroke
				(width 0.1)
				(type default)
			)
			(layer "F.SilkS")
		)
		(fp_line
			(start 8.922512 -0.882904)
			(end 8.947658 -0.882904)
			(stroke
				(width 0.1)
				(type default)
			)
			(layer "F.SilkS")
		)
		(fp_line
			(start 8.922512 -0.882904)
			(end 8.952738 -0.91186)
			(stroke
				(width 0.1)
				(type default)
			)
			(layer "F.SilkS")
		)
		(fp_line
			(start 8.922512 -0.882904)
			(end 8.952738 -0.91186)
			(stroke
				(width 0.1)
				(type default)
			)
			(layer "F.SilkS")
		)
		(fp_line
			(start 8.941308 -5.171694)
			(end 8.49884 -4.74726)
			(stroke
				(width 0.1)
				(type default)
			)
			(layer "F.SilkS")
		)
		(fp_line
			(start 8.941308 -5.171694)
			(end 8.49884 -4.74726)
			(stroke
				(width 0.1)
				(type default)
			)
			(layer "F.SilkS")
		)
		(fp_line
			(start 8.941308 -5.171694)
			(end 8.88111 -5.171694)
			(stroke
				(width 0.1)
				(type default)
			)
			(layer "F.SilkS")
		)
		(fp_line
			(start 8.941308 -5.171694)
			(end 8.88111 -5.171694)
			(stroke
				(width 0.1)
				(type default)
			)
			(layer "F.SilkS")
		)
		(fp_line
			(start 8.947658 -0.882904)
			(end 8.952738 -0.91186)
			(stroke
				(width 0.1)
				(type default)
			)
			(layer "F.SilkS")
		)
		(fp_line
			(start 8.947658 -0.882904)
			(end 8.952738 -0.91186)
			(stroke
				(width 0.1)
				(type default)
			)
			(layer "F.SilkS")
		)
		(fp_line
			(start 8.965184 -0.981456)
			(end 8.952738 -0.91186)
			(stroke
				(width 0.1)
				(type default)
			)
			(layer "F.SilkS")
		)
		(fp_line
			(start 8.965184 -0.981456)
			(end 8.952738 -0.91186)
			(stroke
				(width 0.1)
				(type default)
			)
			(layer "F.SilkS")
		)
		(fp_line
			(start 8.977122 -1.050798)
			(end 8.965184 -0.981456)
			(stroke
				(width 0.1)
				(type default)
			)
			(layer "F.SilkS")
		)
		(fp_line
			(start 8.977122 -1.050798)
			(end 8.965184 -0.981456)
			(stroke
				(width 0.1)
				(type default)
			)
			(layer "F.SilkS")
		)
		(fp_line
			(start 8.989314 -1.12014)
			(end 8.977122 -1.050798)
			(stroke
				(width 0.1)
				(type default)
			)
			(layer "F.SilkS")
		)
		(fp_line
			(start 8.989314 -1.12014)
			(end 8.977122 -1.050798)
			(stroke
				(width 0.1)
				(type default)
			)
			(layer "F.SilkS")
		)
		(fp_line
			(start 9.001506 -5.171694)
			(end 8.486648 -4.677664)
			(stroke
				(width 0.1)
				(type default)
			)
			(layer "F.SilkS")
		)
		(fp_line
			(start 9.001506 -5.171694)
			(end 8.486648 -4.677664)
			(stroke
				(width 0.1)
				(type default)
			)
			(layer "F.SilkS")
		)
		(fp_line
			(start 9.001506 -5.171694)
			(end 8.941308 -5.171694)
			(stroke
				(width 0.1)
				(type default)
			)
			(layer "F.SilkS")
		)
		(fp_line
			(start 9.001506 -5.171694)
			(end 8.941308 -5.171694)
			(stroke
				(width 0.1)
				(type default)
			)
			(layer "F.SilkS")
		)
		(fp_line
			(start 9.001506 -1.189482)
			(end 8.989314 -1.12014)
			(stroke
				(width 0.1)
				(type default)
			)
			(layer "F.SilkS")
		)
		(fp_line
			(start 9.001506 -1.189482)
			(end 8.989314 -1.12014)
			(stroke
				(width 0.1)
				(type default)
			)
			(layer "F.SilkS")
		)
		(fp_line
			(start 9.013952 -1.259078)
			(end 9.001506 -1.189482)
			(stroke
				(width 0.1)
				(type default)
			)
			(layer "F.SilkS")
		)
		(fp_line
			(start 9.013952 -1.259078)
			(end 9.001506 -1.189482)
			(stroke
				(width 0.1)
				(type default)
			)
			(layer "F.SilkS")
		)
		(fp_line
			(start 9.026144 -1.32842)
			(end 9.013952 -1.259078)
			(stroke
				(width 0.1)
				(type default)
			)
			(layer "F.SilkS")
		)
		(fp_line
			(start 9.026144 -1.32842)
			(end 9.013952 -1.259078)
			(stroke
				(width 0.1)
				(type default)
			)
			(layer "F.SilkS")
		)
		(fp_line
			(start 9.038082 -1.397762)
			(end 9.026144 -1.32842)
			(stroke
				(width 0.1)
				(type default)
			)
			(layer "F.SilkS")
		)
		(fp_line
			(start 9.038082 -1.397762)
			(end 9.026144 -1.32842)
			(stroke
				(width 0.1)
				(type default)
			)
			(layer "F.SilkS")
		)
		(fp_line
			(start 9.050274 -1.467104)
			(end 9.038082 -1.397762)
			(stroke
				(width 0.1)
				(type default)
			)
			(layer "F.SilkS")
		)
		(fp_line
			(start 9.050274 -1.467104)
			(end 9.038082 -1.397762)
			(stroke
				(width 0.1)
				(type default)
			)
			(layer "F.SilkS")
		)
		(fp_line
			(start 9.061704 -5.171694)
			(end 8.474456 -4.608322)
			(stroke
				(width 0.1)
				(type default)
			)
			(layer "F.SilkS")
		)
		(fp_line
			(start 9.061704 -5.171694)
			(end 8.474456 -4.608322)
			(stroke
				(width 0.1)
				(type default)
			)
			(layer "F.SilkS")
		)
		(fp_line
			(start 9.061704 -5.171694)
			(end 9.001506 -5.171694)
			(stroke
				(width 0.1)
				(type default)
			)
			(layer "F.SilkS")
		)
		(fp_line
			(start 9.061704 -5.171694)
			(end 9.001506 -5.171694)
			(stroke
				(width 0.1)
				(type default)
			)
			(layer "F.SilkS")
		)
		(fp_line
			(start 9.062466 -1.5367)
			(end 9.050274 -1.467104)
			(stroke
				(width 0.1)
				(type default)
			)
			(layer "F.SilkS")
		)
		(fp_line
			(start 9.062466 -1.5367)
			(end 9.050274 -1.467104)
			(stroke
				(width 0.1)
				(type default)
			)
			(layer "F.SilkS")
		)
		(fp_line
			(start 9.074912 -1.606296)
			(end 9.062466 -1.5367)
			(stroke
				(width 0.1)
				(type default)
			)
			(layer "F.SilkS")
		)
		(fp_line
			(start 9.074912 -1.606296)
			(end 9.062466 -1.5367)
			(stroke
				(width 0.1)
				(type default)
			)
			(layer "F.SilkS")
		)
		(fp_line
			(start 9.087104 -1.675384)
			(end 9.074912 -1.606296)
			(stroke
				(width 0.1)
				(type default)
			)
			(layer "F.SilkS")
		)
		(fp_line
			(start 9.087104 -1.675384)
			(end 9.074912 -1.606296)
			(stroke
				(width 0.1)
				(type default)
			)
			(layer "F.SilkS")
		)
		(fp_line
			(start 9.099042 -1.744726)
			(end 9.087104 -1.675384)
			(stroke
				(width 0.1)
				(type default)
			)
			(layer "F.SilkS")
		)
		(fp_line
			(start 9.099042 -1.744726)
			(end 9.087104 -1.675384)
			(stroke
				(width 0.1)
				(type default)
			)
			(layer "F.SilkS")
		)
		(fp_line
			(start 9.111234 -1.814322)
			(end 9.099042 -1.744726)
			(stroke
				(width 0.1)
				(type default)
			)
			(layer "F.SilkS")
		)
		(fp_line
			(start 9.111234 -1.814322)
			(end 9.099042 -1.744726)
			(stroke
				(width 0.1)
				(type default)
			)
			(layer "F.SilkS")
		)
		(fp_line
			(start 9.121902 -5.171694)
			(end 8.462264 -4.53898)
			(stroke
				(width 0.1)
				(type default)
			)
			(layer "F.SilkS")
		)
		(fp_line
			(start 9.121902 -5.171694)
			(end 8.462264 -4.53898)
			(stroke
				(width 0.1)
				(type default)
			)
			(layer "F.SilkS")
		)
		(fp_line
			(start 9.121902 -5.171694)
			(end 9.061704 -5.171694)
			(stroke
				(width 0.1)
				(type default)
			)
			(layer "F.SilkS")
		)
		(fp_line
			(start 9.121902 -5.171694)
			(end 9.061704 -5.171694)
			(stroke
				(width 0.1)
				(type default)
			)
			(layer "F.SilkS")
		)
		(fp_line
			(start 9.12368 -1.883664)
			(end 9.111234 -1.814322)
			(stroke
				(width 0.1)
				(type default)
			)
			(layer "F.SilkS")
		)
		(fp_line
			(start 9.12368 -1.883664)
			(end 9.111234 -1.814322)
			(stroke
				(width 0.1)
				(type default)
			)
			(layer "F.SilkS")
		)
		(fp_line
			(start 9.135872 -1.953006)
			(end 9.12368 -1.883664)
			(stroke
				(width 0.1)
				(type default)
			)
			(layer "F.SilkS")
		)
		(fp_line
			(start 9.135872 -1.953006)
			(end 9.12368 -1.883664)
			(stroke
				(width 0.1)
				(type default)
			)
			(layer "F.SilkS")
		)
		(fp_line
			(start 9.148064 -2.022602)
			(end 9.135872 -1.953006)
			(stroke
				(width 0.1)
				(type default)
			)
			(layer "F.SilkS")
		)
		(fp_line
			(start 9.148064 -2.022602)
			(end 9.135872 -1.953006)
			(stroke
				(width 0.1)
				(type default)
			)
			(layer "F.SilkS")
		)
		(fp_line
			(start 9.160002 -2.091944)
			(end 9.148064 -2.022602)
			(stroke
				(width 0.1)
				(type default)
			)
			(layer "F.SilkS")
		)
		(fp_line
			(start 9.160002 -2.091944)
			(end 9.148064 -2.022602)
			(stroke
				(width 0.1)
				(type default)
			)
			(layer "F.SilkS")
		)
		(fp_line
			(start 9.172194 -2.161286)
			(end 9.160002 -2.091944)
			(stroke
				(width 0.1)
				(type default)
			)
			(layer "F.SilkS")
		)
		(fp_line
			(start 9.172194 -2.161286)
			(end 9.160002 -2.091944)
			(stroke
				(width 0.1)
				(type default)
			)
			(layer "F.SilkS")
		)
		(fp_line
			(start 9.172194 -2.161286)
			(end 9.18464 -2.230882)
			(stroke
				(width 0.1)
				(type default)
			)
			(layer "F.SilkS")
		)
		(fp_line
			(start 9.172194 -2.161286)
			(end 9.18464 -2.230882)
			(stroke
				(width 0.1)
				(type default)
			)
			(layer "F.SilkS")
		)
		(fp_line
			(start 9.181846 -5.171694)
			(end 8.450326 -4.469638)
			(stroke
				(width 0.1)
				(type default)
			)
			(layer "F.SilkS")
		)
		(fp_line
			(start 9.181846 -5.171694)
			(end 8.450326 -4.469638)
			(stroke
				(width 0.1)
				(type default)
			)
			(layer "F.SilkS")
		)
		(fp_line
			(start 9.181846 -5.171694)
			(end 9.121902 -5.171694)
			(stroke
				(width 0.1)
				(type default)
			)
			(layer "F.SilkS")
		)
		(fp_line
			(start 9.181846 -5.171694)
			(end 9.121902 -5.171694)
			(stroke
				(width 0.1)
				(type default)
			)
			(layer "F.SilkS")
		)
		(fp_line
			(start 9.18464 -2.230882)
			(end 9.196832 -2.300224)
			(stroke
				(width 0.1)
				(type default)
			)
			(layer "F.SilkS")
		)
		(fp_line
			(start 9.18464 -2.230882)
			(end 9.196832 -2.300224)
			(stroke
				(width 0.1)
				(type default)
			)
			(layer "F.SilkS")
		)
		(fp_line
			(start 9.196832 -2.300224)
			(end 9.209024 -2.369566)
			(stroke
				(width 0.1)
				(type default)
			)
			(layer "F.SilkS")
		)
		(fp_line
			(start 9.196832 -2.300224)
			(end 9.209024 -2.369566)
			(stroke
				(width 0.1)
				(type default)
			)
			(layer "F.SilkS")
		)
		(fp_line
			(start 9.209024 -2.369566)
			(end 9.220962 -2.438908)
			(stroke
				(width 0.1)
				(type default)
			)
			(layer "F.SilkS")
		)
		(fp_line
			(start 9.209024 -2.369566)
			(end 9.220962 -2.438908)
			(stroke
				(width 0.1)
				(type default)
			)
			(layer "F.SilkS")
		)
		(fp_line
			(start 9.220962 -2.438908)
			(end 9.233408 -2.508504)
			(stroke
				(width 0.1)
				(type default)
			)
			(layer "F.SilkS")
		)
		(fp_line
			(start 9.220962 -2.438908)
			(end 9.233408 -2.508504)
			(stroke
				(width 0.1)
				(type default)
			)
			(layer "F.SilkS")
		)
		(fp_line
			(start 9.233408 -2.508504)
			(end 9.2456 -2.577592)
			(stroke
				(width 0.1)
				(type default)
			)
			(layer "F.SilkS")
		)
		(fp_line
			(start 9.233408 -2.508504)
			(end 9.2456 -2.577592)
			(stroke
				(width 0.1)
				(type default)
			)
			(layer "F.SilkS")
		)
		(fp_line
			(start 9.242298 -5.171694)
			(end 8.43788 -4.400296)
			(stroke
				(width 0.1)
				(type default)
			)
			(layer "F.SilkS")
		)
		(fp_line
			(start 9.242298 -5.171694)
			(end 8.43788 -4.400296)
			(stroke
				(width 0.1)
				(type default)
			)
			(layer "F.SilkS")
		)
		(fp_line
			(start 9.242298 -5.171694)
			(end 9.181846 -5.171694)
			(stroke
				(width 0.1)
				(type default)
			)
			(layer "F.SilkS")
		)
		(fp_line
			(start 9.242298 -5.171694)
			(end 9.181846 -5.171694)
			(stroke
				(width 0.1)
				(type default)
			)
			(layer "F.SilkS")
		)
		(fp_line
			(start 9.2456 -2.577592)
			(end 9.257792 -2.647188)
			(stroke
				(width 0.1)
				(type default)
			)
			(layer "F.SilkS")
		)
		(fp_line
			(start 9.2456 -2.577592)
			(end 9.257792 -2.647188)
			(stroke
				(width 0.1)
				(type default)
			)
			(layer "F.SilkS")
		)
		(fp_line
			(start 9.257792 -2.647188)
			(end 9.269984 -2.716784)
			(stroke
				(width 0.1)
				(type default)
			)
			(layer "F.SilkS")
		)
		(fp_line
			(start 9.257792 -2.647188)
			(end 9.269984 -2.716784)
			(stroke
				(width 0.1)
				(type default)
			)
			(layer "F.SilkS")
		)
		(fp_line
			(start 9.269984 -2.716784)
			(end 9.281922 -2.786126)
			(stroke
				(width 0.1)
				(type default)
			)
			(layer "F.SilkS")
		)
		(fp_line
			(start 9.269984 -2.716784)
			(end 9.281922 -2.786126)
			(stroke
				(width 0.1)
				(type default)
			)
			(layer "F.SilkS")
		)
		(fp_line
			(start 9.281922 -2.786126)
			(end 9.294368 -2.855468)
			(stroke
				(width 0.1)
				(type default)
			)
			(layer "F.SilkS")
		)
		(fp_line
			(start 9.281922 -2.786126)
			(end 9.294368 -2.855468)
			(stroke
				(width 0.1)
				(type default)
			)
			(layer "F.SilkS")
		)
		(fp_line
			(start 9.294368 -2.855468)
			(end 9.30656 -2.925064)
			(stroke
				(width 0.1)
				(type default)
			)
			(layer "F.SilkS")
		)
		(fp_line
			(start 9.294368 -2.855468)
			(end 9.30656 -2.925064)
			(stroke
				(width 0.1)
				(type default)
			)
			(layer "F.SilkS")
		)
		(fp_line
			(start 9.302242 -5.171694)
			(end 8.425942 -4.3307)
			(stroke
				(width 0.1)
				(type default)
			)
			(layer "F.SilkS")
		)
		(fp_line
			(start 9.302242 -5.171694)
			(end 8.425942 -4.3307)
			(stroke
				(width 0.1)
				(type default)
			)
			(layer "F.SilkS")
		)
		(fp_line
			(start 9.302242 -5.171694)
			(end 9.242298 -5.171694)
			(stroke
				(width 0.1)
				(type default)
			)
			(layer "F.SilkS")
		)
		(fp_line
			(start 9.302242 -5.171694)
			(end 9.242298 -5.171694)
			(stroke
				(width 0.1)
				(type default)
			)
			(layer "F.SilkS")
		)
		(fp_line
			(start 9.30656 -2.925064)
			(end 9.318752 -2.994406)
			(stroke
				(width 0.1)
				(type default)
			)
			(layer "F.SilkS")
		)
		(fp_line
			(start 9.30656 -2.925064)
			(end 9.318752 -2.994406)
			(stroke
				(width 0.1)
				(type default)
			)
			(layer "F.SilkS")
		)
		(fp_line
			(start 9.318752 -2.994406)
			(end 9.330944 -3.063748)
			(stroke
				(width 0.1)
				(type default)
			)
			(layer "F.SilkS")
		)
		(fp_line
			(start 9.318752 -2.994406)
			(end 9.330944 -3.063748)
			(stroke
				(width 0.1)
				(type default)
			)
			(layer "F.SilkS")
		)
		(fp_line
			(start 9.330944 -3.063748)
			(end 9.343136 -3.13309)
			(stroke
				(width 0.1)
				(type default)
			)
			(layer "F.SilkS")
		)
		(fp_line
			(start 9.330944 -3.063748)
			(end 9.343136 -3.13309)
			(stroke
				(width 0.1)
				(type default)
			)
			(layer "F.SilkS")
		)
		(fp_line
			(start 9.343136 -3.13309)
			(end 9.355328 -3.202432)
			(stroke
				(width 0.1)
				(type default)
			)
			(layer "F.SilkS")
		)
		(fp_line
			(start 9.343136 -3.13309)
			(end 9.355328 -3.202432)
			(stroke
				(width 0.1)
				(type default)
			)
			(layer "F.SilkS")
		)
		(fp_line
			(start 9.355328 -3.202432)
			(end 9.36752 -3.272028)
			(stroke
				(width 0.1)
				(type default)
			)
			(layer "F.SilkS")
		)
		(fp_line
			(start 9.355328 -3.202432)
			(end 9.36752 -3.272028)
			(stroke
				(width 0.1)
				(type default)
			)
			(layer "F.SilkS")
		)
		(fp_line
			(start 9.36244 -5.171694)
			(end 8.41375 -4.261612)
			(stroke
				(width 0.1)
				(type default)
			)
			(layer "F.SilkS")
		)
		(fp_line
			(start 9.36244 -5.171694)
			(end 8.41375 -4.261612)
			(stroke
				(width 0.1)
				(type default)
			)
			(layer "F.SilkS")
		)
		(fp_line
			(start 9.36244 -5.171694)
			(end 9.302242 -5.171694)
			(stroke
				(width 0.1)
				(type default)
			)
			(layer "F.SilkS")
		)
		(fp_line
			(start 9.36244 -5.171694)
			(end 9.302242 -5.171694)
			(stroke
				(width 0.1)
				(type default)
			)
			(layer "F.SilkS")
		)
		(fp_line
			(start 9.36752 -3.272028)
			(end 9.379712 -3.34137)
			(stroke
				(width 0.1)
				(type default)
			)
			(layer "F.SilkS")
		)
		(fp_line
			(start 9.36752 -3.272028)
			(end 9.379712 -3.34137)
			(stroke
				(width 0.1)
				(type default)
			)
			(layer "F.SilkS")
		)
		(fp_line
			(start 9.379712 -3.34137)
			(end 9.391904 -3.410712)
			(stroke
				(width 0.1)
				(type default)
			)
			(layer "F.SilkS")
		)
		(fp_line
			(start 9.379712 -3.34137)
			(end 9.391904 -3.410712)
			(stroke
				(width 0.1)
				(type default)
			)
			(layer "F.SilkS")
		)
		(fp_line
			(start 9.404096 -3.480054)
			(end 9.391904 -3.410712)
			(stroke
				(width 0.1)
				(type default)
			)
			(layer "F.SilkS")
		)
		(fp_line
			(start 9.404096 -3.480054)
			(end 9.391904 -3.410712)
			(stroke
				(width 0.1)
				(type default)
			)
			(layer "F.SilkS")
		)
		(fp_line
			(start 9.416288 -3.54965)
			(end 6.565392 -0.815086)
			(stroke
				(width 0.1)
				(type default)
			)
			(layer "F.SilkS")
		)
		(fp_line
			(start 9.416288 -3.54965)
			(end 6.565392 -0.815086)
			(stroke
				(width 0.1)
				(type default)
			)
			(layer "F.SilkS")
		)
		(fp_line
			(start 9.416288 -3.54965)
			(end 9.404096 -3.480054)
			(stroke
				(width 0.1)
				(type default)
			)
			(layer "F.SilkS")
		)
		(fp_line
			(start 9.416288 -3.54965)
			(end 9.404096 -3.480054)
			(stroke
				(width 0.1)
				(type default)
			)
			(layer "F.SilkS")
		)
		(fp_line
			(start 9.416288 -3.54965)
			(end 9.42848 -3.618992)
			(stroke
				(width 0.1)
				(type default)
			)
			(layer "F.SilkS")
		)
		(fp_line
			(start 9.416288 -3.54965)
			(end 9.42848 -3.618992)
			(stroke
				(width 0.1)
				(type default)
			)
			(layer "F.SilkS")
		)
		(fp_line
			(start 9.422638 -5.171694)
			(end 8.401558 -4.19227)
			(stroke
				(width 0.1)
				(type default)
			)
			(layer "F.SilkS")
		)
		(fp_line
			(start 9.422638 -5.171694)
			(end 8.401558 -4.19227)
			(stroke
				(width 0.1)
				(type default)
			)
			(layer "F.SilkS")
		)
		(fp_line
			(start 9.422638 -5.171694)
			(end 9.36244 -5.171694)
			(stroke
				(width 0.1)
				(type default)
			)
			(layer "F.SilkS")
		)
		(fp_line
			(start 9.422638 -5.171694)
			(end 9.36244 -5.171694)
			(stroke
				(width 0.1)
				(type default)
			)
			(layer "F.SilkS")
		)
		(fp_line
			(start 9.42848 -3.618992)
			(end 9.440672 -3.688334)
			(stroke
				(width 0.1)
				(type default)
			)
			(layer "F.SilkS")
		)
		(fp_line
			(start 9.42848 -3.618992)
			(end 9.440672 -3.688334)
			(stroke
				(width 0.1)
				(type default)
			)
			(layer "F.SilkS")
		)
		(fp_line
			(start 9.440672 -3.688334)
			(end 9.452864 -3.75793)
			(stroke
				(width 0.1)
				(type default)
			)
			(layer "F.SilkS")
		)
		(fp_line
			(start 9.440672 -3.688334)
			(end 9.452864 -3.75793)
			(stroke
				(width 0.1)
				(type default)
			)
			(layer "F.SilkS")
		)
		(fp_line
			(start 9.465056 -3.827526)
			(end 9.452864 -3.75793)
			(stroke
				(width 0.1)
				(type default)
			)
			(layer "F.SilkS")
		)
		(fp_line
			(start 9.465056 -3.827526)
			(end 9.452864 -3.75793)
			(stroke
				(width 0.1)
				(type default)
			)
			(layer "F.SilkS")
		)
		(fp_line
			(start 9.465056 -3.827526)
			(end 9.477248 -3.896614)
			(stroke
				(width 0.1)
				(type default)
			)
			(layer "F.SilkS")
		)
		(fp_line
			(start 9.465056 -3.827526)
			(end 9.477248 -3.896614)
			(stroke
				(width 0.1)
				(type default)
			)
			(layer "F.SilkS")
		)
		(fp_line
			(start 9.477248 -3.896614)
			(end 8.107172 -2.582418)
			(stroke
				(width 0.1)
				(type default)
			)
			(layer "F.SilkS")
		)
		(fp_line
			(start 9.477248 -3.896614)
			(end 8.107172 -2.582418)
			(stroke
				(width 0.1)
				(type default)
			)
			(layer "F.SilkS")
		)
		(fp_line
			(start 9.477248 -3.896614)
			(end 9.48944 -3.965956)
			(stroke
				(width 0.1)
				(type default)
			)
			(layer "F.SilkS")
		)
		(fp_line
			(start 9.477248 -3.896614)
			(end 9.48944 -3.965956)
			(stroke
				(width 0.1)
				(type default)
			)
			(layer "F.SilkS")
		)
		(fp_line
			(start 9.482836 -5.171694)
			(end 8.389366 -4.122674)
			(stroke
				(width 0.1)
				(type default)
			)
			(layer "F.SilkS")
		)
		(fp_line
			(start 9.482836 -5.171694)
			(end 8.389366 -4.122674)
			(stroke
				(width 0.1)
				(type default)
			)
			(layer "F.SilkS")
		)
		(fp_line
			(start 9.482836 -5.171694)
			(end 9.422638 -5.171694)
			(stroke
				(width 0.1)
				(type default)
			)
			(layer "F.SilkS")
		)
		(fp_line
			(start 9.482836 -5.171694)
			(end 9.422638 -5.171694)
			(stroke
				(width 0.1)
				(type default)
			)
			(layer "F.SilkS")
		)
		(fp_line
			(start 9.48944 -3.965956)
			(end 8.123682 -2.655824)
			(stroke
				(width 0.1)
				(type default)
			)
			(layer "F.SilkS")
		)
		(fp_line
			(start 9.48944 -3.965956)
			(end 8.123682 -2.655824)
			(stroke
				(width 0.1)
				(type default)
			)
			(layer "F.SilkS")
		)
		(fp_line
			(start 9.48944 -3.965956)
			(end 9.501632 -4.035552)
			(stroke
				(width 0.1)
				(type default)
			)
			(layer "F.SilkS")
		)
		(fp_line
			(start 9.48944 -3.965956)
			(end 9.501632 -4.035552)
			(stroke
				(width 0.1)
				(type default)
			)
			(layer "F.SilkS")
		)
		(fp_line
			(start 9.501632 -4.035552)
			(end 8.140446 -2.729738)
			(stroke
				(width 0.1)
				(type default)
			)
			(layer "F.SilkS")
		)
		(fp_line
			(start 9.501632 -4.035552)
			(end 8.140446 -2.729738)
			(stroke
				(width 0.1)
				(type default)
			)
			(layer "F.SilkS")
		)
		(fp_line
			(start 9.501632 -4.035552)
			(end 9.513824 -4.104894)
			(stroke
				(width 0.1)
				(type default)
			)
			(layer "F.SilkS")
		)
		(fp_line
			(start 9.501632 -4.035552)
			(end 9.513824 -4.104894)
			(stroke
				(width 0.1)
				(type default)
			)
			(layer "F.SilkS")
		)
		(fp_line
			(start 9.513824 -4.104894)
			(end 8.156956 -2.803398)
			(stroke
				(width 0.1)
				(type default)
			)
			(layer "F.SilkS")
		)
		(fp_line
			(start 9.513824 -4.104894)
			(end 8.156956 -2.803398)
			(stroke
				(width 0.1)
				(type default)
			)
			(layer "F.SilkS")
		)
		(fp_line
			(start 9.513824 -4.104894)
			(end 9.526016 -4.174236)
			(stroke
				(width 0.1)
				(type default)
			)
			(layer "F.SilkS")
		)
		(fp_line
			(start 9.513824 -4.104894)
			(end 9.526016 -4.174236)
			(stroke
				(width 0.1)
				(type default)
			)
			(layer "F.SilkS")
		)
		(fp_line
			(start 9.526016 -4.174236)
			(end 8.170418 -2.87401)
			(stroke
				(width 0.1)
				(type default)
			)
			(layer "F.SilkS")
		)
		(fp_line
			(start 9.526016 -4.174236)
			(end 8.170418 -2.87401)
			(stroke
				(width 0.1)
				(type default)
			)
			(layer "F.SilkS")
		)
		(fp_line
			(start 9.526016 -4.174236)
			(end 9.538208 -4.243578)
			(stroke
				(width 0.1)
				(type default)
			)
			(layer "F.SilkS")
		)
		(fp_line
			(start 9.526016 -4.174236)
			(end 9.538208 -4.243578)
			(stroke
				(width 0.1)
				(type default)
			)
			(layer "F.SilkS")
		)
		(fp_line
			(start 9.538208 -4.243578)
			(end 8.18261 -2.943352)
			(stroke
				(width 0.1)
				(type default)
			)
			(layer "F.SilkS")
		)
		(fp_line
			(start 9.538208 -4.243578)
			(end 8.18261 -2.943352)
			(stroke
				(width 0.1)
				(type default)
			)
			(layer "F.SilkS")
		)
		(fp_line
			(start 9.538208 -4.243578)
			(end 9.5504 -4.313174)
			(stroke
				(width 0.1)
				(type default)
			)
			(layer "F.SilkS")
		)
		(fp_line
			(start 9.538208 -4.243578)
			(end 9.5504 -4.313174)
			(stroke
				(width 0.1)
				(type default)
			)
			(layer "F.SilkS")
		)
		(fp_line
			(start 9.543034 -5.171694)
			(end 8.377174 -4.053332)
			(stroke
				(width 0.1)
				(type default)
			)
			(layer "F.SilkS")
		)
		(fp_line
			(start 9.543034 -5.171694)
			(end 8.377174 -4.053332)
			(stroke
				(width 0.1)
				(type default)
			)
			(layer "F.SilkS")
		)
		(fp_line
			(start 9.543034 -5.171694)
			(end 9.482836 -5.171694)
			(stroke
				(width 0.1)
				(type default)
			)
			(layer "F.SilkS")
		)
		(fp_line
			(start 9.543034 -5.171694)
			(end 9.482836 -5.171694)
			(stroke
				(width 0.1)
				(type default)
			)
			(layer "F.SilkS")
		)
		(fp_line
			(start 9.5504 -4.313174)
			(end 8.194802 -3.012694)
			(stroke
				(width 0.1)
				(type default)
			)
			(layer "F.SilkS")
		)
		(fp_line
			(start 9.5504 -4.313174)
			(end 8.194802 -3.012694)
			(stroke
				(width 0.1)
				(type default)
			)
			(layer "F.SilkS")
		)
		(fp_line
			(start 9.5504 -4.313174)
			(end 9.562592 -4.382516)
			(stroke
				(width 0.1)
				(type default)
			)
			(layer "F.SilkS")
		)
		(fp_line
			(start 9.5504 -4.313174)
			(end 9.562592 -4.382516)
			(stroke
				(width 0.1)
				(type default)
			)
			(layer "F.SilkS")
		)
		(fp_line
			(start 9.562592 -4.382516)
			(end 8.206994 -3.08229)
			(stroke
				(width 0.1)
				(type default)
			)
			(layer "F.SilkS")
		)
		(fp_line
			(start 9.562592 -4.382516)
			(end 8.206994 -3.08229)
			(stroke
				(width 0.1)
				(type default)
			)
			(layer "F.SilkS")
		)
		(fp_line
			(start 9.562592 -4.382516)
			(end 9.574784 -4.452112)
			(stroke
				(width 0.1)
				(type default)
			)
			(layer "F.SilkS")
		)
		(fp_line
			(start 9.562592 -4.382516)
			(end 9.574784 -4.452112)
			(stroke
				(width 0.1)
				(type default)
			)
			(layer "F.SilkS")
		)
		(fp_line
			(start 9.574784 -4.452112)
			(end 8.219186 -3.151378)
			(stroke
				(width 0.1)
				(type default)
			)
			(layer "F.SilkS")
		)
		(fp_line
			(start 9.574784 -4.452112)
			(end 8.219186 -3.151378)
			(stroke
				(width 0.1)
				(type default)
			)
			(layer "F.SilkS")
		)
		(fp_line
			(start 9.574784 -4.452112)
			(end 9.586976 -4.5212)
			(stroke
				(width 0.1)
				(type default)
			)
			(layer "F.SilkS")
		)
		(fp_line
			(start 9.574784 -4.452112)
			(end 9.586976 -4.5212)
			(stroke
				(width 0.1)
				(type default)
			)
			(layer "F.SilkS")
		)
		(fp_line
			(start 9.586976 -4.5212)
			(end 8.231378 -3.22072)
			(stroke
				(width 0.1)
				(type default)
			)
			(layer "F.SilkS")
		)
		(fp_line
			(start 9.586976 -4.5212)
			(end 8.231378 -3.22072)
			(stroke
				(width 0.1)
				(type default)
			)
			(layer "F.SilkS")
		)
		(fp_line
			(start 9.586976 -4.5212)
			(end 9.599168 -4.590796)
			(stroke
				(width 0.1)
				(type default)
			)
			(layer "F.SilkS")
		)
		(fp_line
			(start 9.586976 -4.5212)
			(end 9.599168 -4.590796)
			(stroke
				(width 0.1)
				(type default)
			)
			(layer "F.SilkS")
		)
		(fp_line
			(start 9.599168 -4.590796)
			(end 8.24357 -3.290316)
			(stroke
				(width 0.1)
				(type default)
			)
			(layer "F.SilkS")
		)
		(fp_line
			(start 9.599168 -4.590796)
			(end 8.24357 -3.290316)
			(stroke
				(width 0.1)
				(type default)
			)
			(layer "F.SilkS")
		)
		(fp_line
			(start 9.599168 -4.590796)
			(end 9.61136 -4.660138)
			(stroke
				(width 0.1)
				(type default)
			)
			(layer "F.SilkS")
		)
		(fp_line
			(start 9.599168 -4.590796)
			(end 9.61136 -4.660138)
			(stroke
				(width 0.1)
				(type default)
			)
			(layer "F.SilkS")
		)
		(fp_line
			(start 9.603232 -5.171694)
			(end 8.365236 -3.98399)
			(stroke
				(width 0.1)
				(type default)
			)
			(layer "F.SilkS")
		)
		(fp_line
			(start 9.603232 -5.171694)
			(end 8.365236 -3.98399)
			(stroke
				(width 0.1)
				(type default)
			)
			(layer "F.SilkS")
		)
		(fp_line
			(start 9.603232 -5.171694)
			(end 9.543034 -5.171694)
			(stroke
				(width 0.1)
				(type default)
			)
			(layer "F.SilkS")
		)
		(fp_line
			(start 9.603232 -5.171694)
			(end 9.543034 -5.171694)
			(stroke
				(width 0.1)
				(type default)
			)
			(layer "F.SilkS")
		)
		(fp_line
			(start 9.61136 -4.660138)
			(end 8.255762 -3.359658)
			(stroke
				(width 0.1)
				(type default)
			)
			(layer "F.SilkS")
		)
		(fp_line
			(start 9.61136 -4.660138)
			(end 8.255762 -3.359658)
			(stroke
				(width 0.1)
				(type default)
			)
			(layer "F.SilkS")
		)
		(fp_line
			(start 9.61136 -4.660138)
			(end 9.623552 -4.729734)
			(stroke
				(width 0.1)
				(type default)
			)
			(layer "F.SilkS")
		)
		(fp_line
			(start 9.61136 -4.660138)
			(end 9.623552 -4.729734)
			(stroke
				(width 0.1)
				(type default)
			)
			(layer "F.SilkS")
		)
		(fp_line
			(start 9.623552 -4.729734)
			(end 8.2677 -3.429)
			(stroke
				(width 0.1)
				(type default)
			)
			(layer "F.SilkS")
		)
		(fp_line
			(start 9.623552 -4.729734)
			(end 8.2677 -3.429)
			(stroke
				(width 0.1)
				(type default)
			)
			(layer "F.SilkS")
		)
		(fp_line
			(start 9.623552 -4.729734)
			(end 9.635744 -4.798822)
			(stroke
				(width 0.1)
				(type default)
			)
			(layer "F.SilkS")
		)
		(fp_line
			(start 9.623552 -4.729734)
			(end 9.635744 -4.798822)
			(stroke
				(width 0.1)
				(type default)
			)
			(layer "F.SilkS")
		)
		(fp_line
			(start 9.635744 -4.798822)
			(end 8.279892 -3.498342)
			(stroke
				(width 0.1)
				(type default)
			)
			(layer "F.SilkS")
		)
		(fp_line
			(start 9.635744 -4.798822)
			(end 8.279892 -3.498342)
			(stroke
				(width 0.1)
				(type default)
			)
			(layer "F.SilkS")
		)
		(fp_line
			(start 9.635744 -4.798822)
			(end 9.64819 -4.868418)
			(stroke
				(width 0.1)
				(type default)
			)
			(layer "F.SilkS")
		)
		(fp_line
			(start 9.635744 -4.798822)
			(end 9.64819 -4.868418)
			(stroke
				(width 0.1)
				(type default)
			)
			(layer "F.SilkS")
		)
		(fp_line
			(start 9.64819 -4.868418)
			(end 8.292084 -3.567684)
			(stroke
				(width 0.1)
				(type default)
			)
			(layer "F.SilkS")
		)
		(fp_line
			(start 9.64819 -4.868418)
			(end 8.292084 -3.567684)
			(stroke
				(width 0.1)
				(type default)
			)
			(layer "F.SilkS")
		)
		(fp_line
			(start 9.64819 -4.868418)
			(end 9.660382 -4.938014)
			(stroke
				(width 0.1)
				(type default)
			)
			(layer "F.SilkS")
		)
		(fp_line
			(start 9.64819 -4.868418)
			(end 9.660382 -4.938014)
			(stroke
				(width 0.1)
				(type default)
			)
			(layer "F.SilkS")
		)
		(fp_line
			(start 9.660382 -4.938014)
			(end 8.304276 -3.63728)
			(stroke
				(width 0.1)
				(type default)
			)
			(layer "F.SilkS")
		)
		(fp_line
			(start 9.660382 -4.938014)
			(end 8.304276 -3.63728)
			(stroke
				(width 0.1)
				(type default)
			)
			(layer "F.SilkS")
		)
		(fp_line
			(start 9.660382 -4.938014)
			(end 9.67232 -5.007356)
			(stroke
				(width 0.1)
				(type default)
			)
			(layer "F.SilkS")
		)
		(fp_line
			(start 9.660382 -4.938014)
			(end 9.67232 -5.007356)
			(stroke
				(width 0.1)
				(type default)
			)
			(layer "F.SilkS")
		)
		(fp_line
			(start 9.663176 -5.171694)
			(end 8.35279 -3.914648)
			(stroke
				(width 0.1)
				(type default)
			)
			(layer "F.SilkS")
		)
		(fp_line
			(start 9.663176 -5.171694)
			(end 8.35279 -3.914648)
			(stroke
				(width 0.1)
				(type default)
			)
			(layer "F.SilkS")
		)
		(fp_line
			(start 9.663176 -5.171694)
			(end 9.603232 -5.171694)
			(stroke
				(width 0.1)
				(type default)
			)
			(layer "F.SilkS")
		)
		(fp_line
			(start 9.663176 -5.171694)
			(end 9.603232 -5.171694)
			(stroke
				(width 0.1)
				(type default)
			)
			(layer "F.SilkS")
		)
		(fp_line
			(start 9.67232 -5.007356)
			(end 8.316468 -3.706368)
			(stroke
				(width 0.1)
				(type default)
			)
			(layer "F.SilkS")
		)
		(fp_line
			(start 9.67232 -5.007356)
			(end 8.316468 -3.706368)
			(stroke
				(width 0.1)
				(type default)
			)
			(layer "F.SilkS")
		)
		(fp_line
			(start 9.67232 -5.007356)
			(end 9.684512 -5.076698)
			(stroke
				(width 0.1)
				(type default)
			)
			(layer "F.SilkS")
		)
		(fp_line
			(start 9.67232 -5.007356)
			(end 9.684512 -5.076698)
			(stroke
				(width 0.1)
				(type default)
			)
			(layer "F.SilkS")
		)
		(fp_line
			(start 9.684512 -5.076698)
			(end 8.32866 -3.77571)
			(stroke
				(width 0.1)
				(type default)
			)
			(layer "F.SilkS")
		)
		(fp_line
			(start 9.684512 -5.076698)
			(end 8.32866 -3.77571)
			(stroke
				(width 0.1)
				(type default)
			)
			(layer "F.SilkS")
		)
		(fp_line
			(start 9.684512 -5.076698)
			(end 9.696704 -5.14604)
			(stroke
				(width 0.1)
				(type default)
			)
			(layer "F.SilkS")
		)
		(fp_line
			(start 9.684512 -5.076698)
			(end 9.696704 -5.14604)
			(stroke
				(width 0.1)
				(type default)
			)
			(layer "F.SilkS")
		)
		(fp_line
			(start 9.696704 -5.14604)
			(end 8.340852 -3.845306)
			(stroke
				(width 0.1)
				(type default)
			)
			(layer "F.SilkS")
		)
		(fp_line
			(start 9.696704 -5.14604)
			(end 8.340852 -3.845306)
			(stroke
				(width 0.1)
				(type default)
			)
			(layer "F.SilkS")
		)
		(fp_line
			(start 9.696704 -5.14604)
			(end 9.701276 -5.171694)
			(stroke
				(width 0.1)
				(type default)
			)
			(layer "F.SilkS")
		)
		(fp_line
			(start 9.696704 -5.14604)
			(end 9.701276 -5.171694)
			(stroke
				(width 0.1)
				(type default)
			)
			(layer "F.SilkS")
		)
		(fp_line
			(start 9.701276 -5.171694)
			(end 9.663176 -5.171694)
			(stroke
				(width 0.1)
				(type default)
			)
			(layer "F.SilkS")
		)
		(fp_line
			(start 9.701276 -5.171694)
			(end 9.663176 -5.171694)
			(stroke
				(width 0.1)
				(type default)
			)
			(layer "F.SilkS")
		)
		(fp_line
			(start 9.754616 -1.96977)
			(end 11.590528 -3.730752)
			(stroke
				(width 0.1)
				(type default)
			)
			(layer "F.SilkS")
		)
		(fp_line
			(start 9.754616 -1.96977)
			(end 11.590528 -3.730752)
			(stroke
				(width 0.1)
				(type default)
			)
			(layer "F.SilkS")
		)
		(fp_line
			(start 9.75614 -2.028698)
			(end 11.526012 -3.726688)
			(stroke
				(width 0.1)
				(type default)
			)
			(layer "F.SilkS")
		)
		(fp_line
			(start 9.75614 -2.028698)
			(end 11.526012 -3.726688)
			(stroke
				(width 0.1)
				(type default)
			)
			(layer "F.SilkS")
		)
		(fp_line
			(start 9.75741 -2.08788)
			(end 11.46175 -3.722878)
			(stroke
				(width 0.1)
				(type default)
			)
			(layer "F.SilkS")
		)
		(fp_line
			(start 9.75741 -2.08788)
			(end 11.46175 -3.722878)
			(stroke
				(width 0.1)
				(type default)
			)
			(layer "F.SilkS")
		)
		(fp_line
			(start 9.758172 -1.915414)
			(end 11.65479 -3.734816)
			(stroke
				(width 0.1)
				(type default)
			)
			(layer "F.SilkS")
		)
		(fp_line
			(start 9.758172 -1.915414)
			(end 11.65479 -3.734816)
			(stroke
				(width 0.1)
				(type default)
			)
			(layer "F.SilkS")
		)
		(fp_line
			(start 9.760458 -2.148332)
			(end 11.394694 -3.71602)
			(stroke
				(width 0.1)
				(type default)
			)
			(layer "F.SilkS")
		)
		(fp_line
			(start 9.760458 -2.148332)
			(end 11.394694 -3.71602)
			(stroke
				(width 0.1)
				(type default)
			)
			(layer "F.SilkS")
		)
		(fp_line
			(start 9.762998 -1.862074)
			(end 11.719052 -3.738626)
			(stroke
				(width 0.1)
				(type default)
			)
			(layer "F.SilkS")
		)
		(fp_line
			(start 9.762998 -1.862074)
			(end 11.719052 -3.738626)
			(stroke
				(width 0.1)
				(type default)
			)
			(layer "F.SilkS")
		)
		(fp_line
			(start 9.76757 -1.808988)
			(end 11.782044 -3.74142)
			(stroke
				(width 0.1)
				(type default)
			)
			(layer "F.SilkS")
		)
		(fp_line
			(start 9.76757 -1.808988)
			(end 11.782044 -3.74142)
			(stroke
				(width 0.1)
				(type default)
			)
			(layer "F.SilkS")
		)
		(fp_line
			(start 9.768586 -2.214118)
			(end 11.319002 -3.701288)
			(stroke
				(width 0.1)
				(type default)
			)
			(layer "F.SilkS")
		)
		(fp_line
			(start 9.768586 -2.214118)
			(end 11.319002 -3.701288)
			(stroke
				(width 0.1)
				(type default)
			)
			(layer "F.SilkS")
		)
		(fp_line
			(start 9.77646 -1.759712)
			(end 11.83894 -3.738372)
			(stroke
				(width 0.1)
				(type default)
			)
			(layer "F.SilkS")
		)
		(fp_line
			(start 9.77646 -1.759712)
			(end 11.83894 -3.738372)
			(stroke
				(width 0.1)
				(type default)
			)
			(layer "F.SilkS")
		)
		(fp_line
			(start 9.777222 -2.279904)
			(end 11.24331 -3.686556)
			(stroke
				(width 0.1)
				(type default)
			)
			(layer "F.SilkS")
		)
		(fp_line
			(start 9.777222 -2.279904)
			(end 11.24331 -3.686556)
			(stroke
				(width 0.1)
				(type default)
			)
			(layer "F.SilkS")
		)
		(fp_line
			(start 9.78662 -1.711706)
			(end 11.89609 -3.735324)
			(stroke
				(width 0.1)
				(type default)
			)
			(layer "F.SilkS")
		)
		(fp_line
			(start 9.78662 -1.711706)
			(end 11.89609 -3.735324)
			(stroke
				(width 0.1)
				(type default)
			)
			(layer "F.SilkS")
		)
		(fp_line
			(start 9.79043 -2.350262)
			(end 11.167872 -3.67157)
			(stroke
				(width 0.1)
				(type default)
			)
			(layer "F.SilkS")
		)
		(fp_line
			(start 9.79043 -2.350262)
			(end 11.167872 -3.67157)
			(stroke
				(width 0.1)
				(type default)
			)
			(layer "F.SilkS")
		)
		(fp_line
			(start 9.797034 -1.663954)
			(end 11.952986 -3.732276)
			(stroke
				(width 0.1)
				(type default)
			)
			(layer "F.SilkS")
		)
		(fp_line
			(start 9.797034 -1.663954)
			(end 11.952986 -3.732276)
			(stroke
				(width 0.1)
				(type default)
			)
			(layer "F.SilkS")
		)
		(fp_line
			(start 9.809988 -1.618742)
			(end 12.010136 -3.729482)
			(stroke
				(width 0.1)
				(type default)
			)
			(layer "F.SilkS")
		)
		(fp_line
			(start 9.809988 -1.618742)
			(end 12.010136 -3.729482)
			(stroke
				(width 0.1)
				(type default)
			)
			(layer "F.SilkS")
		)
		(fp_line
			(start 9.812528 -2.429256)
			(end 11.09218 -3.656838)
			(stroke
				(width 0.1)
				(type default)
			)
			(layer "F.SilkS")
		)
		(fp_line
			(start 9.812528 -2.429256)
			(end 11.09218 -3.656838)
			(stroke
				(width 0.1)
				(type default)
			)
			(layer "F.SilkS")
		)
		(fp_line
			(start 9.825228 -1.575562)
			(end 12.063984 -3.723132)
			(stroke
				(width 0.1)
				(type default)
			)
			(layer "F.SilkS")
		)
		(fp_line
			(start 9.825228 -1.575562)
			(end 12.063984 -3.723132)
			(stroke
				(width 0.1)
				(type default)
			)
			(layer "F.SilkS")
		)
		(fp_line
			(start 9.834626 -2.507996)
			(end 11.00201 -3.627882)
			(stroke
				(width 0.1)
				(type default)
			)
			(layer "F.SilkS")
		)
		(fp_line
			(start 9.834626 -2.507996)
			(end 11.00201 -3.627882)
			(stroke
				(width 0.1)
				(type default)
			)
			(layer "F.SilkS")
		)
		(fp_line
			(start 9.840214 -1.532382)
			(end 12.115038 -3.714496)
			(stroke
				(width 0.1)
				(type default)
			)
			(layer "F.SilkS")
		)
		(fp_line
			(start 9.840214 -1.532382)
			(end 12.115038 -3.714496)
			(stroke
				(width 0.1)
				(type default)
			)
			(layer "F.SilkS")
		)
		(fp_line
			(start 9.856978 -2.587244)
			(end 10.90676 -3.594354)
			(stroke
				(width 0.1)
				(type default)
			)
			(layer "F.SilkS")
		)
		(fp_line
			(start 9.856978 -2.587244)
			(end 10.90676 -3.594354)
			(stroke
				(width 0.1)
				(type default)
			)
			(layer "F.SilkS")
		)
		(fp_line
			(start 9.857232 -1.49098)
			(end 12.165838 -3.705352)
			(stroke
				(width 0.1)
				(type default)
			)
			(layer "F.SilkS")
		)
		(fp_line
			(start 9.857232 -1.49098)
			(end 12.165838 -3.705352)
			(stroke
				(width 0.1)
				(type default)
			)
			(layer "F.SilkS")
		)
		(fp_line
			(start 9.87679 -1.452118)
			(end 10.97661 -2.50698)
			(stroke
				(width 0.1)
				(type default)
			)
			(layer "F.SilkS")
		)
		(fp_line
			(start 9.87679 -1.452118)
			(end 10.97661 -2.50698)
			(stroke
				(width 0.1)
				(type default)
			)
			(layer "F.SilkS")
		)
		(fp_line
			(start 9.884664 -2.671572)
			(end 10.811764 -3.560826)
			(stroke
				(width 0.1)
				(type default)
			)
			(layer "F.SilkS")
		)
		(fp_line
			(start 9.884664 -2.671572)
			(end 10.811764 -3.560826)
			(stroke
				(width 0.1)
				(type default)
			)
			(layer "F.SilkS")
		)
		(fp_line
			(start 9.896602 -1.413256)
			(end 10.944606 -2.418588)
			(stroke
				(width 0.1)
				(type default)
			)
			(layer "F.SilkS")
		)
		(fp_line
			(start 9.896602 -1.413256)
			(end 10.944606 -2.418588)
			(stroke
				(width 0.1)
				(type default)
			)
			(layer "F.SilkS")
		)
		(fp_line
			(start 9.916922 -1.375156)
			(end 10.912856 -2.33045)
			(stroke
				(width 0.1)
				(type default)
			)
			(layer "F.SilkS")
		)
		(fp_line
			(start 9.916922 -1.375156)
			(end 10.912856 -2.33045)
			(stroke
				(width 0.1)
				(type default)
			)
			(layer "F.SilkS")
		)
		(fp_line
			(start 9.940798 -1.340358)
			(end 10.903712 -2.263902)
			(stroke
				(width 0.1)
				(type default)
			)
			(layer "F.SilkS")
		)
		(fp_line
			(start 9.940798 -1.340358)
			(end 10.903712 -2.263902)
			(stroke
				(width 0.1)
				(type default)
			)
			(layer "F.SilkS")
		)
		(fp_line
			(start 9.945116 -2.787142)
			(end 10.69721 -3.508502)
			(stroke
				(width 0.1)
				(type default)
			)
			(layer "F.SilkS")
		)
		(fp_line
			(start 9.945116 -2.787142)
			(end 10.69721 -3.508502)
			(stroke
				(width 0.1)
				(type default)
			)
			(layer "F.SilkS")
		)
		(fp_line
			(start 9.964674 -1.30556)
			(end 10.898632 -2.201418)
			(stroke
				(width 0.1)
				(type default)
			)
			(layer "F.SilkS")
		)
		(fp_line
			(start 9.964674 -1.30556)
			(end 10.898632 -2.201418)
			(stroke
				(width 0.1)
				(type default)
			)
			(layer "F.SilkS")
		)
		(fp_line
			(start 9.98855 -1.270508)
			(end 10.902442 -2.147316)
			(stroke
				(width 0.1)
				(type default)
			)
			(layer "F.SilkS")
		)
		(fp_line
			(start 9.98855 -1.270508)
			(end 10.902442 -2.147316)
			(stroke
				(width 0.1)
				(type default)
			)
			(layer "F.SilkS")
		)
		(fp_line
			(start 10.005568 -2.902966)
			(end 10.557002 -3.431794)
			(stroke
				(width 0.1)
				(type default)
			)
			(layer "F.SilkS")
		)
		(fp_line
			(start 10.005568 -2.902966)
			(end 10.557002 -3.431794)
			(stroke
				(width 0.1)
				(type default)
			)
			(layer "F.SilkS")
		)
		(fp_line
			(start 10.015982 -1.239266)
			(end 10.90803 -2.094992)
			(stroke
				(width 0.1)
				(type default)
			)
			(layer "F.SilkS")
		)
		(fp_line
			(start 10.015982 -1.239266)
			(end 10.90803 -2.094992)
			(stroke
				(width 0.1)
				(type default)
			)
			(layer "F.SilkS")
		)
		(fp_line
			(start 10.043668 -1.208278)
			(end 10.921238 -2.04978)
			(stroke
				(width 0.1)
				(type default)
			)
			(layer "F.SilkS")
		)
		(fp_line
			(start 10.043668 -1.208278)
			(end 10.921238 -2.04978)
			(stroke
				(width 0.1)
				(type default)
			)
			(layer "F.SilkS")
		)
		(fp_line
			(start 10.071608 -1.17729)
			(end 10.9347 -2.00533)
			(stroke
				(width 0.1)
				(type default)
			)
			(layer "F.SilkS")
		)
		(fp_line
			(start 10.071608 -1.17729)
			(end 10.9347 -2.00533)
			(stroke
				(width 0.1)
				(type default)
			)
			(layer "F.SilkS")
		)
		(fp_line
			(start 10.102088 -1.148588)
			(end 10.956798 -1.9685)
			(stroke
				(width 0.1)
				(type default)
			)
			(layer "F.SilkS")
		)
		(fp_line
			(start 10.102088 -1.148588)
			(end 10.956798 -1.9685)
			(stroke
				(width 0.1)
				(type default)
			)
			(layer "F.SilkS")
		)
		(fp_line
			(start 10.133584 -1.121156)
			(end 10.978642 -1.931924)
			(stroke
				(width 0.1)
				(type default)
			)
			(layer "F.SilkS")
		)
		(fp_line
			(start 10.133584 -1.121156)
			(end 10.978642 -1.931924)
			(stroke
				(width 0.1)
				(type default)
			)
			(layer "F.SilkS")
		)
		(fp_line
			(start 10.16508 -1.093724)
			(end 11.006582 -1.90119)
			(stroke
				(width 0.1)
				(type default)
			)
			(layer "F.SilkS")
		)
		(fp_line
			(start 10.16508 -1.093724)
			(end 11.006582 -1.90119)
			(stroke
				(width 0.1)
				(type default)
			)
			(layer "F.SilkS")
		)
		(fp_line
			(start 10.198354 -1.067816)
			(end 11.037062 -1.872742)
			(stroke
				(width 0.1)
				(type default)
			)
			(layer "F.SilkS")
		)
		(fp_line
			(start 10.198354 -1.067816)
			(end 11.037062 -1.872742)
			(stroke
				(width 0.1)
				(type default)
			)
			(layer "F.SilkS")
		)
		(fp_line
			(start 10.233406 -1.043686)
			(end 11.06932 -1.845818)
			(stroke
				(width 0.1)
				(type default)
			)
			(layer "F.SilkS")
		)
		(fp_line
			(start 10.233406 -1.043686)
			(end 11.06932 -1.845818)
			(stroke
				(width 0.1)
				(type default)
			)
			(layer "F.SilkS")
		)
		(fp_line
			(start 10.268458 -1.01981)
			(end 11.108182 -1.825244)
			(stroke
				(width 0.1)
				(type default)
			)
			(layer "F.SilkS")
		)
		(fp_line
			(start 10.268458 -1.01981)
			(end 11.108182 -1.825244)
			(stroke
				(width 0.1)
				(type default)
			)
			(layer "F.SilkS")
		)
		(fp_line
			(start 10.30478 -0.99695)
			(end 11.147044 -1.804924)
			(stroke
				(width 0.1)
				(type default)
			)
			(layer "F.SilkS")
		)
		(fp_line
			(start 10.30478 -0.99695)
			(end 11.147044 -1.804924)
			(stroke
				(width 0.1)
				(type default)
			)
			(layer "F.SilkS")
		)
		(fp_line
			(start 10.343388 -0.976122)
			(end 11.190478 -1.788922)
			(stroke
				(width 0.1)
				(type default)
			)
			(layer "F.SilkS")
		)
		(fp_line
			(start 10.343388 -0.976122)
			(end 11.190478 -1.788922)
			(stroke
				(width 0.1)
				(type default)
			)
			(layer "F.SilkS")
		)
		(fp_line
			(start 10.381996 -0.955548)
			(end 11.237722 -1.776476)
			(stroke
				(width 0.1)
				(type default)
			)
			(layer "F.SilkS")
		)
		(fp_line
			(start 10.381996 -0.955548)
			(end 11.237722 -1.776476)
			(stroke
				(width 0.1)
				(type default)
			)
			(layer "F.SilkS")
		)
		(fp_line
			(start 10.421366 -0.935482)
			(end 11.28522 -1.76403)
			(stroke
				(width 0.1)
				(type default)
			)
			(layer "F.SilkS")
		)
		(fp_line
			(start 10.421366 -0.935482)
			(end 11.28522 -1.76403)
			(stroke
				(width 0.1)
				(type default)
			)
			(layer "F.SilkS")
		)
		(fp_line
			(start 10.46353 -0.918464)
			(end 11.33856 -1.75768)
			(stroke
				(width 0.1)
				(type default)
			)
			(layer "F.SilkS")
		)
		(fp_line
			(start 10.46353 -0.918464)
			(end 11.33856 -1.75768)
			(stroke
				(width 0.1)
				(type default)
			)
			(layer "F.SilkS")
		)
		(fp_line
			(start 10.505694 -0.901192)
			(end 11.39444 -1.753616)
			(stroke
				(width 0.1)
				(type default)
			)
			(layer "F.SilkS")
		)
		(fp_line
			(start 10.505694 -0.901192)
			(end 11.39444 -1.753616)
			(stroke
				(width 0.1)
				(type default)
			)
			(layer "F.SilkS")
		)
		(fp_line
			(start 10.548366 -0.884682)
			(end 11.45032 -1.749552)
			(stroke
				(width 0.1)
				(type default)
			)
			(layer "F.SilkS")
		)
		(fp_line
			(start 10.548366 -0.884682)
			(end 11.45032 -1.749552)
			(stroke
				(width 0.1)
				(type default)
			)
			(layer "F.SilkS")
		)
		(fp_line
			(start 10.572496 -4.831842)
			(end 10.566146 -4.825746)
			(stroke
				(width 0.1)
				(type default)
			)
			(layer "F.SilkS")
		)
		(fp_line
			(start 10.572496 -4.831842)
			(end 10.566146 -4.825746)
			(stroke
				(width 0.1)
				(type default)
			)
			(layer "F.SilkS")
		)
		(fp_line
			(start 10.582148 -4.783328)
			(end 10.566146 -4.825746)
			(stroke
				(width 0.1)
				(type default)
			)
			(layer "F.SilkS")
		)
		(fp_line
			(start 10.582148 -4.783328)
			(end 10.566146 -4.825746)
			(stroke
				(width 0.1)
				(type default)
			)
			(layer "F.SilkS")
		)
		(fp_line
			(start 10.59434 -0.870712)
			(end 11.516614 -1.75514)
			(stroke
				(width 0.1)
				(type default)
			)
			(layer "F.SilkS")
		)
		(fp_line
			(start 10.59434 -0.870712)
			(end 11.516614 -1.75514)
			(stroke
				(width 0.1)
				(type default)
			)
			(layer "F.SilkS")
		)
		(fp_line
			(start 10.59815 -4.74091)
			(end 10.582148 -4.783328)
			(stroke
				(width 0.1)
				(type default)
			)
			(layer "F.SilkS")
		)
		(fp_line
			(start 10.59815 -4.74091)
			(end 10.582148 -4.783328)
			(stroke
				(width 0.1)
				(type default)
			)
			(layer "F.SilkS")
		)
		(fp_line
			(start 10.613898 -4.698746)
			(end 10.59815 -4.74091)
			(stroke
				(width 0.1)
				(type default)
			)
			(layer "F.SilkS")
		)
		(fp_line
			(start 10.613898 -4.698746)
			(end 10.59815 -4.74091)
			(stroke
				(width 0.1)
				(type default)
			)
			(layer "F.SilkS")
		)
		(fp_line
			(start 10.613898 -4.698746)
			(end 10.6299 -4.656074)
			(stroke
				(width 0.1)
				(type default)
			)
			(layer "F.SilkS")
		)
		(fp_line
			(start 10.613898 -4.698746)
			(end 10.6299 -4.656074)
			(stroke
				(width 0.1)
				(type default)
			)
			(layer "F.SilkS")
		)
		(fp_line
			(start 10.6299 -4.656074)
			(end 10.645902 -4.613656)
			(stroke
				(width 0.1)
				(type default)
			)
			(layer "F.SilkS")
		)
		(fp_line
			(start 10.6299 -4.656074)
			(end 10.645902 -4.613656)
			(stroke
				(width 0.1)
				(type default)
			)
			(layer "F.SilkS")
		)
		(fp_line
			(start 10.64006 -0.856996)
			(end 11.585448 -1.763522)
			(stroke
				(width 0.1)
				(type default)
			)
			(layer "F.SilkS")
		)
		(fp_line
			(start 10.64006 -0.856996)
			(end 11.585448 -1.763522)
			(stroke
				(width 0.1)
				(type default)
			)
			(layer "F.SilkS")
		)
		(fp_line
			(start 10.645902 -4.613656)
			(end 10.661904 -4.571492)
			(stroke
				(width 0.1)
				(type default)
			)
			(layer "F.SilkS")
		)
		(fp_line
			(start 10.645902 -4.613656)
			(end 10.661904 -4.571492)
			(stroke
				(width 0.1)
				(type default)
			)
			(layer "F.SilkS")
		)
		(fp_line
			(start 10.661904 -4.571492)
			(end 10.677906 -4.529074)
			(stroke
				(width 0.1)
				(type default)
			)
			(layer "F.SilkS")
		)
		(fp_line
			(start 10.661904 -4.571492)
			(end 10.677906 -4.529074)
			(stroke
				(width 0.1)
				(type default)
			)
			(layer "F.SilkS")
		)
		(fp_line
			(start 10.677906 -4.529074)
			(end 10.693908 -4.486402)
			(stroke
				(width 0.1)
				(type default)
			)
			(layer "F.SilkS")
		)
		(fp_line
			(start 10.677906 -4.529074)
			(end 10.693908 -4.486402)
			(stroke
				(width 0.1)
				(type default)
			)
			(layer "F.SilkS")
		)
		(fp_line
			(start 10.686542 -0.843534)
			(end 11.654282 -1.772158)
			(stroke
				(width 0.1)
				(type default)
			)
			(layer "F.SilkS")
		)
		(fp_line
			(start 10.686542 -0.843534)
			(end 11.654282 -1.772158)
			(stroke
				(width 0.1)
				(type default)
			)
			(layer "F.SilkS")
		)
		(fp_line
			(start 10.693908 -4.486402)
			(end 10.709656 -4.443984)
			(stroke
				(width 0.1)
				(type default)
			)
			(layer "F.SilkS")
		)
		(fp_line
			(start 10.693908 -4.486402)
			(end 10.709656 -4.443984)
			(stroke
				(width 0.1)
				(type default)
			)
			(layer "F.SilkS")
		)
		(fp_line
			(start 10.698734 -4.895088)
			(end 10.582148 -4.783328)
			(stroke
				(width 0.1)
				(type default)
			)
			(layer "F.SilkS")
		)
		(fp_line
			(start 10.698734 -4.895088)
			(end 10.582148 -4.783328)
			(stroke
				(width 0.1)
				(type default)
			)
			(layer "F.SilkS")
		)
		(fp_line
			(start 10.709656 -4.443984)
			(end 10.725658 -4.40182)
			(stroke
				(width 0.1)
				(type default)
			)
			(layer "F.SilkS")
		)
		(fp_line
			(start 10.709656 -4.443984)
			(end 10.725658 -4.40182)
			(stroke
				(width 0.1)
				(type default)
			)
			(layer "F.SilkS")
		)
		(fp_line
			(start 10.725658 -4.40182)
			(end 10.74166 -4.359402)
			(stroke
				(width 0.1)
				(type default)
			)
			(layer "F.SilkS")
		)
		(fp_line
			(start 10.725658 -4.40182)
			(end 10.74166 -4.359402)
			(stroke
				(width 0.1)
				(type default)
			)
			(layer "F.SilkS")
		)
		(fp_line
			(start 10.736072 -0.833628)
			(end 11.723116 -1.78054)
			(stroke
				(width 0.1)
				(type default)
			)
			(layer "F.SilkS")
		)
		(fp_line
			(start 10.736072 -0.833628)
			(end 11.723116 -1.78054)
			(stroke
				(width 0.1)
				(type default)
			)
			(layer "F.SilkS")
		)
		(fp_line
			(start 10.74166 -4.359402)
			(end 10.757662 -4.316984)
			(stroke
				(width 0.1)
				(type default)
			)
			(layer "F.SilkS")
		)
		(fp_line
			(start 10.74166 -4.359402)
			(end 10.757662 -4.316984)
			(stroke
				(width 0.1)
				(type default)
			)
			(layer "F.SilkS")
		)
		(fp_line
			(start 10.757662 -4.316984)
			(end 10.773664 -4.274566)
			(stroke
				(width 0.1)
				(type default)
			)
			(layer "F.SilkS")
		)
		(fp_line
			(start 10.757662 -4.316984)
			(end 10.773664 -4.274566)
			(stroke
				(width 0.1)
				(type default)
			)
			(layer "F.SilkS")
		)
		(fp_line
			(start 10.773664 -4.274566)
			(end 10.789666 -4.232148)
			(stroke
				(width 0.1)
				(type default)
			)
			(layer "F.SilkS")
		)
		(fp_line
			(start 10.773664 -4.274566)
			(end 10.789666 -4.232148)
			(stroke
				(width 0.1)
				(type default)
			)
			(layer "F.SilkS")
		)
		(fp_line
			(start 10.785602 -0.823214)
			(end 11.818112 -1.813814)
			(stroke
				(width 0.1)
				(type default)
			)
			(layer "F.SilkS")
		)
		(fp_line
			(start 10.785602 -0.823214)
			(end 11.818112 -1.813814)
			(stroke
				(width 0.1)
				(type default)
			)
			(layer "F.SilkS")
		)
		(fp_line
			(start 10.789666 -4.232148)
			(end 10.805414 -4.18973)
			(stroke
				(width 0.1)
				(type default)
			)
			(layer "F.SilkS")
		)
		(fp_line
			(start 10.789666 -4.232148)
			(end 10.805414 -4.18973)
			(stroke
				(width 0.1)
				(type default)
			)
			(layer "F.SilkS")
		)
		(fp_line
			(start 10.805414 -4.18973)
			(end 10.821416 -4.147312)
			(stroke
				(width 0.1)
				(type default)
			)
			(layer "F.SilkS")
		)
		(fp_line
			(start 10.805414 -4.18973)
			(end 10.821416 -4.147312)
			(stroke
				(width 0.1)
				(type default)
			)
			(layer "F.SilkS")
		)
		(fp_line
			(start 10.818368 -4.952492)
			(end 10.59815 -4.74091)
			(stroke
				(width 0.1)
				(type default)
			)
			(layer "F.SilkS")
		)
		(fp_line
			(start 10.818368 -4.952492)
			(end 10.59815 -4.74091)
			(stroke
				(width 0.1)
				(type default)
			)
			(layer "F.SilkS")
		)
		(fp_line
			(start 10.821416 -4.147312)
			(end 10.837418 -4.104894)
			(stroke
				(width 0.1)
				(type default)
			)
			(layer "F.SilkS")
		)
		(fp_line
			(start 10.821416 -4.147312)
			(end 10.837418 -4.104894)
			(stroke
				(width 0.1)
				(type default)
			)
			(layer "F.SilkS")
		)
		(fp_line
			(start 10.836402 -0.814324)
			(end 11.91514 -1.84912)
			(stroke
				(width 0.1)
				(type default)
			)
			(layer "F.SilkS")
		)
		(fp_line
			(start 10.836402 -0.814324)
			(end 11.91514 -1.84912)
			(stroke
				(width 0.1)
				(type default)
			)
			(layer "F.SilkS")
		)
		(fp_line
			(start 10.837418 -4.104894)
			(end 10.85342 -4.062476)
			(stroke
				(width 0.1)
				(type default)
			)
			(layer "F.SilkS")
		)
		(fp_line
			(start 10.837418 -4.104894)
			(end 10.85342 -4.062476)
			(stroke
				(width 0.1)
				(type default)
			)
			(layer "F.SilkS")
		)
		(fp_line
			(start 10.889742 -0.808228)
			(end 12.047474 -1.918462)
			(stroke
				(width 0.1)
				(type default)
			)
			(layer "F.SilkS")
		)
		(fp_line
			(start 10.889742 -0.808228)
			(end 12.047474 -1.918462)
			(stroke
				(width 0.1)
				(type default)
			)
			(layer "F.SilkS")
		)
		(fp_line
			(start 10.931144 -5.002784)
			(end 10.613898 -4.698746)
			(stroke
				(width 0.1)
				(type default)
			)
			(layer "F.SilkS")
		)
		(fp_line
			(start 10.931144 -5.002784)
			(end 10.613898 -4.698746)
			(stroke
				(width 0.1)
				(type default)
			)
			(layer "F.SilkS")
		)
		(fp_line
			(start 10.99947 -0.797814)
			(end 13.653516 -3.343402)
			(stroke
				(width 0.1)
				(type default)
			)
			(layer "F.SilkS")
		)
		(fp_line
			(start 10.99947 -0.797814)
			(end 13.653516 -3.343402)
			(stroke
				(width 0.1)
				(type default)
			)
			(layer "F.SilkS")
		)
		(fp_line
			(start 11.03503 -5.044694)
			(end 10.6299 -4.656074)
			(stroke
				(width 0.1)
				(type default)
			)
			(layer "F.SilkS")
		)
		(fp_line
			(start 11.03503 -5.044694)
			(end 10.6299 -4.656074)
			(stroke
				(width 0.1)
				(type default)
			)
			(layer "F.SilkS")
		)
		(fp_line
			(start 11.057382 -0.795274)
			(end 13.64107 -3.27406)
			(stroke
				(width 0.1)
				(type default)
			)
			(layer "F.SilkS")
		)
		(fp_line
			(start 11.057382 -0.795274)
			(end 13.64107 -3.27406)
			(stroke
				(width 0.1)
				(type default)
			)
			(layer "F.SilkS")
		)
		(fp_line
			(start 11.11504 -0.792988)
			(end 13.629132 -3.204972)
			(stroke
				(width 0.1)
				(type default)
			)
			(layer "F.SilkS")
		)
		(fp_line
			(start 11.11504 -0.792988)
			(end 13.629132 -3.204972)
			(stroke
				(width 0.1)
				(type default)
			)
			(layer "F.SilkS")
		)
		(fp_line
			(start 11.13536 -5.083048)
			(end 10.645902 -4.613656)
			(stroke
				(width 0.1)
				(type default)
			)
			(layer "F.SilkS")
		)
		(fp_line
			(start 11.13536 -5.083048)
			(end 10.645902 -4.613656)
			(stroke
				(width 0.1)
				(type default)
			)
			(layer "F.SilkS")
		)
		(fp_line
			(start 11.182096 -0.799846)
			(end 13.61694 -3.135376)
			(stroke
				(width 0.1)
				(type default)
			)
			(layer "F.SilkS")
		)
		(fp_line
			(start 11.182096 -0.799846)
			(end 13.61694 -3.135376)
			(stroke
				(width 0.1)
				(type default)
			)
			(layer "F.SilkS")
		)
		(fp_line
			(start 11.226546 -5.11302)
			(end 10.661904 -4.571492)
			(stroke
				(width 0.1)
				(type default)
			)
			(layer "F.SilkS")
		)
		(fp_line
			(start 11.226546 -5.11302)
			(end 10.661904 -4.571492)
			(stroke
				(width 0.1)
				(type default)
			)
			(layer "F.SilkS")
		)
		(fp_line
			(start 11.246612 -2.76606)
			(end 12.216638 -3.696716)
			(stroke
				(width 0.1)
				(type default)
			)
			(layer "F.SilkS")
		)
		(fp_line
			(start 11.246612 -2.76606)
			(end 12.216638 -3.696716)
			(stroke
				(width 0.1)
				(type default)
			)
			(layer "F.SilkS")
		)
		(fp_line
			(start 11.248898 -0.805942)
			(end 13.604494 -3.06578)
			(stroke
				(width 0.1)
				(type default)
			)
			(layer "F.SilkS")
		)
		(fp_line
			(start 11.248898 -0.805942)
			(end 13.604494 -3.06578)
			(stroke
				(width 0.1)
				(type default)
			)
			(layer "F.SilkS")
		)
		(fp_line
			(start 11.315446 -5.140706)
			(end 10.677906 -4.529074)
			(stroke
				(width 0.1)
				(type default)
			)
			(layer "F.SilkS")
		)
		(fp_line
			(start 11.315446 -5.140706)
			(end 10.677906 -4.529074)
			(stroke
				(width 0.1)
				(type default)
			)
			(layer "F.SilkS")
		)
		(fp_line
			(start 11.315954 -0.813054)
			(end 13.592556 -2.996692)
			(stroke
				(width 0.1)
				(type default)
			)
			(layer "F.SilkS")
		)
		(fp_line
			(start 11.315954 -0.813054)
			(end 13.592556 -2.996692)
			(stroke
				(width 0.1)
				(type default)
			)
			(layer "F.SilkS")
		)
		(fp_line
			(start 11.364722 -2.821686)
			(end 12.265914 -3.686302)
			(stroke
				(width 0.1)
				(type default)
			)
			(layer "F.SilkS")
		)
		(fp_line
			(start 11.364722 -2.821686)
			(end 12.265914 -3.686302)
			(stroke
				(width 0.1)
				(type default)
			)
			(layer "F.SilkS")
		)
		(fp_line
			(start 11.382756 -0.81915)
			(end 13.580364 -2.927096)
			(stroke
				(width 0.1)
				(type default)
			)
			(layer "F.SilkS")
		)
		(fp_line
			(start 11.382756 -0.81915)
			(end 13.580364 -2.927096)
			(stroke
				(width 0.1)
				(type default)
			)
			(layer "F.SilkS")
		)
		(fp_line
			(start 11.398758 -5.163058)
			(end 10.693908 -4.486402)
			(stroke
				(width 0.1)
				(type default)
			)
			(layer "F.SilkS")
		)
		(fp_line
			(start 11.398758 -5.163058)
			(end 10.693908 -4.486402)
			(stroke
				(width 0.1)
				(type default)
			)
			(layer "F.SilkS")
		)
		(fp_line
			(start 11.436096 -2.832354)
			(end 12.31138 -3.672078)
			(stroke
				(width 0.1)
				(type default)
			)
			(layer "F.SilkS")
		)
		(fp_line
			(start 11.436096 -2.832354)
			(end 12.31138 -3.672078)
			(stroke
				(width 0.1)
				(type default)
			)
			(layer "F.SilkS")
		)
		(fp_line
			(start 11.460734 -0.836422)
			(end 13.568172 -2.857754)
			(stroke
				(width 0.1)
				(type default)
			)
			(layer "F.SilkS")
		)
		(fp_line
			(start 11.460734 -0.836422)
			(end 13.568172 -2.857754)
			(stroke
				(width 0.1)
				(type default)
			)
			(layer "F.SilkS")
		)
		(fp_line
			(start 11.478514 -5.1816)
			(end 10.709656 -4.443984)
			(stroke
				(width 0.1)
				(type default)
			)
			(layer "F.SilkS")
		)
		(fp_line
			(start 11.478514 -5.1816)
			(end 10.709656 -4.443984)
			(stroke
				(width 0.1)
				(type default)
			)
			(layer "F.SilkS")
		)
		(fp_line
			(start 11.505184 -2.84099)
			(end 12.356592 -3.657854)
			(stroke
				(width 0.1)
				(type default)
			)
			(layer "F.SilkS")
		)
		(fp_line
			(start 11.505184 -2.84099)
			(end 12.356592 -3.657854)
			(stroke
				(width 0.1)
				(type default)
			)
			(layer "F.SilkS")
		)
		(fp_line
			(start 11.546332 -0.860552)
			(end 13.55598 -2.788412)
			(stroke
				(width 0.1)
				(type default)
			)
			(layer "F.SilkS")
		)
		(fp_line
			(start 11.546332 -0.860552)
			(end 13.55598 -2.788412)
			(stroke
				(width 0.1)
				(type default)
			)
			(layer "F.SilkS")
		)
		(fp_line
			(start 11.557762 -5.199888)
			(end 10.725658 -4.40182)
			(stroke
				(width 0.1)
				(type default)
			)
			(layer "F.SilkS")
		)
		(fp_line
			(start 11.557762 -5.199888)
			(end 10.725658 -4.40182)
			(stroke
				(width 0.1)
				(type default)
			)
			(layer "F.SilkS")
		)
		(fp_line
			(start 11.629898 -5.211572)
			(end 10.74166 -4.359402)
			(stroke
				(width 0.1)
				(type default)
			)
			(layer "F.SilkS")
		)
		(fp_line
			(start 11.629898 -5.211572)
			(end 10.74166 -4.359402)
			(stroke
				(width 0.1)
				(type default)
			)
			(layer "F.SilkS")
		)
		(fp_line
			(start 11.63193 -0.884936)
			(end 13.544042 -2.71907)
			(stroke
				(width 0.1)
				(type default)
			)
			(layer "F.SilkS")
		)
		(fp_line
			(start 11.63193 -0.884936)
			(end 13.544042 -2.71907)
			(stroke
				(width 0.1)
				(type default)
			)
			(layer "F.SilkS")
		)
		(fp_line
			(start 11.702034 -5.223002)
			(end 10.757662 -4.316984)
			(stroke
				(width 0.1)
				(type default)
			)
			(layer "F.SilkS")
		)
		(fp_line
			(start 11.702034 -5.223002)
			(end 10.757662 -4.316984)
			(stroke
				(width 0.1)
				(type default)
			)
			(layer "F.SilkS")
		)
		(fp_line
			(start 11.728704 -0.919988)
			(end 13.531596 -2.649728)
			(stroke
				(width 0.1)
				(type default)
			)
			(layer "F.SilkS")
		)
		(fp_line
			(start 11.728704 -0.919988)
			(end 13.531596 -2.649728)
			(stroke
				(width 0.1)
				(type default)
			)
			(layer "F.SilkS")
		)
		(fp_line
			(start 11.77417 -5.234178)
			(end 10.773664 -4.274566)
			(stroke
				(width 0.1)
				(type default)
			)
			(layer "F.SilkS")
		)
		(fp_line
			(start 11.77417 -5.234178)
			(end 10.773664 -4.274566)
			(stroke
				(width 0.1)
				(type default)
			)
			(layer "F.SilkS")
		)
		(fp_line
			(start 11.84021 -5.24002)
			(end 10.789666 -4.232148)
			(stroke
				(width 0.1)
				(type default)
			)
			(layer "F.SilkS")
		)
		(fp_line
			(start 11.84021 -5.24002)
			(end 10.789666 -4.232148)
			(stroke
				(width 0.1)
				(type default)
			)
			(layer "F.SilkS")
		)
		(fp_line
			(start 11.8491 -0.9779)
			(end 13.519404 -2.580386)
			(stroke
				(width 0.1)
				(type default)
			)
			(layer "F.SilkS")
		)
		(fp_line
			(start 11.8491 -0.9779)
			(end 13.519404 -2.580386)
			(stroke
				(width 0.1)
				(type default)
			)
			(layer "F.SilkS")
		)
		(fp_line
			(start 11.906504 -5.245862)
			(end 10.805414 -4.18973)
			(stroke
				(width 0.1)
				(type default)
			)
			(layer "F.SilkS")
		)
		(fp_line
			(start 11.906504 -5.245862)
			(end 10.805414 -4.18973)
			(stroke
				(width 0.1)
				(type default)
			)
			(layer "F.SilkS")
		)
		(fp_line
			(start 11.972798 -5.251958)
			(end 10.821416 -4.147312)
			(stroke
				(width 0.1)
				(type default)
			)
			(layer "F.SilkS")
		)
		(fp_line
			(start 11.972798 -5.251958)
			(end 10.821416 -4.147312)
			(stroke
				(width 0.1)
				(type default)
			)
			(layer "F.SilkS")
		)
		(fp_line
			(start 12.000738 -1.06553)
			(end 13.507466 -2.51079)
			(stroke
				(width 0.1)
				(type default)
			)
			(layer "F.SilkS")
		)
		(fp_line
			(start 12.000738 -1.06553)
			(end 13.507466 -2.51079)
			(stroke
				(width 0.1)
				(type default)
			)
			(layer "F.SilkS")
		)
		(fp_line
			(start 12.036806 -5.255514)
			(end 10.837418 -4.104894)
			(stroke
				(width 0.1)
				(type default)
			)
			(layer "F.SilkS")
		)
		(fp_line
			(start 12.036806 -5.255514)
			(end 10.837418 -4.104894)
			(stroke
				(width 0.1)
				(type default)
			)
			(layer "F.SilkS")
		)
		(fp_line
			(start 12.093956 -0.882904)
			(end 12.111228 -0.882904)
			(stroke
				(width 0.1)
				(type default)
			)
			(layer "F.SilkS")
		)
		(fp_line
			(start 12.093956 -0.882904)
			(end 12.111228 -0.882904)
			(stroke
				(width 0.1)
				(type default)
			)
			(layer "F.SilkS")
		)
		(fp_line
			(start 12.098528 -5.257038)
			(end 10.85342 -4.062476)
			(stroke
				(width 0.1)
				(type default)
			)
			(layer "F.SilkS")
		)
		(fp_line
			(start 12.098528 -5.257038)
			(end 10.85342 -4.062476)
			(stroke
				(width 0.1)
				(type default)
			)
			(layer "F.SilkS")
		)
		(fp_line
			(start 12.102592 -0.932434)
			(end 12.093956 -0.882904)
			(stroke
				(width 0.1)
				(type default)
			)
			(layer "F.SilkS")
		)
		(fp_line
			(start 12.102592 -0.932434)
			(end 12.093956 -0.882904)
			(stroke
				(width 0.1)
				(type default)
			)
			(layer "F.SilkS")
		)
		(fp_line
			(start 12.102592 -0.932434)
			(end 13.458444 -2.233422)
			(stroke
				(width 0.1)
				(type default)
			)
			(layer "F.SilkS")
		)
		(fp_line
			(start 12.102592 -0.932434)
			(end 13.458444 -2.233422)
			(stroke
				(width 0.1)
				(type default)
			)
			(layer "F.SilkS")
		)
		(fp_line
			(start 12.111228 -0.882904)
			(end 12.171172 -0.882904)
			(stroke
				(width 0.1)
				(type default)
			)
			(layer "F.SilkS")
		)
		(fp_line
			(start 12.111228 -0.882904)
			(end 12.171172 -0.882904)
			(stroke
				(width 0.1)
				(type default)
			)
			(layer "F.SilkS")
		)
		(fp_line
			(start 12.111228 -0.882904)
			(end 13.446506 -2.163826)
			(stroke
				(width 0.1)
				(type default)
			)
			(layer "F.SilkS")
		)
		(fp_line
			(start 12.111228 -0.882904)
			(end 13.446506 -2.163826)
			(stroke
				(width 0.1)
				(type default)
			)
			(layer "F.SilkS")
		)
		(fp_line
			(start 12.115038 -1.00203)
			(end 12.102592 -0.932434)
			(stroke
				(width 0.1)
				(type default)
			)
			(layer "F.SilkS")
		)
		(fp_line
			(start 12.115038 -1.00203)
			(end 12.102592 -0.932434)
			(stroke
				(width 0.1)
				(type default)
			)
			(layer "F.SilkS")
		)
		(fp_line
			(start 12.115038 -1.00203)
			(end 13.47089 -2.302764)
			(stroke
				(width 0.1)
				(type default)
			)
			(layer "F.SilkS")
		)
		(fp_line
			(start 12.115038 -1.00203)
			(end 13.47089 -2.302764)
			(stroke
				(width 0.1)
				(type default)
			)
			(layer "F.SilkS")
		)
		(fp_line
			(start 12.12723 -1.071626)
			(end 12.115038 -1.00203)
			(stroke
				(width 0.1)
				(type default)
			)
			(layer "F.SilkS")
		)
		(fp_line
			(start 12.12723 -1.071626)
			(end 12.115038 -1.00203)
			(stroke
				(width 0.1)
				(type default)
			)
			(layer "F.SilkS")
		)
		(fp_line
			(start 12.12723 -1.071626)
			(end 13.483082 -2.372106)
			(stroke
				(width 0.1)
				(type default)
			)
			(layer "F.SilkS")
		)
		(fp_line
			(start 12.12723 -1.071626)
			(end 13.483082 -2.372106)
			(stroke
				(width 0.1)
				(type default)
			)
			(layer "F.SilkS")
		)
		(fp_line
			(start 12.139676 -1.140968)
			(end 12.12723 -1.071626)
			(stroke
				(width 0.1)
				(type default)
			)
			(layer "F.SilkS")
		)
		(fp_line
			(start 12.139676 -1.140968)
			(end 12.12723 -1.071626)
			(stroke
				(width 0.1)
				(type default)
			)
			(layer "F.SilkS")
		)
		(fp_line
			(start 12.139676 -1.140968)
			(end 13.49502 -2.441448)
			(stroke
				(width 0.1)
				(type default)
			)
			(layer "F.SilkS")
		)
		(fp_line
			(start 12.139676 -1.140968)
			(end 13.49502 -2.441448)
			(stroke
				(width 0.1)
				(type default)
			)
			(layer "F.SilkS")
		)
		(fp_line
			(start 12.160504 -5.258816)
			(end 10.92708 -4.07543)
			(stroke
				(width 0.1)
				(type default)
			)
			(layer "F.SilkS")
		)
		(fp_line
			(start 12.160504 -5.258816)
			(end 10.92708 -4.07543)
			(stroke
				(width 0.1)
				(type default)
			)
			(layer "F.SilkS")
		)
		(fp_line
			(start 12.171172 -0.882904)
			(end 12.23137 -0.882904)
			(stroke
				(width 0.1)
				(type default)
			)
			(layer "F.SilkS")
		)
		(fp_line
			(start 12.171172 -0.882904)
			(end 12.23137 -0.882904)
			(stroke
				(width 0.1)
				(type default)
			)
			(layer "F.SilkS")
		)
		(fp_line
			(start 12.171172 -0.882904)
			(end 13.434314 -2.094738)
			(stroke
				(width 0.1)
				(type default)
			)
			(layer "F.SilkS")
		)
		(fp_line
			(start 12.171172 -0.882904)
			(end 13.434314 -2.094738)
			(stroke
				(width 0.1)
				(type default)
			)
			(layer "F.SilkS")
		)
		(fp_line
			(start 12.22248 -5.260594)
			(end 11.042904 -4.12877)
			(stroke
				(width 0.1)
				(type default)
			)
			(layer "F.SilkS")
		)
		(fp_line
			(start 12.22248 -5.260594)
			(end 11.042904 -4.12877)
			(stroke
				(width 0.1)
				(type default)
			)
			(layer "F.SilkS")
		)
		(fp_line
			(start 12.23137 -0.882904)
			(end 12.291568 -0.882904)
			(stroke
				(width 0.1)
				(type default)
			)
			(layer "F.SilkS")
		)
		(fp_line
			(start 12.23137 -0.882904)
			(end 12.291568 -0.882904)
			(stroke
				(width 0.1)
				(type default)
			)
			(layer "F.SilkS")
		)
		(fp_line
			(start 12.23137 -0.882904)
			(end 13.422122 -2.025396)
			(stroke
				(width 0.1)
				(type default)
			)
			(layer "F.SilkS")
		)
		(fp_line
			(start 12.23137 -0.882904)
			(end 13.422122 -2.025396)
			(stroke
				(width 0.1)
				(type default)
			)
			(layer "F.SilkS")
		)
		(fp_line
			(start 12.281408 -5.25907)
			(end 11.150092 -4.173728)
			(stroke
				(width 0.1)
				(type default)
			)
			(layer "F.SilkS")
		)
		(fp_line
			(start 12.281408 -5.25907)
			(end 11.150092 -4.173728)
			(stroke
				(width 0.1)
				(type default)
			)
			(layer "F.SilkS")
		)
		(fp_line
			(start 12.291568 -0.882904)
			(end 12.351512 -0.882904)
			(stroke
				(width 0.1)
				(type default)
			)
			(layer "F.SilkS")
		)
		(fp_line
			(start 12.291568 -0.882904)
			(end 12.351512 -0.882904)
			(stroke
				(width 0.1)
				(type default)
			)
			(layer "F.SilkS")
		)
		(fp_line
			(start 12.291568 -0.882904)
			(end 13.40993 -1.9558)
			(stroke
				(width 0.1)
				(type default)
			)
			(layer "F.SilkS")
		)
		(fp_line
			(start 12.291568 -0.882904)
			(end 13.40993 -1.9558)
			(stroke
				(width 0.1)
				(type default)
			)
			(layer "F.SilkS")
		)
		(fp_line
			(start 12.335002 -2.251964)
			(end 12.323064 -2.182622)
			(stroke
				(width 0.1)
				(type default)
			)
			(layer "F.SilkS")
		)
		(fp_line
			(start 12.335002 -2.251964)
			(end 12.323064 -2.182622)
			(stroke
				(width 0.1)
				(type default)
			)
			(layer "F.SilkS")
		)
		(fp_line
			(start 12.337542 -5.255514)
			(end 11.246358 -4.208526)
			(stroke
				(width 0.1)
				(type default)
			)
			(layer "F.SilkS")
		)
		(fp_line
			(start 12.337542 -5.255514)
			(end 11.246358 -4.208526)
			(stroke
				(width 0.1)
				(type default)
			)
			(layer "F.SilkS")
		)
		(fp_line
			(start 12.347194 -2.321306)
			(end 12.335002 -2.251964)
			(stroke
				(width 0.1)
				(type default)
			)
			(layer "F.SilkS")
		)
		(fp_line
			(start 12.347194 -2.321306)
			(end 12.335002 -2.251964)
			(stroke
				(width 0.1)
				(type default)
			)
			(layer "F.SilkS")
		)
		(fp_line
			(start 12.351512 -0.882904)
			(end 12.41171 -0.882904)
			(stroke
				(width 0.1)
				(type default)
			)
			(layer "F.SilkS")
		)
		(fp_line
			(start 12.351512 -0.882904)
			(end 12.41171 -0.882904)
			(stroke
				(width 0.1)
				(type default)
			)
			(layer "F.SilkS")
		)
		(fp_line
			(start 12.351512 -0.882904)
			(end 13.397992 -1.886458)
			(stroke
				(width 0.1)
				(type default)
			)
			(layer "F.SilkS")
		)
		(fp_line
			(start 12.351512 -0.882904)
			(end 13.397992 -1.886458)
			(stroke
				(width 0.1)
				(type default)
			)
			(layer "F.SilkS")
		)
		(fp_line
			(start 12.359386 -2.390902)
			(end 12.347194 -2.321306)
			(stroke
				(width 0.1)
				(type default)
			)
			(layer "F.SilkS")
		)
		(fp_line
			(start 12.359386 -2.390902)
			(end 12.347194 -2.321306)
			(stroke
				(width 0.1)
				(type default)
			)
			(layer "F.SilkS")
		)
		(fp_line
			(start 12.371578 -2.460244)
			(end 12.359386 -2.390902)
			(stroke
				(width 0.1)
				(type default)
			)
			(layer "F.SilkS")
		)
		(fp_line
			(start 12.371578 -2.460244)
			(end 12.359386 -2.390902)
			(stroke
				(width 0.1)
				(type default)
			)
			(layer "F.SilkS")
		)
		(fp_line
			(start 12.38377 -2.529586)
			(end 12.371578 -2.460244)
			(stroke
				(width 0.1)
				(type default)
			)
			(layer "F.SilkS")
		)
		(fp_line
			(start 12.38377 -2.529586)
			(end 12.371578 -2.460244)
			(stroke
				(width 0.1)
				(type default)
			)
			(layer "F.SilkS")
		)
		(fp_line
			(start 12.393676 -5.251704)
			(end 11.336782 -4.237736)
			(stroke
				(width 0.1)
				(type default)
			)
			(layer "F.SilkS")
		)
		(fp_line
			(start 12.393676 -5.251704)
			(end 11.336782 -4.237736)
			(stroke
				(width 0.1)
				(type default)
			)
			(layer "F.SilkS")
		)
		(fp_line
			(start 12.395962 -2.598928)
			(end 12.38377 -2.529586)
			(stroke
				(width 0.1)
				(type default)
			)
			(layer "F.SilkS")
		)
		(fp_line
			(start 12.395962 -2.598928)
			(end 12.38377 -2.529586)
			(stroke
				(width 0.1)
				(type default)
			)
			(layer "F.SilkS")
		)
		(fp_line
			(start 12.401804 -3.64363)
			(end 11.574526 -2.849626)
			(stroke
				(width 0.1)
				(type default)
			)
			(layer "F.SilkS")
		)
		(fp_line
			(start 12.401804 -3.64363)
			(end 11.574526 -2.849626)
			(stroke
				(width 0.1)
				(type default)
			)
			(layer "F.SilkS")
		)
		(fp_line
			(start 12.408154 -2.668524)
			(end 12.395962 -2.598928)
			(stroke
				(width 0.1)
				(type default)
			)
			(layer "F.SilkS")
		)
		(fp_line
			(start 12.408154 -2.668524)
			(end 12.395962 -2.598928)
			(stroke
				(width 0.1)
				(type default)
			)
			(layer "F.SilkS")
		)
		(fp_line
			(start 12.41171 -0.882904)
			(end 12.471908 -0.882904)
			(stroke
				(width 0.1)
				(type default)
			)
			(layer "F.SilkS")
		)
		(fp_line
			(start 12.41171 -0.882904)
			(end 12.471908 -0.882904)
			(stroke
				(width 0.1)
				(type default)
			)
			(layer "F.SilkS")
		)
		(fp_line
			(start 12.41171 -0.882904)
			(end 13.385546 -1.817116)
			(stroke
				(width 0.1)
				(type default)
			)
			(layer "F.SilkS")
		)
		(fp_line
			(start 12.41171 -0.882904)
			(end 13.385546 -1.817116)
			(stroke
				(width 0.1)
				(type default)
			)
			(layer "F.SilkS")
		)
		(fp_line
			(start 12.445238 -3.62712)
			(end 11.643614 -2.858262)
			(stroke
				(width 0.1)
				(type default)
			)
			(layer "F.SilkS")
		)
		(fp_line
			(start 12.445238 -3.62712)
			(end 11.643614 -2.858262)
			(stroke
				(width 0.1)
				(type default)
			)
			(layer "F.SilkS")
		)
		(fp_line
			(start 12.44981 -5.24764)
			(end 11.421364 -4.261104)
			(stroke
				(width 0.1)
				(type default)
			)
			(layer "F.SilkS")
		)
		(fp_line
			(start 12.44981 -5.24764)
			(end 11.421364 -4.261104)
			(stroke
				(width 0.1)
				(type default)
			)
			(layer "F.SilkS")
		)
		(fp_line
			(start 12.471908 -0.882904)
			(end 12.53236 -0.882904)
			(stroke
				(width 0.1)
				(type default)
			)
			(layer "F.SilkS")
		)
		(fp_line
			(start 12.471908 -0.882904)
			(end 12.53236 -0.882904)
			(stroke
				(width 0.1)
				(type default)
			)
			(layer "F.SilkS")
		)
		(fp_line
			(start 12.471908 -0.882904)
			(end 13.373354 -1.74752)
			(stroke
				(width 0.1)
				(type default)
			)
			(layer "F.SilkS")
		)
		(fp_line
			(start 12.471908 -0.882904)
			(end 13.373354 -1.74752)
			(stroke
				(width 0.1)
				(type default)
			)
			(layer "F.SilkS")
		)
		(fp_line
			(start 12.485624 -3.608324)
			(end 11.704574 -2.859278)
			(stroke
				(width 0.1)
				(type default)
			)
			(layer "F.SilkS")
		)
		(fp_line
			(start 12.485624 -3.608324)
			(end 11.704574 -2.859278)
			(stroke
				(width 0.1)
				(type default)
			)
			(layer "F.SilkS")
		)
		(fp_line
			(start 12.506198 -5.24383)
			(end 11.499596 -4.278376)
			(stroke
				(width 0.1)
				(type default)
			)
			(layer "F.SilkS")
		)
		(fp_line
			(start 12.506198 -5.24383)
			(end 11.499596 -4.278376)
			(stroke
				(width 0.1)
				(type default)
			)
			(layer "F.SilkS")
		)
		(fp_line
			(start 12.52601 -3.589274)
			(end 11.763502 -2.858008)
			(stroke
				(width 0.1)
				(type default)
			)
			(layer "F.SilkS")
		)
		(fp_line
			(start 12.52601 -3.589274)
			(end 11.763502 -2.858008)
			(stroke
				(width 0.1)
				(type default)
			)
			(layer "F.SilkS")
		)
		(fp_line
			(start 12.53236 -0.882904)
			(end 12.592558 -0.882904)
			(stroke
				(width 0.1)
				(type default)
			)
			(layer "F.SilkS")
		)
		(fp_line
			(start 12.53236 -0.882904)
			(end 12.592558 -0.882904)
			(stroke
				(width 0.1)
				(type default)
			)
			(layer "F.SilkS")
		)
		(fp_line
			(start 12.53236 -0.882904)
			(end 13.361416 -1.678178)
			(stroke
				(width 0.1)
				(type default)
			)
			(layer "F.SilkS")
		)
		(fp_line
			(start 12.53236 -0.882904)
			(end 13.361416 -1.678178)
			(stroke
				(width 0.1)
				(type default)
			)
			(layer "F.SilkS")
		)
		(fp_line
			(start 12.562078 -5.24002)
			(end 11.575542 -4.293616)
			(stroke
				(width 0.1)
				(type default)
			)
			(layer "F.SilkS")
		)
		(fp_line
			(start 12.562078 -5.24002)
			(end 11.575542 -4.293616)
			(stroke
				(width 0.1)
				(type default)
			)
			(layer "F.SilkS")
		)
		(fp_line
			(start 12.590018 -3.708654)
			(end 12.57808 -3.639312)
			(stroke
				(width 0.1)
				(type default)
			)
			(layer "F.SilkS")
		)
		(fp_line
			(start 12.590018 -3.708654)
			(end 12.57808 -3.639312)
			(stroke
				(width 0.1)
				(type default)
			)
			(layer "F.SilkS")
		)
		(fp_line
			(start 12.592558 -0.882904)
			(end 12.652502 -0.882904)
			(stroke
				(width 0.1)
				(type default)
			)
			(layer "F.SilkS")
		)
		(fp_line
			(start 12.592558 -0.882904)
			(end 12.652502 -0.882904)
			(stroke
				(width 0.1)
				(type default)
			)
			(layer "F.SilkS")
		)
		(fp_line
			(start 12.592558 -0.882904)
			(end 13.34897 -1.608836)
			(stroke
				(width 0.1)
				(type default)
			)
			(layer "F.SilkS")
		)
		(fp_line
			(start 12.592558 -0.882904)
			(end 13.34897 -1.608836)
			(stroke
				(width 0.1)
				(type default)
			)
			(layer "F.SilkS")
		)
		(fp_line
			(start 12.601956 -3.777996)
			(end 12.590018 -3.708654)
			(stroke
				(width 0.1)
				(type default)
			)
			(layer "F.SilkS")
		)
		(fp_line
			(start 12.601956 -3.777996)
			(end 12.590018 -3.708654)
			(stroke
				(width 0.1)
				(type default)
			)
			(layer "F.SilkS")
		)
		(fp_line
			(start 12.618212 -5.23621)
			(end 11.6459 -4.303268)
			(stroke
				(width 0.1)
				(type default)
			)
			(layer "F.SilkS")
		)
		(fp_line
			(start 12.618212 -5.23621)
			(end 11.6459 -4.303268)
			(stroke
				(width 0.1)
				(type default)
			)
			(layer "F.SilkS")
		)
		(fp_line
			(start 12.652502 -0.882904)
			(end 12.7127 -0.882904)
			(stroke
				(width 0.1)
				(type default)
			)
			(layer "F.SilkS")
		)
		(fp_line
			(start 12.652502 -0.882904)
			(end 12.7127 -0.882904)
			(stroke
				(width 0.1)
				(type default)
			)
			(layer "F.SilkS")
		)
		(fp_line
			(start 12.652502 -0.882904)
			(end 13.337286 -1.539494)
			(stroke
				(width 0.1)
				(type default)
			)
			(layer "F.SilkS")
		)
		(fp_line
			(start 12.652502 -0.882904)
			(end 13.337286 -1.539494)
			(stroke
				(width 0.1)
				(type default)
			)
			(layer "F.SilkS")
		)
		(fp_line
			(start 12.666726 -5.225034)
			(end 11.715242 -4.312412)
			(stroke
				(width 0.1)
				(type default)
			)
			(layer "F.SilkS")
		)
		(fp_line
			(start 12.666726 -5.225034)
			(end 11.715242 -4.312412)
			(stroke
				(width 0.1)
				(type default)
			)
			(layer "F.SilkS")
		)
		(fp_line
			(start 12.7127 -0.882904)
			(end 12.772898 -0.882904)
			(stroke
				(width 0.1)
				(type default)
			)
			(layer "F.SilkS")
		)
		(fp_line
			(start 12.7127 -0.882904)
			(end 12.772898 -0.882904)
			(stroke
				(width 0.1)
				(type default)
			)
			(layer "F.SilkS")
		)
		(fp_line
			(start 12.7127 -0.882904)
			(end 13.32484 -1.470152)
			(stroke
				(width 0.1)
				(type default)
			)
			(layer "F.SilkS")
		)
		(fp_line
			(start 12.7127 -0.882904)
			(end 13.32484 -1.470152)
			(stroke
				(width 0.1)
				(type default)
			)
			(layer "F.SilkS")
		)
		(fp_line
			(start 12.715494 -5.214112)
			(end 11.78179 -4.318254)
			(stroke
				(width 0.1)
				(type default)
			)
			(layer "F.SilkS")
		)
		(fp_line
			(start 12.715494 -5.214112)
			(end 11.78179 -4.318254)
			(stroke
				(width 0.1)
				(type default)
			)
			(layer "F.SilkS")
		)
		(fp_line
			(start 12.764008 -5.202936)
			(end 11.846306 -4.322572)
			(stroke
				(width 0.1)
				(type default)
			)
			(layer "F.SilkS")
		)
		(fp_line
			(start 12.764008 -5.202936)
			(end 11.846306 -4.322572)
			(stroke
				(width 0.1)
				(type default)
			)
			(layer "F.SilkS")
		)
		(fp_line
			(start 12.772898 -0.882904)
			(end 12.832842 -0.882904)
			(stroke
				(width 0.1)
				(type default)
			)
			(layer "F.SilkS")
		)
		(fp_line
			(start 12.772898 -0.882904)
			(end 12.832842 -0.882904)
			(stroke
				(width 0.1)
				(type default)
			)
			(layer "F.SilkS")
		)
		(fp_line
			(start 12.772898 -0.882904)
			(end 13.312394 -1.400556)
			(stroke
				(width 0.1)
				(type default)
			)
			(layer "F.SilkS")
		)
		(fp_line
			(start 12.772898 -0.882904)
			(end 13.312394 -1.400556)
			(stroke
				(width 0.1)
				(type default)
			)
			(layer "F.SilkS")
		)
		(fp_line
			(start 12.812522 -5.19176)
			(end 11.910568 -4.326636)
			(stroke
				(width 0.1)
				(type default)
			)
			(layer "F.SilkS")
		)
		(fp_line
			(start 12.812522 -5.19176)
			(end 11.910568 -4.326636)
			(stroke
				(width 0.1)
				(type default)
			)
			(layer "F.SilkS")
		)
		(fp_line
			(start 12.832842 -0.882904)
			(end 12.89304 -0.882904)
			(stroke
				(width 0.1)
				(type default)
			)
			(layer "F.SilkS")
		)
		(fp_line
			(start 12.832842 -0.882904)
			(end 12.89304 -0.882904)
			(stroke
				(width 0.1)
				(type default)
			)
			(layer "F.SilkS")
		)
		(fp_line
			(start 12.832842 -0.882904)
			(end 13.30071 -1.331468)
			(stroke
				(width 0.1)
				(type default)
			)
			(layer "F.SilkS")
		)
		(fp_line
			(start 12.832842 -0.882904)
			(end 13.30071 -1.331468)
			(stroke
				(width 0.1)
				(type default)
			)
			(layer "F.SilkS")
		)
		(fp_line
			(start 12.861036 -5.180584)
			(end 11.972036 -4.327906)
			(stroke
				(width 0.1)
				(type default)
			)
			(layer "F.SilkS")
		)
		(fp_line
			(start 12.861036 -5.180584)
			(end 11.972036 -4.327906)
			(stroke
				(width 0.1)
				(type default)
			)
			(layer "F.SilkS")
		)
		(fp_line
			(start 12.89304 -0.882904)
			(end 12.953238 -0.882904)
			(stroke
				(width 0.1)
				(type default)
			)
			(layer "F.SilkS")
		)
		(fp_line
			(start 12.89304 -0.882904)
			(end 12.953238 -0.882904)
			(stroke
				(width 0.1)
				(type default)
			)
			(layer "F.SilkS")
		)
		(fp_line
			(start 12.89304 -0.882904)
			(end 13.288264 -1.262126)
			(stroke
				(width 0.1)
				(type default)
			)
			(layer "F.SilkS")
		)
		(fp_line
			(start 12.89304 -0.882904)
			(end 13.288264 -1.262126)
			(stroke
				(width 0.1)
				(type default)
			)
			(layer "F.SilkS")
		)
		(fp_line
			(start 12.909804 -5.169408)
			(end 12.033758 -4.328922)
			(stroke
				(width 0.1)
				(type default)
			)
			(layer "F.SilkS")
		)
		(fp_line
			(start 12.909804 -5.169408)
			(end 12.033758 -4.328922)
			(stroke
				(width 0.1)
				(type default)
			)
			(layer "F.SilkS")
		)
		(fp_line
			(start 12.953238 -0.882904)
			(end 13.01369 -0.882904)
			(stroke
				(width 0.1)
				(type default)
			)
			(layer "F.SilkS")
		)
		(fp_line
			(start 12.953238 -0.882904)
			(end 13.01369 -0.882904)
			(stroke
				(width 0.1)
				(type default)
			)
			(layer "F.SilkS")
		)
		(fp_line
			(start 12.953238 -0.882904)
			(end 13.275818 -1.19253)
			(stroke
				(width 0.1)
				(type default)
			)
			(layer "F.SilkS")
		)
		(fp_line
			(start 12.953238 -0.882904)
			(end 13.275818 -1.19253)
			(stroke
				(width 0.1)
				(type default)
			)
			(layer "F.SilkS")
		)
		(fp_line
			(start 12.955778 -5.155946)
			(end 12.09421 -4.32943)
			(stroke
				(width 0.1)
				(type default)
			)
			(layer "F.SilkS")
		)
		(fp_line
			(start 12.955778 -5.155946)
			(end 12.09421 -4.32943)
			(stroke
				(width 0.1)
				(type default)
			)
			(layer "F.SilkS")
		)
		(fp_line
			(start 12.996926 -5.137658)
			(end 12.149836 -4.325112)
			(stroke
				(width 0.1)
				(type default)
			)
			(layer "F.SilkS")
		)
		(fp_line
			(start 12.996926 -5.137658)
			(end 12.149836 -4.325112)
			(stroke
				(width 0.1)
				(type default)
			)
			(layer "F.SilkS")
		)
		(fp_line
			(start 13.01369 -0.882904)
			(end 13.073634 -0.882904)
			(stroke
				(width 0.1)
				(type default)
			)
			(layer "F.SilkS")
		)
		(fp_line
			(start 13.01369 -0.882904)
			(end 13.073634 -0.882904)
			(stroke
				(width 0.1)
				(type default)
			)
			(layer "F.SilkS")
		)
		(fp_line
			(start 13.01369 -0.882904)
			(end 13.264134 -1.123188)
			(stroke
				(width 0.1)
				(type default)
			)
			(layer "F.SilkS")
		)
		(fp_line
			(start 13.01369 -0.882904)
			(end 13.264134 -1.123188)
			(stroke
				(width 0.1)
				(type default)
			)
			(layer "F.SilkS")
		)
		(fp_line
			(start 13.038074 -5.11937)
			(end 12.205462 -4.320794)
			(stroke
				(width 0.1)
				(type default)
			)
			(layer "F.SilkS")
		)
		(fp_line
			(start 13.038074 -5.11937)
			(end 12.205462 -4.320794)
			(stroke
				(width 0.1)
				(type default)
			)
			(layer "F.SilkS")
		)
		(fp_line
			(start 13.073634 -0.882904)
			(end 13.133578 -0.882904)
			(stroke
				(width 0.1)
				(type default)
			)
			(layer "F.SilkS")
		)
		(fp_line
			(start 13.073634 -0.882904)
			(end 13.133578 -0.882904)
			(stroke
				(width 0.1)
				(type default)
			)
			(layer "F.SilkS")
		)
		(fp_line
			(start 13.073634 -0.882904)
			(end 13.251942 -1.053846)
			(stroke
				(width 0.1)
				(type default)
			)
			(layer "F.SilkS")
		)
		(fp_line
			(start 13.073634 -0.882904)
			(end 13.251942 -1.053846)
			(stroke
				(width 0.1)
				(type default)
			)
			(layer "F.SilkS")
		)
		(fp_line
			(start 13.079222 -5.101336)
			(end 12.256008 -4.311396)
			(stroke
				(width 0.1)
				(type default)
			)
			(layer "F.SilkS")
		)
		(fp_line
			(start 13.079222 -5.101336)
			(end 12.256008 -4.311396)
			(stroke
				(width 0.1)
				(type default)
			)
			(layer "F.SilkS")
		)
		(fp_line
			(start 13.120116 -5.083048)
			(end 12.302998 -4.29895)
			(stroke
				(width 0.1)
				(type default)
			)
			(layer "F.SilkS")
		)
		(fp_line
			(start 13.120116 -5.083048)
			(end 12.302998 -4.29895)
			(stroke
				(width 0.1)
				(type default)
			)
			(layer "F.SilkS")
		)
		(fp_line
			(start 13.133578 -0.882904)
			(end 13.19403 -0.882904)
			(stroke
				(width 0.1)
				(type default)
			)
			(layer "F.SilkS")
		)
		(fp_line
			(start 13.133578 -0.882904)
			(end 13.19403 -0.882904)
			(stroke
				(width 0.1)
				(type default)
			)
			(layer "F.SilkS")
		)
		(fp_line
			(start 13.133578 -0.882904)
			(end 13.23975 -0.984504)
			(stroke
				(width 0.1)
				(type default)
			)
			(layer "F.SilkS")
		)
		(fp_line
			(start 13.133578 -0.882904)
			(end 13.23975 -0.984504)
			(stroke
				(width 0.1)
				(type default)
			)
			(layer "F.SilkS")
		)
		(fp_line
			(start 13.161518 -5.06476)
			(end 12.34948 -4.285742)
			(stroke
				(width 0.1)
				(type default)
			)
			(layer "F.SilkS")
		)
		(fp_line
			(start 13.161518 -5.06476)
			(end 12.34948 -4.285742)
			(stroke
				(width 0.1)
				(type default)
			)
			(layer "F.SilkS")
		)
		(fp_line
			(start 13.19403 -0.882904)
			(end 13.22197 -0.882904)
			(stroke
				(width 0.1)
				(type default)
			)
			(layer "F.SilkS")
		)
		(fp_line
			(start 13.19403 -0.882904)
			(end 13.22197 -0.882904)
			(stroke
				(width 0.1)
				(type default)
			)
			(layer "F.SilkS")
		)
		(fp_line
			(start 13.19403 -0.882904)
			(end 13.227812 -0.914908)
			(stroke
				(width 0.1)
				(type default)
			)
			(layer "F.SilkS")
		)
		(fp_line
			(start 13.19403 -0.882904)
			(end 13.227812 -0.914908)
			(stroke
				(width 0.1)
				(type default)
			)
			(layer "F.SilkS")
		)
		(fp_line
			(start 13.20292 -5.046472)
			(end 12.388596 -4.265422)
			(stroke
				(width 0.1)
				(type default)
			)
			(layer "F.SilkS")
		)
		(fp_line
			(start 13.20292 -5.046472)
			(end 12.388596 -4.265422)
			(stroke
				(width 0.1)
				(type default)
			)
			(layer "F.SilkS")
		)
		(fp_line
			(start 13.22197 -0.882904)
			(end 13.227812 -0.914908)
			(stroke
				(width 0.1)
				(type default)
			)
			(layer "F.SilkS")
		)
		(fp_line
			(start 13.22197 -0.882904)
			(end 13.227812 -0.914908)
			(stroke
				(width 0.1)
				(type default)
			)
			(layer "F.SilkS")
		)
		(fp_line
			(start 13.227812 -0.914908)
			(end 13.23975 -0.984504)
			(stroke
				(width 0.1)
				(type default)
			)
			(layer "F.SilkS")
		)
		(fp_line
			(start 13.227812 -0.914908)
			(end 13.23975 -0.984504)
			(stroke
				(width 0.1)
				(type default)
			)
			(layer "F.SilkS")
		)
		(fp_line
			(start 13.238988 -5.023612)
			(end 12.427458 -4.245102)
			(stroke
				(width 0.1)
				(type default)
			)
			(layer "F.SilkS")
		)
		(fp_line
			(start 13.238988 -5.023612)
			(end 12.427458 -4.245102)
			(stroke
				(width 0.1)
				(type default)
			)
			(layer "F.SilkS")
		)
		(fp_line
			(start 13.23975 -0.984504)
			(end 13.251942 -1.053846)
			(stroke
				(width 0.1)
				(type default)
			)
			(layer "F.SilkS")
		)
		(fp_line
			(start 13.23975 -0.984504)
			(end 13.251942 -1.053846)
			(stroke
				(width 0.1)
				(type default)
			)
			(layer "F.SilkS")
		)
		(fp_line
			(start 13.251942 -1.053846)
			(end 13.264134 -1.123188)
			(stroke
				(width 0.1)
				(type default)
			)
			(layer "F.SilkS")
		)
		(fp_line
			(start 13.251942 -1.053846)
			(end 13.264134 -1.123188)
			(stroke
				(width 0.1)
				(type default)
			)
			(layer "F.SilkS")
		)
		(fp_line
			(start 13.264134 -1.123188)
			(end 13.275818 -1.19253)
			(stroke
				(width 0.1)
				(type default)
			)
			(layer "F.SilkS")
		)
		(fp_line
			(start 13.264134 -1.123188)
			(end 13.275818 -1.19253)
			(stroke
				(width 0.1)
				(type default)
			)
			(layer "F.SilkS")
		)
		(fp_line
			(start 13.272516 -4.998212)
			(end 12.461748 -4.22021)
			(stroke
				(width 0.1)
				(type default)
			)
			(layer "F.SilkS")
		)
		(fp_line
			(start 13.272516 -4.998212)
			(end 12.461748 -4.22021)
			(stroke
				(width 0.1)
				(type default)
			)
			(layer "F.SilkS")
		)
		(fp_line
			(start 13.275818 -1.19253)
			(end 13.288264 -1.262126)
			(stroke
				(width 0.1)
				(type default)
			)
			(layer "F.SilkS")
		)
		(fp_line
			(start 13.275818 -1.19253)
			(end 13.288264 -1.262126)
			(stroke
				(width 0.1)
				(type default)
			)
			(layer "F.SilkS")
		)
		(fp_line
			(start 13.288264 -1.262126)
			(end 13.30071 -1.331468)
			(stroke
				(width 0.1)
				(type default)
			)
			(layer "F.SilkS")
		)
		(fp_line
			(start 13.288264 -1.262126)
			(end 13.30071 -1.331468)
			(stroke
				(width 0.1)
				(type default)
			)
			(layer "F.SilkS")
		)
		(fp_line
			(start 13.30071 -1.331468)
			(end 13.312394 -1.400556)
			(stroke
				(width 0.1)
				(type default)
			)
			(layer "F.SilkS")
		)
		(fp_line
			(start 13.30071 -1.331468)
			(end 13.312394 -1.400556)
			(stroke
				(width 0.1)
				(type default)
			)
			(layer "F.SilkS")
		)
		(fp_line
			(start 13.306298 -4.972812)
			(end 12.49299 -4.192524)
			(stroke
				(width 0.1)
				(type default)
			)
			(layer "F.SilkS")
		)
		(fp_line
			(start 13.306298 -4.972812)
			(end 12.49299 -4.192524)
			(stroke
				(width 0.1)
				(type default)
			)
			(layer "F.SilkS")
		)
		(fp_line
			(start 13.312394 -1.400556)
			(end 13.32484 -1.470152)
			(stroke
				(width 0.1)
				(type default)
			)
			(layer "F.SilkS")
		)
		(fp_line
			(start 13.312394 -1.400556)
			(end 13.32484 -1.470152)
			(stroke
				(width 0.1)
				(type default)
			)
			(layer "F.SilkS")
		)
		(fp_line
			(start 13.32484 -1.470152)
			(end 13.337286 -1.539494)
			(stroke
				(width 0.1)
				(type default)
			)
			(layer "F.SilkS")
		)
		(fp_line
			(start 13.32484 -1.470152)
			(end 13.337286 -1.539494)
			(stroke
				(width 0.1)
				(type default)
			)
			(layer "F.SilkS")
		)
		(fp_line
			(start 13.337286 -1.539494)
			(end 13.34897 -1.608836)
			(stroke
				(width 0.1)
				(type default)
			)
			(layer "F.SilkS")
		)
		(fp_line
			(start 13.337286 -1.539494)
			(end 13.34897 -1.608836)
			(stroke
				(width 0.1)
				(type default)
			)
			(layer "F.SilkS")
		)
		(fp_line
			(start 13.34008 -4.947412)
			(end 12.522454 -4.16306)
			(stroke
				(width 0.1)
				(type default)
			)
			(layer "F.SilkS")
		)
		(fp_line
			(start 13.34008 -4.947412)
			(end 12.522454 -4.16306)
			(stroke
				(width 0.1)
				(type default)
			)
			(layer "F.SilkS")
		)
		(fp_line
			(start 13.34897 -1.608836)
			(end 13.361416 -1.678178)
			(stroke
				(width 0.1)
				(type default)
			)
			(layer "F.SilkS")
		)
		(fp_line
			(start 13.34897 -1.608836)
			(end 13.361416 -1.678178)
			(stroke
				(width 0.1)
				(type default)
			)
			(layer "F.SilkS")
		)
		(fp_line
			(start 13.361416 -1.678178)
			(end 13.373354 -1.74752)
			(stroke
				(width 0.1)
				(type default)
			)
			(layer "F.SilkS")
		)
		(fp_line
			(start 13.361416 -1.678178)
			(end 13.373354 -1.74752)
			(stroke
				(width 0.1)
				(type default)
			)
			(layer "F.SilkS")
		)
		(fp_line
			(start 13.373354 -1.74752)
			(end 13.385546 -1.817116)
			(stroke
				(width 0.1)
				(type default)
			)
			(layer "F.SilkS")
		)
		(fp_line
			(start 13.373354 -1.74752)
			(end 13.385546 -1.817116)
			(stroke
				(width 0.1)
				(type default)
			)
			(layer "F.SilkS")
		)
		(fp_line
			(start 13.373862 -4.922012)
			(end 12.545822 -4.127754)
			(stroke
				(width 0.1)
				(type default)
			)
			(layer "F.SilkS")
		)
		(fp_line
			(start 13.373862 -4.922012)
			(end 12.545822 -4.127754)
			(stroke
				(width 0.1)
				(type default)
			)
			(layer "F.SilkS")
		)
		(fp_line
			(start 13.385546 -1.817116)
			(end 13.397992 -1.886458)
			(stroke
				(width 0.1)
				(type default)
			)
			(layer "F.SilkS")
		)
		(fp_line
			(start 13.385546 -1.817116)
			(end 13.397992 -1.886458)
			(stroke
				(width 0.1)
				(type default)
			)
			(layer "F.SilkS")
		)
		(fp_line
			(start 13.397992 -1.886458)
			(end 13.40993 -1.9558)
			(stroke
				(width 0.1)
				(type default)
			)
			(layer "F.SilkS")
		)
		(fp_line
			(start 13.397992 -1.886458)
			(end 13.40993 -1.9558)
			(stroke
				(width 0.1)
				(type default)
			)
			(layer "F.SilkS")
		)
		(fp_line
			(start 13.407136 -4.896358)
			(end 12.568936 -4.092194)
			(stroke
				(width 0.1)
				(type default)
			)
			(layer "F.SilkS")
		)
		(fp_line
			(start 13.407136 -4.896358)
			(end 12.568936 -4.092194)
			(stroke
				(width 0.1)
				(type default)
			)
			(layer "F.SilkS")
		)
		(fp_line
			(start 13.40993 -1.9558)
			(end 13.422122 -2.025396)
			(stroke
				(width 0.1)
				(type default)
			)
			(layer "F.SilkS")
		)
		(fp_line
			(start 13.40993 -1.9558)
			(end 13.422122 -2.025396)
			(stroke
				(width 0.1)
				(type default)
			)
			(layer "F.SilkS")
		)
		(fp_line
			(start 13.422122 -2.025396)
			(end 13.434314 -2.094738)
			(stroke
				(width 0.1)
				(type default)
			)
			(layer "F.SilkS")
		)
		(fp_line
			(start 13.422122 -2.025396)
			(end 13.434314 -2.094738)
			(stroke
				(width 0.1)
				(type default)
			)
			(layer "F.SilkS")
		)
		(fp_line
			(start 13.434314 -2.094738)
			(end 13.446506 -2.163826)
			(stroke
				(width 0.1)
				(type default)
			)
			(layer "F.SilkS")
		)
		(fp_line
			(start 13.434314 -2.094738)
			(end 13.446506 -2.163826)
			(stroke
				(width 0.1)
				(type default)
			)
			(layer "F.SilkS")
		)
		(fp_line
			(start 13.440664 -4.871212)
			(end 12.58443 -4.049522)
			(stroke
				(width 0.1)
				(type default)
			)
			(layer "F.SilkS")
		)
		(fp_line
			(start 13.440664 -4.871212)
			(end 12.58443 -4.049522)
			(stroke
				(width 0.1)
				(type default)
			)
			(layer "F.SilkS")
		)
		(fp_line
			(start 13.446506 -2.163826)
			(end 13.458444 -2.233422)
			(stroke
				(width 0.1)
				(type default)
			)
			(layer "F.SilkS")
		)
		(fp_line
			(start 13.446506 -2.163826)
			(end 13.458444 -2.233422)
			(stroke
				(width 0.1)
				(type default)
			)
			(layer "F.SilkS")
		)
		(fp_line
			(start 13.458444 -2.233422)
			(end 13.47089 -2.302764)
			(stroke
				(width 0.1)
				(type default)
			)
			(layer "F.SilkS")
		)
		(fp_line
			(start 13.458444 -2.233422)
			(end 13.47089 -2.302764)
			(stroke
				(width 0.1)
				(type default)
			)
			(layer "F.SilkS")
		)
		(fp_line
			(start 13.466826 -4.837938)
			(end 12.599162 -4.005834)
			(stroke
				(width 0.1)
				(type default)
			)
			(layer "F.SilkS")
		)
		(fp_line
			(start 13.466826 -4.837938)
			(end 12.599162 -4.005834)
			(stroke
				(width 0.1)
				(type default)
			)
			(layer "F.SilkS")
		)
		(fp_line
			(start 13.47089 -2.302764)
			(end 13.483082 -2.372106)
			(stroke
				(width 0.1)
				(type default)
			)
			(layer "F.SilkS")
		)
		(fp_line
			(start 13.47089 -2.302764)
			(end 13.483082 -2.372106)
			(stroke
				(width 0.1)
				(type default)
			)
			(layer "F.SilkS")
		)
		(fp_line
			(start 13.483082 -2.372106)
			(end 13.49502 -2.441448)
			(stroke
				(width 0.1)
				(type default)
			)
			(layer "F.SilkS")
		)
		(fp_line
			(start 13.483082 -2.372106)
			(end 13.49502 -2.441448)
			(stroke
				(width 0.1)
				(type default)
			)
			(layer "F.SilkS")
		)
		(fp_line
			(start 13.492226 -4.804918)
			(end 12.606782 -3.955288)
			(stroke
				(width 0.1)
				(type default)
			)
			(layer "F.SilkS")
		)
		(fp_line
			(start 13.492226 -4.804918)
			(end 12.606782 -3.955288)
			(stroke
				(width 0.1)
				(type default)
			)
			(layer "F.SilkS")
		)
		(fp_line
			(start 13.49502 -2.441448)
			(end 13.507466 -2.51079)
			(stroke
				(width 0.1)
				(type default)
			)
			(layer "F.SilkS")
		)
		(fp_line
			(start 13.49502 -2.441448)
			(end 13.507466 -2.51079)
			(stroke
				(width 0.1)
				(type default)
			)
			(layer "F.SilkS")
		)
		(fp_line
			(start 13.507466 -2.51079)
			(end 13.519404 -2.580386)
			(stroke
				(width 0.1)
				(type default)
			)
			(layer "F.SilkS")
		)
		(fp_line
			(start 13.507466 -2.51079)
			(end 13.519404 -2.580386)
			(stroke
				(width 0.1)
				(type default)
			)
			(layer "F.SilkS")
		)
		(fp_line
			(start 13.518134 -4.771898)
			(end 12.612116 -3.902964)
			(stroke
				(width 0.1)
				(type default)
			)
			(layer "F.SilkS")
		)
		(fp_line
			(start 13.518134 -4.771898)
			(end 12.612116 -3.902964)
			(stroke
				(width 0.1)
				(type default)
			)
			(layer "F.SilkS")
		)
		(fp_line
			(start 13.519404 -2.580386)
			(end 13.531596 -2.649728)
			(stroke
				(width 0.1)
				(type default)
			)
			(layer "F.SilkS")
		)
		(fp_line
			(start 13.519404 -2.580386)
			(end 13.531596 -2.649728)
			(stroke
				(width 0.1)
				(type default)
			)
			(layer "F.SilkS")
		)
		(fp_line
			(start 13.531596 -2.649728)
			(end 13.544042 -2.71907)
			(stroke
				(width 0.1)
				(type default)
			)
			(layer "F.SilkS")
		)
		(fp_line
			(start 13.531596 -2.649728)
			(end 13.544042 -2.71907)
			(stroke
				(width 0.1)
				(type default)
			)
			(layer "F.SilkS")
		)
		(fp_line
			(start 13.544042 -4.738878)
			(end 12.60856 -3.84175)
			(stroke
				(width 0.1)
				(type default)
			)
			(layer "F.SilkS")
		)
		(fp_line
			(start 13.544042 -4.738878)
			(end 12.60856 -3.84175)
			(stroke
				(width 0.1)
				(type default)
			)
			(layer "F.SilkS")
		)
		(fp_line
			(start 13.544042 -2.71907)
			(end 13.55598 -2.788412)
			(stroke
				(width 0.1)
				(type default)
			)
			(layer "F.SilkS")
		)
		(fp_line
			(start 13.544042 -2.71907)
			(end 13.55598 -2.788412)
			(stroke
				(width 0.1)
				(type default)
			)
			(layer "F.SilkS")
		)
		(fp_line
			(start 13.55598 -2.788412)
			(end 13.568172 -2.857754)
			(stroke
				(width 0.1)
				(type default)
			)
			(layer "F.SilkS")
		)
		(fp_line
			(start 13.55598 -2.788412)
			(end 13.568172 -2.857754)
			(stroke
				(width 0.1)
				(type default)
			)
			(layer "F.SilkS")
		)
		(fp_line
			(start 13.568172 -2.857754)
			(end 13.580364 -2.927096)
			(stroke
				(width 0.1)
				(type default)
			)
			(layer "F.SilkS")
		)
		(fp_line
			(start 13.568172 -2.857754)
			(end 13.580364 -2.927096)
			(stroke
				(width 0.1)
				(type default)
			)
			(layer "F.SilkS")
		)
		(fp_line
			(start 13.569442 -4.705858)
			(end 12.601956 -3.777996)
			(stroke
				(width 0.1)
				(type default)
			)
			(layer "F.SilkS")
		)
		(fp_line
			(start 13.569442 -4.705858)
			(end 12.601956 -3.777996)
			(stroke
				(width 0.1)
				(type default)
			)
			(layer "F.SilkS")
		)
		(fp_line
			(start 13.580364 -2.927096)
			(end 13.592556 -2.996692)
			(stroke
				(width 0.1)
				(type default)
			)
			(layer "F.SilkS")
		)
		(fp_line
			(start 13.580364 -2.927096)
			(end 13.592556 -2.996692)
			(stroke
				(width 0.1)
				(type default)
			)
			(layer "F.SilkS")
		)
		(fp_line
			(start 13.592556 -2.996692)
			(end 13.604494 -3.06578)
			(stroke
				(width 0.1)
				(type default)
			)
			(layer "F.SilkS")
		)
		(fp_line
			(start 13.592556 -2.996692)
			(end 13.604494 -3.06578)
			(stroke
				(width 0.1)
				(type default)
			)
			(layer "F.SilkS")
		)
		(fp_line
			(start 13.59535 -4.672838)
			(end 12.590018 -3.708654)
			(stroke
				(width 0.1)
				(type default)
			)
			(layer "F.SilkS")
		)
		(fp_line
			(start 13.59535 -4.672838)
			(end 12.590018 -3.708654)
			(stroke
				(width 0.1)
				(type default)
			)
			(layer "F.SilkS")
		)
		(fp_line
			(start 13.604494 -3.06578)
			(end 13.61694 -3.135376)
			(stroke
				(width 0.1)
				(type default)
			)
			(layer "F.SilkS")
		)
		(fp_line
			(start 13.604494 -3.06578)
			(end 13.61694 -3.135376)
			(stroke
				(width 0.1)
				(type default)
			)
			(layer "F.SilkS")
		)
		(fp_line
			(start 13.616432 -4.635246)
			(end 12.57808 -3.639312)
			(stroke
				(width 0.1)
				(type default)
			)
			(layer "F.SilkS")
		)
		(fp_line
			(start 13.616432 -4.635246)
			(end 12.57808 -3.639312)
			(stroke
				(width 0.1)
				(type default)
			)
			(layer "F.SilkS")
		)
		(fp_line
			(start 13.61694 -3.135376)
			(end 13.629132 -3.204972)
			(stroke
				(width 0.1)
				(type default)
			)
			(layer "F.SilkS")
		)
		(fp_line
			(start 13.61694 -3.135376)
			(end 13.629132 -3.204972)
			(stroke
				(width 0.1)
				(type default)
			)
			(layer "F.SilkS")
		)
		(fp_line
			(start 13.629132 -3.204972)
			(end 13.64107 -3.27406)
			(stroke
				(width 0.1)
				(type default)
			)
			(layer "F.SilkS")
		)
		(fp_line
			(start 13.629132 -3.204972)
			(end 13.64107 -3.27406)
			(stroke
				(width 0.1)
				(type default)
			)
			(layer "F.SilkS")
		)
		(fp_line
			(start 13.633196 -4.593844)
			(end 11.82116 -2.855722)
			(stroke
				(width 0.1)
				(type default)
			)
			(layer "F.SilkS")
		)
		(fp_line
			(start 13.633196 -4.593844)
			(end 11.82116 -2.855722)
			(stroke
				(width 0.1)
				(type default)
			)
			(layer "F.SilkS")
		)
		(fp_line
			(start 13.64996 -4.552442)
			(end 11.877548 -2.851912)
			(stroke
				(width 0.1)
				(type default)
			)
			(layer "F.SilkS")
		)
		(fp_line
			(start 13.64996 -4.552442)
			(end 11.877548 -2.851912)
			(stroke
				(width 0.1)
				(type default)
			)
			(layer "F.SilkS")
		)
		(fp_line
			(start 13.653516 -3.343402)
			(end 13.64107 -3.27406)
			(stroke
				(width 0.1)
				(type default)
			)
			(layer "F.SilkS")
		)
		(fp_line
			(start 13.653516 -3.343402)
			(end 13.64107 -3.27406)
			(stroke
				(width 0.1)
				(type default)
			)
			(layer "F.SilkS")
		)
		(fp_line
			(start 13.665708 -3.412998)
			(end 10.943336 -0.801624)
			(stroke
				(width 0.1)
				(type default)
			)
			(layer "F.SilkS")
		)
		(fp_line
			(start 13.665708 -3.412998)
			(end 10.943336 -0.801624)
			(stroke
				(width 0.1)
				(type default)
			)
			(layer "F.SilkS")
		)
		(fp_line
			(start 13.665708 -3.412998)
			(end 13.653516 -3.343402)
			(stroke
				(width 0.1)
				(type default)
			)
			(layer "F.SilkS")
		)
		(fp_line
			(start 13.665708 -3.412998)
			(end 13.653516 -3.343402)
			(stroke
				(width 0.1)
				(type default)
			)
			(layer "F.SilkS")
		)
		(fp_line
			(start 13.667232 -4.51104)
			(end 11.93292 -2.84734)
			(stroke
				(width 0.1)
				(type default)
			)
			(layer "F.SilkS")
		)
		(fp_line
			(start 13.667232 -4.51104)
			(end 11.93292 -2.84734)
			(stroke
				(width 0.1)
				(type default)
			)
			(layer "F.SilkS")
		)
		(fp_line
			(start 13.677646 -3.48234)
			(end 12.323064 -2.182622)
			(stroke
				(width 0.1)
				(type default)
			)
			(layer "F.SilkS")
		)
		(fp_line
			(start 13.677646 -3.48234)
			(end 12.323064 -2.182622)
			(stroke
				(width 0.1)
				(type default)
			)
			(layer "F.SilkS")
		)
		(fp_line
			(start 13.677646 -3.48234)
			(end 13.665708 -3.412998)
			(stroke
				(width 0.1)
				(type default)
			)
			(layer "F.SilkS")
		)
		(fp_line
			(start 13.677646 -3.48234)
			(end 13.665708 -3.412998)
			(stroke
				(width 0.1)
				(type default)
			)
			(layer "F.SilkS")
		)
		(fp_line
			(start 13.684504 -4.469638)
			(end 11.986006 -2.840482)
			(stroke
				(width 0.1)
				(type default)
			)
			(layer "F.SilkS")
		)
		(fp_line
			(start 13.684504 -4.469638)
			(end 11.986006 -2.840482)
			(stroke
				(width 0.1)
				(type default)
			)
			(layer "F.SilkS")
		)
		(fp_line
			(start 13.690092 -3.551682)
			(end 12.335002 -2.251964)
			(stroke
				(width 0.1)
				(type default)
			)
			(layer "F.SilkS")
		)
		(fp_line
			(start 13.690092 -3.551682)
			(end 12.335002 -2.251964)
			(stroke
				(width 0.1)
				(type default)
			)
			(layer "F.SilkS")
		)
		(fp_line
			(start 13.690092 -3.551682)
			(end 13.677646 -3.48234)
			(stroke
				(width 0.1)
				(type default)
			)
			(layer "F.SilkS")
		)
		(fp_line
			(start 13.690092 -3.551682)
			(end 13.677646 -3.48234)
			(stroke
				(width 0.1)
				(type default)
			)
			(layer "F.SilkS")
		)
		(fp_line
			(start 13.701014 -4.42849)
			(end 12.037822 -2.832862)
			(stroke
				(width 0.1)
				(type default)
			)
			(layer "F.SilkS")
		)
		(fp_line
			(start 13.701014 -4.42849)
			(end 12.037822 -2.832862)
			(stroke
				(width 0.1)
				(type default)
			)
			(layer "F.SilkS")
		)
		(fp_line
			(start 13.70203 -3.621024)
			(end 12.347194 -2.321306)
			(stroke
				(width 0.1)
				(type default)
			)
			(layer "F.SilkS")
		)
		(fp_line
			(start 13.70203 -3.621024)
			(end 12.347194 -2.321306)
			(stroke
				(width 0.1)
				(type default)
			)
			(layer "F.SilkS")
		)
		(fp_line
			(start 13.70203 -3.621024)
			(end 13.690092 -3.551682)
			(stroke
				(width 0.1)
				(type default)
			)
			(layer "F.SilkS")
		)
		(fp_line
			(start 13.70203 -3.621024)
			(end 13.690092 -3.551682)
			(stroke
				(width 0.1)
				(type default)
			)
			(layer "F.SilkS")
		)
		(fp_line
			(start 13.714222 -3.690366)
			(end 12.359386 -2.390902)
			(stroke
				(width 0.1)
				(type default)
			)
			(layer "F.SilkS")
		)
		(fp_line
			(start 13.714222 -3.690366)
			(end 12.359386 -2.390902)
			(stroke
				(width 0.1)
				(type default)
			)
			(layer "F.SilkS")
		)
		(fp_line
			(start 13.714222 -3.690366)
			(end 13.70203 -3.621024)
			(stroke
				(width 0.1)
				(type default)
			)
			(layer "F.SilkS")
		)
		(fp_line
			(start 13.714222 -3.690366)
			(end 13.70203 -3.621024)
			(stroke
				(width 0.1)
				(type default)
			)
			(layer "F.SilkS")
		)
		(fp_line
			(start 13.715238 -4.383786)
			(end 12.087352 -2.822448)
			(stroke
				(width 0.1)
				(type default)
			)
			(layer "F.SilkS")
		)
		(fp_line
			(start 13.715238 -4.383786)
			(end 12.087352 -2.822448)
			(stroke
				(width 0.1)
				(type default)
			)
			(layer "F.SilkS")
		)
		(fp_line
			(start 13.722096 -4.332732)
			(end 12.135612 -2.810764)
			(stroke
				(width 0.1)
				(type default)
			)
			(layer "F.SilkS")
		)
		(fp_line
			(start 13.722096 -4.332732)
			(end 12.135612 -2.810764)
			(stroke
				(width 0.1)
				(type default)
			)
			(layer "F.SilkS")
		)
		(fp_line
			(start 13.72616 -3.759962)
			(end 12.371578 -2.460244)
			(stroke
				(width 0.1)
				(type default)
			)
			(layer "F.SilkS")
		)
		(fp_line
			(start 13.72616 -3.759962)
			(end 12.371578 -2.460244)
			(stroke
				(width 0.1)
				(type default)
			)
			(layer "F.SilkS")
		)
		(fp_line
			(start 13.729208 -4.281932)
			(end 12.181078 -2.796794)
			(stroke
				(width 0.1)
				(type default)
			)
			(layer "F.SilkS")
		)
		(fp_line
			(start 13.729208 -4.281932)
			(end 12.181078 -2.796794)
			(stroke
				(width 0.1)
				(type default)
			)
			(layer "F.SilkS")
		)
		(fp_line
			(start 13.731494 -3.822446)
			(end 12.38377 -2.529586)
			(stroke
				(width 0.1)
				(type default)
			)
			(layer "F.SilkS")
		)
		(fp_line
			(start 13.731494 -3.822446)
			(end 12.38377 -2.529586)
			(stroke
				(width 0.1)
				(type default)
			)
			(layer "F.SilkS")
		)
		(fp_line
			(start 13.73632 -4.230878)
			(end 12.224766 -2.781046)
			(stroke
				(width 0.1)
				(type default)
			)
			(layer "F.SilkS")
		)
		(fp_line
			(start 13.73632 -4.230878)
			(end 12.224766 -2.781046)
			(stroke
				(width 0.1)
				(type default)
			)
			(layer "F.SilkS")
		)
		(fp_line
			(start 13.736574 -3.88493)
			(end 12.395962 -2.598928)
			(stroke
				(width 0.1)
				(type default)
			)
			(layer "F.SilkS")
		)
		(fp_line
			(start 13.736574 -3.88493)
			(end 12.395962 -2.598928)
			(stroke
				(width 0.1)
				(type default)
			)
			(layer "F.SilkS")
		)
		(fp_line
			(start 13.741654 -3.947668)
			(end 12.408154 -2.668524)
			(stroke
				(width 0.1)
				(type default)
			)
			(layer "F.SilkS")
		)
		(fp_line
			(start 13.741654 -3.947668)
			(end 12.408154 -2.668524)
			(stroke
				(width 0.1)
				(type default)
			)
			(layer "F.SilkS")
		)
		(fp_line
			(start 13.743178 -4.179824)
			(end 12.266422 -2.76352)
			(stroke
				(width 0.1)
				(type default)
			)
			(layer "F.SilkS")
		)
		(fp_line
			(start 13.743178 -4.179824)
			(end 12.266422 -2.76352)
			(stroke
				(width 0.1)
				(type default)
			)
			(layer "F.SilkS")
		)
		(fp_line
			(start 13.74648 -4.010152)
			(end 12.380214 -2.699512)
			(stroke
				(width 0.1)
				(type default)
			)
			(layer "F.SilkS")
		)
		(fp_line
			(start 13.74648 -4.010152)
			(end 12.380214 -2.699512)
			(stroke
				(width 0.1)
				(type default)
			)
			(layer "F.SilkS")
		)
		(fp_line
			(start 13.750036 -4.12877)
			(end 12.306046 -2.743454)
			(stroke
				(width 0.1)
				(type default)
			)
			(layer "F.SilkS")
		)
		(fp_line
			(start 13.750036 -4.12877)
			(end 12.306046 -2.743454)
			(stroke
				(width 0.1)
				(type default)
			)
			(layer "F.SilkS")
		)
		(fp_line
			(start 13.751814 -4.072636)
			(end 12.344654 -2.722626)
			(stroke
				(width 0.1)
				(type default)
			)
			(layer "F.SilkS")
		)
		(fp_line
			(start 13.751814 -4.072636)
			(end 12.344654 -2.722626)
			(stroke
				(width 0.1)
				(type default)
			)
			(layer "F.SilkS")
		)
		(fp_line
			(start 13.944854 -0.882904)
			(end 13.976096 -0.882904)
			(stroke
				(width 0.1)
				(type default)
			)
			(layer "F.SilkS")
		)
		(fp_line
			(start 13.944854 -0.882904)
			(end 13.976096 -0.882904)
			(stroke
				(width 0.1)
				(type default)
			)
			(layer "F.SilkS")
		)
		(fp_line
			(start 13.95095 -0.916178)
			(end 13.944854 -0.882904)
			(stroke
				(width 0.1)
				(type default)
			)
			(layer "F.SilkS")
		)
		(fp_line
			(start 13.95095 -0.916178)
			(end 13.944854 -0.882904)
			(stroke
				(width 0.1)
				(type default)
			)
			(layer "F.SilkS")
		)
		(fp_line
			(start 13.95095 -0.916178)
			(end 15.307056 -2.21742)
			(stroke
				(width 0.1)
				(type default)
			)
			(layer "F.SilkS")
		)
		(fp_line
			(start 13.95095 -0.916178)
			(end 15.307056 -2.21742)
			(stroke
				(width 0.1)
				(type default)
			)
			(layer "F.SilkS")
		)
		(fp_line
			(start 13.962888 -0.985774)
			(end 13.95095 -0.916178)
			(stroke
				(width 0.1)
				(type default)
			)
			(layer "F.SilkS")
		)
		(fp_line
			(start 13.962888 -0.985774)
			(end 13.95095 -0.916178)
			(stroke
				(width 0.1)
				(type default)
			)
			(layer "F.SilkS")
		)
		(fp_line
			(start 13.962888 -0.985774)
			(end 15.319248 -2.286762)
			(stroke
				(width 0.1)
				(type default)
			)
			(layer "F.SilkS")
		)
		(fp_line
			(start 13.962888 -0.985774)
			(end 15.319248 -2.286762)
			(stroke
				(width 0.1)
				(type default)
			)
			(layer "F.SilkS")
		)
		(fp_line
			(start 13.975334 -1.055116)
			(end 13.962888 -0.985774)
			(stroke
				(width 0.1)
				(type default)
			)
			(layer "F.SilkS")
		)
		(fp_line
			(start 13.975334 -1.055116)
			(end 13.962888 -0.985774)
			(stroke
				(width 0.1)
				(type default)
			)
			(layer "F.SilkS")
		)
		(fp_line
			(start 13.975334 -1.055116)
			(end 15.331186 -2.356104)
			(stroke
				(width 0.1)
				(type default)
			)
			(layer "F.SilkS")
		)
		(fp_line
			(start 13.975334 -1.055116)
			(end 15.331186 -2.356104)
			(stroke
				(width 0.1)
				(type default)
			)
			(layer "F.SilkS")
		)
		(fp_line
			(start 13.976096 -0.882904)
			(end 14.036294 -0.882904)
			(stroke
				(width 0.1)
				(type default)
			)
			(layer "F.SilkS")
		)
		(fp_line
			(start 13.976096 -0.882904)
			(end 14.036294 -0.882904)
			(stroke
				(width 0.1)
				(type default)
			)
			(layer "F.SilkS")
		)
		(fp_line
			(start 13.976096 -0.882904)
			(end 15.294864 -2.147824)
			(stroke
				(width 0.1)
				(type default)
			)
			(layer "F.SilkS")
		)
		(fp_line
			(start 13.976096 -0.882904)
			(end 15.294864 -2.147824)
			(stroke
				(width 0.1)
				(type default)
			)
			(layer "F.SilkS")
		)
		(fp_line
			(start 13.987272 -1.124458)
			(end 13.975334 -1.055116)
			(stroke
				(width 0.1)
				(type default)
			)
			(layer "F.SilkS")
		)
		(fp_line
			(start 13.987272 -1.124458)
			(end 13.975334 -1.055116)
			(stroke
				(width 0.1)
				(type default)
			)
			(layer "F.SilkS")
		)
		(fp_line
			(start 13.987272 -1.124458)
			(end 15.343632 -2.425446)
			(stroke
				(width 0.1)
				(type default)
			)
			(layer "F.SilkS")
		)
		(fp_line
			(start 13.987272 -1.124458)
			(end 15.343632 -2.425446)
			(stroke
				(width 0.1)
				(type default)
			)
			(layer "F.SilkS")
		)
		(fp_line
			(start 13.999464 -1.194054)
			(end 13.987272 -1.124458)
			(stroke
				(width 0.1)
				(type default)
			)
			(layer "F.SilkS")
		)
		(fp_line
			(start 13.999464 -1.194054)
			(end 13.987272 -1.124458)
			(stroke
				(width 0.1)
				(type default)
			)
			(layer "F.SilkS")
		)
		(fp_line
			(start 13.999464 -1.194054)
			(end 15.355824 -2.495042)
			(stroke
				(width 0.1)
				(type default)
			)
			(layer "F.SilkS")
		)
		(fp_line
			(start 13.999464 -1.194054)
			(end 15.355824 -2.495042)
			(stroke
				(width 0.1)
				(type default)
			)
			(layer "F.SilkS")
		)
		(fp_line
			(start 14.01191 -1.26365)
			(end 13.999464 -1.194054)
			(stroke
				(width 0.1)
				(type default)
			)
			(layer "F.SilkS")
		)
		(fp_line
			(start 14.01191 -1.26365)
			(end 13.999464 -1.194054)
			(stroke
				(width 0.1)
				(type default)
			)
			(layer "F.SilkS")
		)
		(fp_line
			(start 14.01191 -1.26365)
			(end 15.367762 -2.564384)
			(stroke
				(width 0.1)
				(type default)
			)
			(layer "F.SilkS")
		)
		(fp_line
			(start 14.01191 -1.26365)
			(end 15.367762 -2.564384)
			(stroke
				(width 0.1)
				(type default)
			)
			(layer "F.SilkS")
		)
		(fp_line
			(start 14.023848 -1.332738)
			(end 14.01191 -1.26365)
			(stroke
				(width 0.1)
				(type default)
			)
			(layer "F.SilkS")
		)
		(fp_line
			(start 14.023848 -1.332738)
			(end 14.01191 -1.26365)
			(stroke
				(width 0.1)
				(type default)
			)
			(layer "F.SilkS")
		)
		(fp_line
			(start 14.023848 -1.332738)
			(end 15.380208 -2.633726)
			(stroke
				(width 0.1)
				(type default)
			)
			(layer "F.SilkS")
		)
		(fp_line
			(start 14.023848 -1.332738)
			(end 15.380208 -2.633726)
			(stroke
				(width 0.1)
				(type default)
			)
			(layer "F.SilkS")
		)
		(fp_line
			(start 14.03604 -1.40208)
			(end 14.023848 -1.332738)
			(stroke
				(width 0.1)
				(type default)
			)
			(layer "F.SilkS")
		)
		(fp_line
			(start 14.03604 -1.40208)
			(end 14.023848 -1.332738)
			(stroke
				(width 0.1)
				(type default)
			)
			(layer "F.SilkS")
		)
		(fp_line
			(start 14.03604 -1.40208)
			(end 15.392654 -2.703322)
			(stroke
				(width 0.1)
				(type default)
			)
			(layer "F.SilkS")
		)
		(fp_line
			(start 14.03604 -1.40208)
			(end 15.392654 -2.703322)
			(stroke
				(width 0.1)
				(type default)
			)
			(layer "F.SilkS")
		)
		(fp_line
			(start 14.036294 -0.882904)
			(end 14.096238 -0.882904)
			(stroke
				(width 0.1)
				(type default)
			)
			(layer "F.SilkS")
		)
		(fp_line
			(start 14.036294 -0.882904)
			(end 14.096238 -0.882904)
			(stroke
				(width 0.1)
				(type default)
			)
			(layer "F.SilkS")
		)
		(fp_line
			(start 14.036294 -0.882904)
			(end 15.282418 -2.078482)
			(stroke
				(width 0.1)
				(type default)
			)
			(layer "F.SilkS")
		)
		(fp_line
			(start 14.036294 -0.882904)
			(end 15.282418 -2.078482)
			(stroke
				(width 0.1)
				(type default)
			)
			(layer "F.SilkS")
		)
		(fp_line
			(start 14.048232 -1.471676)
			(end 14.03604 -1.40208)
			(stroke
				(width 0.1)
				(type default)
			)
			(layer "F.SilkS")
		)
		(fp_line
			(start 14.048232 -1.471676)
			(end 14.03604 -1.40208)
			(stroke
				(width 0.1)
				(type default)
			)
			(layer "F.SilkS")
		)
		(fp_line
			(start 14.048232 -1.471676)
			(end 15.404592 -2.772664)
			(stroke
				(width 0.1)
				(type default)
			)
			(layer "F.SilkS")
		)
		(fp_line
			(start 14.048232 -1.471676)
			(end 15.404592 -2.772664)
			(stroke
				(width 0.1)
				(type default)
			)
			(layer "F.SilkS")
		)
		(fp_line
			(start 14.060678 -1.541018)
			(end 14.048232 -1.471676)
			(stroke
				(width 0.1)
				(type default)
			)
			(layer "F.SilkS")
		)
		(fp_line
			(start 14.060678 -1.541018)
			(end 14.048232 -1.471676)
			(stroke
				(width 0.1)
				(type default)
			)
			(layer "F.SilkS")
		)
		(fp_line
			(start 14.060678 -1.541018)
			(end 15.416784 -2.84226)
			(stroke
				(width 0.1)
				(type default)
			)
			(layer "F.SilkS")
		)
		(fp_line
			(start 14.060678 -1.541018)
			(end 15.416784 -2.84226)
			(stroke
				(width 0.1)
				(type default)
			)
			(layer "F.SilkS")
		)
		(fp_line
			(start 14.072362 -1.61036)
			(end 14.060678 -1.541018)
			(stroke
				(width 0.1)
				(type default)
			)
			(layer "F.SilkS")
		)
		(fp_line
			(start 14.072362 -1.61036)
			(end 14.060678 -1.541018)
			(stroke
				(width 0.1)
				(type default)
			)
			(layer "F.SilkS")
		)
		(fp_line
			(start 14.072362 -1.61036)
			(end 15.42923 -2.911602)
			(stroke
				(width 0.1)
				(type default)
			)
			(layer "F.SilkS")
		)
		(fp_line
			(start 14.072362 -1.61036)
			(end 15.42923 -2.911602)
			(stroke
				(width 0.1)
				(type default)
			)
			(layer "F.SilkS")
		)
		(fp_line
			(start 14.084808 -1.679702)
			(end 14.072362 -1.61036)
			(stroke
				(width 0.1)
				(type default)
			)
			(layer "F.SilkS")
		)
		(fp_line
			(start 14.084808 -1.679702)
			(end 14.072362 -1.61036)
			(stroke
				(width 0.1)
				(type default)
			)
			(layer "F.SilkS")
		)
		(fp_line
			(start 14.084808 -1.679702)
			(end 14.097254 -1.749044)
			(stroke
				(width 0.1)
				(type default)
			)
			(layer "F.SilkS")
		)
		(fp_line
			(start 14.084808 -1.679702)
			(end 14.097254 -1.749044)
			(stroke
				(width 0.1)
				(type default)
			)
			(layer "F.SilkS")
		)
		(fp_line
			(start 14.096238 -0.882904)
			(end 14.156436 -0.882904)
			(stroke
				(width 0.1)
				(type default)
			)
			(layer "F.SilkS")
		)
		(fp_line
			(start 14.096238 -0.882904)
			(end 14.156436 -0.882904)
			(stroke
				(width 0.1)
				(type default)
			)
			(layer "F.SilkS")
		)
		(fp_line
			(start 14.096238 -0.882904)
			(end 15.270226 -2.00914)
			(stroke
				(width 0.1)
				(type default)
			)
			(layer "F.SilkS")
		)
		(fp_line
			(start 14.096238 -0.882904)
			(end 15.270226 -2.00914)
			(stroke
				(width 0.1)
				(type default)
			)
			(layer "F.SilkS")
		)
		(fp_line
			(start 14.109192 -1.81864)
			(end 14.097254 -1.749044)
			(stroke
				(width 0.1)
				(type default)
			)
			(layer "F.SilkS")
		)
		(fp_line
			(start 14.109192 -1.81864)
			(end 14.097254 -1.749044)
			(stroke
				(width 0.1)
				(type default)
			)
			(layer "F.SilkS")
		)
		(fp_line
			(start 14.121384 -1.887982)
			(end 14.109192 -1.81864)
			(stroke
				(width 0.1)
				(type default)
			)
			(layer "F.SilkS")
		)
		(fp_line
			(start 14.121384 -1.887982)
			(end 14.109192 -1.81864)
			(stroke
				(width 0.1)
				(type default)
			)
			(layer "F.SilkS")
		)
		(fp_line
			(start 14.13383 -1.957324)
			(end 14.121384 -1.887982)
			(stroke
				(width 0.1)
				(type default)
			)
			(layer "F.SilkS")
		)
		(fp_line
			(start 14.13383 -1.957324)
			(end 14.121384 -1.887982)
			(stroke
				(width 0.1)
				(type default)
			)
			(layer "F.SilkS")
		)
		(fp_line
			(start 14.145768 -2.02692)
			(end 14.13383 -1.957324)
			(stroke
				(width 0.1)
				(type default)
			)
			(layer "F.SilkS")
		)
		(fp_line
			(start 14.145768 -2.02692)
			(end 14.13383 -1.957324)
			(stroke
				(width 0.1)
				(type default)
			)
			(layer "F.SilkS")
		)
		(fp_line
			(start 14.156436 -0.882904)
			(end 14.216888 -0.882904)
			(stroke
				(width 0.1)
				(type default)
			)
			(layer "F.SilkS")
		)
		(fp_line
			(start 14.156436 -0.882904)
			(end 14.216888 -0.882904)
			(stroke
				(width 0.1)
				(type default)
			)
			(layer "F.SilkS")
		)
		(fp_line
			(start 14.156436 -0.882904)
			(end 15.258288 -1.939544)
			(stroke
				(width 0.1)
				(type default)
			)
			(layer "F.SilkS")
		)
		(fp_line
			(start 14.156436 -0.882904)
			(end 15.258288 -1.939544)
			(stroke
				(width 0.1)
				(type default)
			)
			(layer "F.SilkS")
		)
		(fp_line
			(start 14.15796 -2.096262)
			(end 14.145768 -2.02692)
			(stroke
				(width 0.1)
				(type default)
			)
			(layer "F.SilkS")
		)
		(fp_line
			(start 14.15796 -2.096262)
			(end 14.145768 -2.02692)
			(stroke
				(width 0.1)
				(type default)
			)
			(layer "F.SilkS")
		)
		(fp_line
			(start 14.170406 -2.165604)
			(end 14.15796 -2.096262)
			(stroke
				(width 0.1)
				(type default)
			)
			(layer "F.SilkS")
		)
		(fp_line
			(start 14.170406 -2.165604)
			(end 14.15796 -2.096262)
			(stroke
				(width 0.1)
				(type default)
			)
			(layer "F.SilkS")
		)
		(fp_line
			(start 14.182344 -2.234946)
			(end 14.170406 -2.165604)
			(stroke
				(width 0.1)
				(type default)
			)
			(layer "F.SilkS")
		)
		(fp_line
			(start 14.182344 -2.234946)
			(end 14.170406 -2.165604)
			(stroke
				(width 0.1)
				(type default)
			)
			(layer "F.SilkS")
		)
		(fp_line
			(start 14.194282 -2.304288)
			(end 14.182344 -2.234946)
			(stroke
				(width 0.1)
				(type default)
			)
			(layer "F.SilkS")
		)
		(fp_line
			(start 14.194282 -2.304288)
			(end 14.182344 -2.234946)
			(stroke
				(width 0.1)
				(type default)
			)
			(layer "F.SilkS")
		)
		(fp_line
			(start 14.206728 -2.373884)
			(end 14.194282 -2.304288)
			(stroke
				(width 0.1)
				(type default)
			)
			(layer "F.SilkS")
		)
		(fp_line
			(start 14.206728 -2.373884)
			(end 14.194282 -2.304288)
			(stroke
				(width 0.1)
				(type default)
			)
			(layer "F.SilkS")
		)
		(fp_line
			(start 14.216888 -0.882904)
			(end 14.277086 -0.882904)
			(stroke
				(width 0.1)
				(type default)
			)
			(layer "F.SilkS")
		)
		(fp_line
			(start 14.216888 -0.882904)
			(end 14.277086 -0.882904)
			(stroke
				(width 0.1)
				(type default)
			)
			(layer "F.SilkS")
		)
		(fp_line
			(start 14.216888 -0.882904)
			(end 15.245842 -1.869948)
			(stroke
				(width 0.1)
				(type default)
			)
			(layer "F.SilkS")
		)
		(fp_line
			(start 14.216888 -0.882904)
			(end 15.245842 -1.869948)
			(stroke
				(width 0.1)
				(type default)
			)
			(layer "F.SilkS")
		)
		(fp_line
			(start 14.21892 -2.443226)
			(end 14.206728 -2.373884)
			(stroke
				(width 0.1)
				(type default)
			)
			(layer "F.SilkS")
		)
		(fp_line
			(start 14.21892 -2.443226)
			(end 14.206728 -2.373884)
			(stroke
				(width 0.1)
				(type default)
			)
			(layer "F.SilkS")
		)
		(fp_line
			(start 14.230858 -2.512314)
			(end 14.21892 -2.443226)
			(stroke
				(width 0.1)
				(type default)
			)
			(layer "F.SilkS")
		)
		(fp_line
			(start 14.230858 -2.512314)
			(end 14.21892 -2.443226)
			(stroke
				(width 0.1)
				(type default)
			)
			(layer "F.SilkS")
		)
		(fp_line
			(start 14.243304 -2.58191)
			(end 14.230858 -2.512314)
			(stroke
				(width 0.1)
				(type default)
			)
			(layer "F.SilkS")
		)
		(fp_line
			(start 14.243304 -2.58191)
			(end 14.230858 -2.512314)
			(stroke
				(width 0.1)
				(type default)
			)
			(layer "F.SilkS")
		)
		(fp_line
			(start 14.255496 -2.651506)
			(end 14.243304 -2.58191)
			(stroke
				(width 0.1)
				(type default)
			)
			(layer "F.SilkS")
		)
		(fp_line
			(start 14.255496 -2.651506)
			(end 14.243304 -2.58191)
			(stroke
				(width 0.1)
				(type default)
			)
			(layer "F.SilkS")
		)
		(fp_line
			(start 14.267434 -2.720594)
			(end 14.255496 -2.651506)
			(stroke
				(width 0.1)
				(type default)
			)
			(layer "F.SilkS")
		)
		(fp_line
			(start 14.267434 -2.720594)
			(end 14.255496 -2.651506)
			(stroke
				(width 0.1)
				(type default)
			)
			(layer "F.SilkS")
		)
		(fp_line
			(start 14.277086 -0.882904)
			(end 14.33703 -0.882904)
			(stroke
				(width 0.1)
				(type default)
			)
			(layer "F.SilkS")
		)
		(fp_line
			(start 14.277086 -0.882904)
			(end 14.33703 -0.882904)
			(stroke
				(width 0.1)
				(type default)
			)
			(layer "F.SilkS")
		)
		(fp_line
			(start 14.277086 -0.882904)
			(end 15.233396 -1.800606)
			(stroke
				(width 0.1)
				(type default)
			)
			(layer "F.SilkS")
		)
		(fp_line
			(start 14.277086 -0.882904)
			(end 15.233396 -1.800606)
			(stroke
				(width 0.1)
				(type default)
			)
			(layer "F.SilkS")
		)
		(fp_line
			(start 14.27988 -2.79019)
			(end 14.267434 -2.720594)
			(stroke
				(width 0.1)
				(type default)
			)
			(layer "F.SilkS")
		)
		(fp_line
			(start 14.27988 -2.79019)
			(end 14.267434 -2.720594)
			(stroke
				(width 0.1)
				(type default)
			)
			(layer "F.SilkS")
		)
		(fp_line
			(start 14.291818 -2.859532)
			(end 14.27988 -2.79019)
			(stroke
				(width 0.1)
				(type default)
			)
			(layer "F.SilkS")
		)
		(fp_line
			(start 14.291818 -2.859532)
			(end 14.27988 -2.79019)
			(stroke
				(width 0.1)
				(type default)
			)
			(layer "F.SilkS")
		)
		(fp_line
			(start 14.30401 -2.928874)
			(end 14.291818 -2.859532)
			(stroke
				(width 0.1)
				(type default)
			)
			(layer "F.SilkS")
		)
		(fp_line
			(start 14.30401 -2.928874)
			(end 14.291818 -2.859532)
			(stroke
				(width 0.1)
				(type default)
			)
			(layer "F.SilkS")
		)
		(fp_line
			(start 14.316456 -2.998216)
			(end 14.30401 -2.928874)
			(stroke
				(width 0.1)
				(type default)
			)
			(layer "F.SilkS")
		)
		(fp_line
			(start 14.316456 -2.998216)
			(end 14.30401 -2.928874)
			(stroke
				(width 0.1)
				(type default)
			)
			(layer "F.SilkS")
		)
		(fp_line
			(start 14.328394 -3.067558)
			(end 14.316456 -2.998216)
			(stroke
				(width 0.1)
				(type default)
			)
			(layer "F.SilkS")
		)
		(fp_line
			(start 14.328394 -3.067558)
			(end 14.316456 -2.998216)
			(stroke
				(width 0.1)
				(type default)
			)
			(layer "F.SilkS")
		)
		(fp_line
			(start 14.33703 -0.882904)
			(end 14.396974 -0.882904)
			(stroke
				(width 0.1)
				(type default)
			)
			(layer "F.SilkS")
		)
		(fp_line
			(start 14.33703 -0.882904)
			(end 14.396974 -0.882904)
			(stroke
				(width 0.1)
				(type default)
			)
			(layer "F.SilkS")
		)
		(fp_line
			(start 14.33703 -0.882904)
			(end 15.221458 -1.731518)
			(stroke
				(width 0.1)
				(type default)
			)
			(layer "F.SilkS")
		)
		(fp_line
			(start 14.33703 -0.882904)
			(end 15.221458 -1.731518)
			(stroke
				(width 0.1)
				(type default)
			)
			(layer "F.SilkS")
		)
		(fp_line
			(start 14.340586 -3.137154)
			(end 14.328394 -3.067558)
			(stroke
				(width 0.1)
				(type default)
			)
			(layer "F.SilkS")
		)
		(fp_line
			(start 14.340586 -3.137154)
			(end 14.328394 -3.067558)
			(stroke
				(width 0.1)
				(type default)
			)
			(layer "F.SilkS")
		)
		(fp_line
			(start 14.352778 -3.206496)
			(end 14.340586 -3.137154)
			(stroke
				(width 0.1)
				(type default)
			)
			(layer "F.SilkS")
		)
		(fp_line
			(start 14.352778 -3.206496)
			(end 14.340586 -3.137154)
			(stroke
				(width 0.1)
				(type default)
			)
			(layer "F.SilkS")
		)
		(fp_line
			(start 14.36497 -3.275838)
			(end 14.352778 -3.206496)
			(stroke
				(width 0.1)
				(type default)
			)
			(layer "F.SilkS")
		)
		(fp_line
			(start 14.36497 -3.275838)
			(end 14.352778 -3.206496)
			(stroke
				(width 0.1)
				(type default)
			)
			(layer "F.SilkS")
		)
		(fp_line
			(start 14.376908 -3.34518)
			(end 14.36497 -3.275838)
			(stroke
				(width 0.1)
				(type default)
			)
			(layer "F.SilkS")
		)
		(fp_line
			(start 14.376908 -3.34518)
			(end 14.36497 -3.275838)
			(stroke
				(width 0.1)
				(type default)
			)
			(layer "F.SilkS")
		)
		(fp_line
			(start 14.389354 -3.414776)
			(end 14.376908 -3.34518)
			(stroke
				(width 0.1)
				(type default)
			)
			(layer "F.SilkS")
		)
		(fp_line
			(start 14.389354 -3.414776)
			(end 14.376908 -3.34518)
			(stroke
				(width 0.1)
				(type default)
			)
			(layer "F.SilkS")
		)
		(fp_line
			(start 14.396974 -0.882904)
			(end 14.45768 -0.882904)
			(stroke
				(width 0.1)
				(type default)
			)
			(layer "F.SilkS")
		)
		(fp_line
			(start 14.396974 -0.882904)
			(end 14.45768 -0.882904)
			(stroke
				(width 0.1)
				(type default)
			)
			(layer "F.SilkS")
		)
		(fp_line
			(start 14.396974 -0.882904)
			(end 15.209266 -1.661922)
			(stroke
				(width 0.1)
				(type default)
			)
			(layer "F.SilkS")
		)
		(fp_line
			(start 14.396974 -0.882904)
			(end 15.209266 -1.661922)
			(stroke
				(width 0.1)
				(type default)
			)
			(layer "F.SilkS")
		)
		(fp_line
			(start 14.401546 -3.484118)
			(end 14.389354 -3.414776)
			(stroke
				(width 0.1)
				(type default)
			)
			(layer "F.SilkS")
		)
		(fp_line
			(start 14.401546 -3.484118)
			(end 14.389354 -3.414776)
			(stroke
				(width 0.1)
				(type default)
			)
			(layer "F.SilkS")
		)
		(fp_line
			(start 14.413484 -3.55346)
			(end 14.401546 -3.484118)
			(stroke
				(width 0.1)
				(type default)
			)
			(layer "F.SilkS")
		)
		(fp_line
			(start 14.413484 -3.55346)
			(end 14.401546 -3.484118)
			(stroke
				(width 0.1)
				(type default)
			)
			(layer "F.SilkS")
		)
		(fp_line
			(start 14.42593 -3.622802)
			(end 14.413484 -3.55346)
			(stroke
				(width 0.1)
				(type default)
			)
			(layer "F.SilkS")
		)
		(fp_line
			(start 14.42593 -3.622802)
			(end 14.413484 -3.55346)
			(stroke
				(width 0.1)
				(type default)
			)
			(layer "F.SilkS")
		)
		(fp_line
			(start 14.438376 -3.692398)
			(end 14.42593 -3.622802)
			(stroke
				(width 0.1)
				(type default)
			)
			(layer "F.SilkS")
		)
		(fp_line
			(start 14.438376 -3.692398)
			(end 14.42593 -3.622802)
			(stroke
				(width 0.1)
				(type default)
			)
			(layer "F.SilkS")
		)
		(fp_line
			(start 14.45006 -3.76174)
			(end 14.438376 -3.692398)
			(stroke
				(width 0.1)
				(type default)
			)
			(layer "F.SilkS")
		)
		(fp_line
			(start 14.45006 -3.76174)
			(end 14.438376 -3.692398)
			(stroke
				(width 0.1)
				(type default)
			)
			(layer "F.SilkS")
		)
		(fp_line
			(start 14.45768 -0.882904)
			(end 14.517624 -0.882904)
			(stroke
				(width 0.1)
				(type default)
			)
			(layer "F.SilkS")
		)
		(fp_line
			(start 14.45768 -0.882904)
			(end 14.517624 -0.882904)
			(stroke
				(width 0.1)
				(type default)
			)
			(layer "F.SilkS")
		)
		(fp_line
			(start 14.45768 -0.882904)
			(end 15.19682 -1.592326)
			(stroke
				(width 0.1)
				(type default)
			)
			(layer "F.SilkS")
		)
		(fp_line
			(start 14.45768 -0.882904)
			(end 15.19682 -1.592326)
			(stroke
				(width 0.1)
				(type default)
			)
			(layer "F.SilkS")
		)
		(fp_line
			(start 14.462506 -3.831082)
			(end 14.45006 -3.76174)
			(stroke
				(width 0.1)
				(type default)
			)
			(layer "F.SilkS")
		)
		(fp_line
			(start 14.462506 -3.831082)
			(end 14.45006 -3.76174)
			(stroke
				(width 0.1)
				(type default)
			)
			(layer "F.SilkS")
		)
		(fp_line
			(start 14.474952 -3.900424)
			(end 14.462506 -3.831082)
			(stroke
				(width 0.1)
				(type default)
			)
			(layer "F.SilkS")
		)
		(fp_line
			(start 14.474952 -3.900424)
			(end 14.462506 -3.831082)
			(stroke
				(width 0.1)
				(type default)
			)
			(layer "F.SilkS")
		)
		(fp_line
			(start 14.486636 -3.969766)
			(end 14.474952 -3.900424)
			(stroke
				(width 0.1)
				(type default)
			)
			(layer "F.SilkS")
		)
		(fp_line
			(start 14.486636 -3.969766)
			(end 14.474952 -3.900424)
			(stroke
				(width 0.1)
				(type default)
			)
			(layer "F.SilkS")
		)
		(fp_line
			(start 14.498828 -4.039362)
			(end 14.486636 -3.969766)
			(stroke
				(width 0.1)
				(type default)
			)
			(layer "F.SilkS")
		)
		(fp_line
			(start 14.498828 -4.039362)
			(end 14.486636 -3.969766)
			(stroke
				(width 0.1)
				(type default)
			)
			(layer "F.SilkS")
		)
		(fp_line
			(start 14.511274 -4.108704)
			(end 14.498828 -4.039362)
			(stroke
				(width 0.1)
				(type default)
			)
			(layer "F.SilkS")
		)
		(fp_line
			(start 14.511274 -4.108704)
			(end 14.498828 -4.039362)
			(stroke
				(width 0.1)
				(type default)
			)
			(layer "F.SilkS")
		)
		(fp_line
			(start 14.517624 -0.882904)
			(end 14.577568 -0.882904)
			(stroke
				(width 0.1)
				(type default)
			)
			(layer "F.SilkS")
		)
		(fp_line
			(start 14.517624 -0.882904)
			(end 14.577568 -0.882904)
			(stroke
				(width 0.1)
				(type default)
			)
			(layer "F.SilkS")
		)
		(fp_line
			(start 14.517624 -0.882904)
			(end 15.184882 -1.522984)
			(stroke
				(width 0.1)
				(type default)
			)
			(layer "F.SilkS")
		)
		(fp_line
			(start 14.517624 -0.882904)
			(end 15.184882 -1.522984)
			(stroke
				(width 0.1)
				(type default)
			)
			(layer "F.SilkS")
		)
		(fp_line
			(start 14.523466 -4.178046)
			(end 14.511274 -4.108704)
			(stroke
				(width 0.1)
				(type default)
			)
			(layer "F.SilkS")
		)
		(fp_line
			(start 14.523466 -4.178046)
			(end 14.511274 -4.108704)
			(stroke
				(width 0.1)
				(type default)
			)
			(layer "F.SilkS")
		)
		(fp_line
			(start 14.523466 -4.178046)
			(end 14.535404 -4.247388)
			(stroke
				(width 0.1)
				(type default)
			)
			(layer "F.SilkS")
		)
		(fp_line
			(start 14.523466 -4.178046)
			(end 14.535404 -4.247388)
			(stroke
				(width 0.1)
				(type default)
			)
			(layer "F.SilkS")
		)
		(fp_line
			(start 14.535404 -4.247388)
			(end 14.54785 -4.316984)
			(stroke
				(width 0.1)
				(type default)
			)
			(layer "F.SilkS")
		)
		(fp_line
			(start 14.535404 -4.247388)
			(end 14.54785 -4.316984)
			(stroke
				(width 0.1)
				(type default)
			)
			(layer "F.SilkS")
		)
		(fp_line
			(start 14.54785 -4.316984)
			(end 14.560042 -4.386326)
			(stroke
				(width 0.1)
				(type default)
			)
			(layer "F.SilkS")
		)
		(fp_line
			(start 14.54785 -4.316984)
			(end 14.560042 -4.386326)
			(stroke
				(width 0.1)
				(type default)
			)
			(layer "F.SilkS")
		)
		(fp_line
			(start 14.560042 -4.386326)
			(end 14.57198 -4.455668)
			(stroke
				(width 0.1)
				(type default)
			)
			(layer "F.SilkS")
		)
		(fp_line
			(start 14.560042 -4.386326)
			(end 14.57198 -4.455668)
			(stroke
				(width 0.1)
				(type default)
			)
			(layer "F.SilkS")
		)
		(fp_line
			(start 14.57198 -4.455668)
			(end 14.584426 -4.52501)
			(stroke
				(width 0.1)
				(type default)
			)
			(layer "F.SilkS")
		)
		(fp_line
			(start 14.57198 -4.455668)
			(end 14.584426 -4.52501)
			(stroke
				(width 0.1)
				(type default)
			)
			(layer "F.SilkS")
		)
		(fp_line
			(start 14.577568 -0.882904)
			(end 14.637766 -0.882904)
			(stroke
				(width 0.1)
				(type default)
			)
			(layer "F.SilkS")
		)
		(fp_line
			(start 14.577568 -0.882904)
			(end 14.637766 -0.882904)
			(stroke
				(width 0.1)
				(type default)
			)
			(layer "F.SilkS")
		)
		(fp_line
			(start 14.577568 -0.882904)
			(end 15.17269 -1.453642)
			(stroke
				(width 0.1)
				(type default)
			)
			(layer "F.SilkS")
		)
		(fp_line
			(start 14.577568 -0.882904)
			(end 15.17269 -1.453642)
			(stroke
				(width 0.1)
				(type default)
			)
			(layer "F.SilkS")
		)
		(fp_line
			(start 14.584426 -4.52501)
			(end 14.596364 -4.594352)
			(stroke
				(width 0.1)
				(type default)
			)
			(layer "F.SilkS")
		)
		(fp_line
			(start 14.584426 -4.52501)
			(end 14.596364 -4.594352)
			(stroke
				(width 0.1)
				(type default)
			)
			(layer "F.SilkS")
		)
		(fp_line
			(start 14.596364 -4.594352)
			(end 14.608556 -4.663948)
			(stroke
				(width 0.1)
				(type default)
			)
			(layer "F.SilkS")
		)
		(fp_line
			(start 14.596364 -4.594352)
			(end 14.608556 -4.663948)
			(stroke
				(width 0.1)
				(type default)
			)
			(layer "F.SilkS")
		)
		(fp_line
			(start 14.608556 -4.663948)
			(end 14.621002 -4.733036)
			(stroke
				(width 0.1)
				(type default)
			)
			(layer "F.SilkS")
		)
		(fp_line
			(start 14.608556 -4.663948)
			(end 14.621002 -4.733036)
			(stroke
				(width 0.1)
				(type default)
			)
			(layer "F.SilkS")
		)
		(fp_line
			(start 14.621002 -4.733036)
			(end 14.63294 -4.802632)
			(stroke
				(width 0.1)
				(type default)
			)
			(layer "F.SilkS")
		)
		(fp_line
			(start 14.621002 -4.733036)
			(end 14.63294 -4.802632)
			(stroke
				(width 0.1)
				(type default)
			)
			(layer "F.SilkS")
		)
		(fp_line
			(start 14.63294 -4.802632)
			(end 14.645132 -4.872228)
			(stroke
				(width 0.1)
				(type default)
			)
			(layer "F.SilkS")
		)
		(fp_line
			(start 14.63294 -4.802632)
			(end 14.645132 -4.872228)
			(stroke
				(width 0.1)
				(type default)
			)
			(layer "F.SilkS")
		)
		(fp_line
			(start 14.637766 -0.882904)
			(end 14.697964 -0.882904)
			(stroke
				(width 0.1)
				(type default)
			)
			(layer "F.SilkS")
		)
		(fp_line
			(start 14.637766 -0.882904)
			(end 14.697964 -0.882904)
			(stroke
				(width 0.1)
				(type default)
			)
			(layer "F.SilkS")
		)
		(fp_line
			(start 14.637766 -0.882904)
			(end 15.160498 -1.384046)
			(stroke
				(width 0.1)
				(type default)
			)
			(layer "F.SilkS")
		)
		(fp_line
			(start 14.637766 -0.882904)
			(end 15.160498 -1.384046)
			(stroke
				(width 0.1)
				(type default)
			)
			(layer "F.SilkS")
		)
		(fp_line
			(start 14.645132 -4.872228)
			(end 14.657324 -4.941316)
			(stroke
				(width 0.1)
				(type default)
			)
			(layer "F.SilkS")
		)
		(fp_line
			(start 14.645132 -4.872228)
			(end 14.657324 -4.941316)
			(stroke
				(width 0.1)
				(type default)
			)
			(layer "F.SilkS")
		)
		(fp_line
			(start 14.657324 -4.941316)
			(end 14.669516 -5.010912)
			(stroke
				(width 0.1)
				(type default)
			)
			(layer "F.SilkS")
		)
		(fp_line
			(start 14.657324 -4.941316)
			(end 14.669516 -5.010912)
			(stroke
				(width 0.1)
				(type default)
			)
			(layer "F.SilkS")
		)
		(fp_line
			(start 14.669516 -5.010912)
			(end 14.681454 -5.080254)
			(stroke
				(width 0.1)
				(type default)
			)
			(layer "F.SilkS")
		)
		(fp_line
			(start 14.669516 -5.010912)
			(end 14.681454 -5.080254)
			(stroke
				(width 0.1)
				(type default)
			)
			(layer "F.SilkS")
		)
		(fp_line
			(start 14.681454 -5.080254)
			(end 14.6939 -5.149596)
			(stroke
				(width 0.1)
				(type default)
			)
			(layer "F.SilkS")
		)
		(fp_line
			(start 14.681454 -5.080254)
			(end 14.6939 -5.149596)
			(stroke
				(width 0.1)
				(type default)
			)
			(layer "F.SilkS")
		)
		(fp_line
			(start 14.69771 -5.171694)
			(end 14.6939 -5.149596)
			(stroke
				(width 0.1)
				(type default)
			)
			(layer "F.SilkS")
		)
		(fp_line
			(start 14.69771 -5.171694)
			(end 14.6939 -5.149596)
			(stroke
				(width 0.1)
				(type default)
			)
			(layer "F.SilkS")
		)
		(fp_line
			(start 14.697964 -0.882904)
			(end 14.757908 -0.882904)
			(stroke
				(width 0.1)
				(type default)
			)
			(layer "F.SilkS")
		)
		(fp_line
			(start 14.697964 -0.882904)
			(end 14.757908 -0.882904)
			(stroke
				(width 0.1)
				(type default)
			)
			(layer "F.SilkS")
		)
		(fp_line
			(start 14.697964 -0.882904)
			(end 15.148052 -1.314704)
			(stroke
				(width 0.1)
				(type default)
			)
			(layer "F.SilkS")
		)
		(fp_line
			(start 14.697964 -0.882904)
			(end 15.148052 -1.314704)
			(stroke
				(width 0.1)
				(type default)
			)
			(layer "F.SilkS")
		)
		(fp_line
			(start 14.71676 -5.171694)
			(end 14.6939 -5.149596)
			(stroke
				(width 0.1)
				(type default)
			)
			(layer "F.SilkS")
		)
		(fp_line
			(start 14.71676 -5.171694)
			(end 14.6939 -5.149596)
			(stroke
				(width 0.1)
				(type default)
			)
			(layer "F.SilkS")
		)
		(fp_line
			(start 14.71676 -5.171694)
			(end 14.69771 -5.171694)
			(stroke
				(width 0.1)
				(type default)
			)
			(layer "F.SilkS")
		)
		(fp_line
			(start 14.71676 -5.171694)
			(end 14.69771 -5.171694)
			(stroke
				(width 0.1)
				(type default)
			)
			(layer "F.SilkS")
		)
		(fp_line
			(start 14.757908 -0.882904)
			(end 14.81836 -0.882904)
			(stroke
				(width 0.1)
				(type default)
			)
			(layer "F.SilkS")
		)
		(fp_line
			(start 14.757908 -0.882904)
			(end 14.81836 -0.882904)
			(stroke
				(width 0.1)
				(type default)
			)
			(layer "F.SilkS")
		)
		(fp_line
			(start 14.757908 -0.882904)
			(end 15.13586 -1.245362)
			(stroke
				(width 0.1)
				(type default)
			)
			(layer "F.SilkS")
		)
		(fp_line
			(start 14.757908 -0.882904)
			(end 15.13586 -1.245362)
			(stroke
				(width 0.1)
				(type default)
			)
			(layer "F.SilkS")
		)
		(fp_line
			(start 14.776958 -5.171694)
			(end 14.681454 -5.080254)
			(stroke
				(width 0.1)
				(type default)
			)
			(layer "F.SilkS")
		)
		(fp_line
			(start 14.776958 -5.171694)
			(end 14.681454 -5.080254)
			(stroke
				(width 0.1)
				(type default)
			)
			(layer "F.SilkS")
		)
		(fp_line
			(start 14.776958 -5.171694)
			(end 14.71676 -5.171694)
			(stroke
				(width 0.1)
				(type default)
			)
			(layer "F.SilkS")
		)
		(fp_line
			(start 14.776958 -5.171694)
			(end 14.71676 -5.171694)
			(stroke
				(width 0.1)
				(type default)
			)
			(layer "F.SilkS")
		)
		(fp_line
			(start 14.81836 -0.882904)
			(end 14.878558 -0.882904)
			(stroke
				(width 0.1)
				(type default)
			)
			(layer "F.SilkS")
		)
		(fp_line
			(start 14.81836 -0.882904)
			(end 14.878558 -0.882904)
			(stroke
				(width 0.1)
				(type default)
			)
			(layer "F.SilkS")
		)
		(fp_line
			(start 14.81836 -0.882904)
			(end 15.123922 -1.17602)
			(stroke
				(width 0.1)
				(type default)
			)
			(layer "F.SilkS")
		)
		(fp_line
			(start 14.81836 -0.882904)
			(end 15.123922 -1.17602)
			(stroke
				(width 0.1)
				(type default)
			)
			(layer "F.SilkS")
		)
		(fp_line
			(start 14.837156 -5.171694)
			(end 14.669516 -5.010912)
			(stroke
				(width 0.1)
				(type default)
			)
			(layer "F.SilkS")
		)
		(fp_line
			(start 14.837156 -5.171694)
			(end 14.669516 -5.010912)
			(stroke
				(width 0.1)
				(type default)
			)
			(layer "F.SilkS")
		)
		(fp_line
			(start 14.837156 -5.171694)
			(end 14.776958 -5.171694)
			(stroke
				(width 0.1)
				(type default)
			)
			(layer "F.SilkS")
		)
		(fp_line
			(start 14.837156 -5.171694)
			(end 14.776958 -5.171694)
			(stroke
				(width 0.1)
				(type default)
			)
			(layer "F.SilkS")
		)
		(fp_line
			(start 14.878558 -0.882904)
			(end 14.938502 -0.882904)
			(stroke
				(width 0.1)
				(type default)
			)
			(layer "F.SilkS")
		)
		(fp_line
			(start 14.878558 -0.882904)
			(end 14.938502 -0.882904)
			(stroke
				(width 0.1)
				(type default)
			)
			(layer "F.SilkS")
		)
		(fp_line
			(start 14.878558 -0.882904)
			(end 15.111476 -1.106424)
			(stroke
				(width 0.1)
				(type default)
			)
			(layer "F.SilkS")
		)
		(fp_line
			(start 14.878558 -0.882904)
			(end 15.111476 -1.106424)
			(stroke
				(width 0.1)
				(type default)
			)
			(layer "F.SilkS")
		)
		(fp_line
			(start 14.8971 -5.171694)
			(end 14.657324 -4.941316)
			(stroke
				(width 0.1)
				(type default)
			)
			(layer "F.SilkS")
		)
		(fp_line
			(start 14.8971 -5.171694)
			(end 14.657324 -4.941316)
			(stroke
				(width 0.1)
				(type default)
			)
			(layer "F.SilkS")
		)
		(fp_line
			(start 14.8971 -5.171694)
			(end 14.837156 -5.171694)
			(stroke
				(width 0.1)
				(type default)
			)
			(layer "F.SilkS")
		)
		(fp_line
			(start 14.8971 -5.171694)
			(end 14.837156 -5.171694)
			(stroke
				(width 0.1)
				(type default)
			)
			(layer "F.SilkS")
		)
		(fp_line
			(start 14.938502 -0.882904)
			(end 14.998954 -0.882904)
			(stroke
				(width 0.1)
				(type default)
			)
			(layer "F.SilkS")
		)
		(fp_line
			(start 14.938502 -0.882904)
			(end 14.998954 -0.882904)
			(stroke
				(width 0.1)
				(type default)
			)
			(layer "F.SilkS")
		)
		(fp_line
			(start 14.938502 -0.882904)
			(end 15.09903 -1.036828)
			(stroke
				(width 0.1)
				(type default)
			)
			(layer "F.SilkS")
		)
		(fp_line
			(start 14.938502 -0.882904)
			(end 15.09903 -1.036828)
			(stroke
				(width 0.1)
				(type default)
			)
			(layer "F.SilkS")
		)
		(fp_line
			(start 14.957552 -5.171694)
			(end 14.645132 -4.872228)
			(stroke
				(width 0.1)
				(type default)
			)
			(layer "F.SilkS")
		)
		(fp_line
			(start 14.957552 -5.171694)
			(end 14.645132 -4.872228)
			(stroke
				(width 0.1)
				(type default)
			)
			(layer "F.SilkS")
		)
		(fp_line
			(start 14.957552 -5.171694)
			(end 14.8971 -5.171694)
			(stroke
				(width 0.1)
				(type default)
			)
			(layer "F.SilkS")
		)
		(fp_line
			(start 14.957552 -5.171694)
			(end 14.8971 -5.171694)
			(stroke
				(width 0.1)
				(type default)
			)
			(layer "F.SilkS")
		)
		(fp_line
			(start 14.998954 -0.882904)
			(end 15.059152 -0.882904)
			(stroke
				(width 0.1)
				(type default)
			)
			(layer "F.SilkS")
		)
		(fp_line
			(start 14.998954 -0.882904)
			(end 15.059152 -0.882904)
			(stroke
				(width 0.1)
				(type default)
			)
			(layer "F.SilkS")
		)
		(fp_line
			(start 14.998954 -0.882904)
			(end 15.087092 -0.96774)
			(stroke
				(width 0.1)
				(type default)
			)
			(layer "F.SilkS")
		)
		(fp_line
			(start 14.998954 -0.882904)
			(end 15.087092 -0.96774)
			(stroke
				(width 0.1)
				(type default)
			)
			(layer "F.SilkS")
		)
		(fp_line
			(start 15.01775 -5.171694)
			(end 14.63294 -4.802632)
			(stroke
				(width 0.1)
				(type default)
			)
			(layer "F.SilkS")
		)
		(fp_line
			(start 15.01775 -5.171694)
			(end 14.63294 -4.802632)
			(stroke
				(width 0.1)
				(type default)
			)
			(layer "F.SilkS")
		)
		(fp_line
			(start 15.01775 -5.171694)
			(end 14.957552 -5.171694)
			(stroke
				(width 0.1)
				(type default)
			)
			(layer "F.SilkS")
		)
		(fp_line
			(start 15.01775 -5.171694)
			(end 14.957552 -5.171694)
			(stroke
				(width 0.1)
				(type default)
			)
			(layer "F.SilkS")
		)
		(fp_line
			(start 15.059152 -0.882904)
			(end 15.072106 -0.882904)
			(stroke
				(width 0.1)
				(type default)
			)
			(layer "F.SilkS")
		)
		(fp_line
			(start 15.059152 -0.882904)
			(end 15.072106 -0.882904)
			(stroke
				(width 0.1)
				(type default)
			)
			(layer "F.SilkS")
		)
		(fp_line
			(start 15.059152 -0.882904)
			(end 15.0749 -0.898398)
			(stroke
				(width 0.1)
				(type default)
			)
			(layer "F.SilkS")
		)
		(fp_line
			(start 15.059152 -0.882904)
			(end 15.0749 -0.898398)
			(stroke
				(width 0.1)
				(type default)
			)
			(layer "F.SilkS")
		)
		(fp_line
			(start 15.072106 -0.882904)
			(end 15.0749 -0.898398)
			(stroke
				(width 0.1)
				(type default)
			)
			(layer "F.SilkS")
		)
		(fp_line
			(start 15.072106 -0.882904)
			(end 15.0749 -0.898398)
			(stroke
				(width 0.1)
				(type default)
			)
			(layer "F.SilkS")
		)
		(fp_line
			(start 15.077694 -5.171694)
			(end 14.621002 -4.733036)
			(stroke
				(width 0.1)
				(type default)
			)
			(layer "F.SilkS")
		)
		(fp_line
			(start 15.077694 -5.171694)
			(end 14.621002 -4.733036)
			(stroke
				(width 0.1)
				(type default)
			)
			(layer "F.SilkS")
		)
		(fp_line
			(start 15.077694 -5.171694)
			(end 15.01775 -5.171694)
			(stroke
				(width 0.1)
				(type default)
			)
			(layer "F.SilkS")
		)
		(fp_line
			(start 15.077694 -5.171694)
			(end 15.01775 -5.171694)
			(stroke
				(width 0.1)
				(type default)
			)
			(layer "F.SilkS")
		)
		(fp_line
			(start 15.087092 -0.96774)
			(end 15.0749 -0.898398)
			(stroke
				(width 0.1)
				(type default)
			)
			(layer "F.SilkS")
		)
		(fp_line
			(start 15.087092 -0.96774)
			(end 15.0749 -0.898398)
			(stroke
				(width 0.1)
				(type default)
			)
			(layer "F.SilkS")
		)
		(fp_line
			(start 15.09903 -1.036828)
			(end 15.087092 -0.96774)
			(stroke
				(width 0.1)
				(type default)
			)
			(layer "F.SilkS")
		)
		(fp_line
			(start 15.09903 -1.036828)
			(end 15.087092 -0.96774)
			(stroke
				(width 0.1)
				(type default)
			)
			(layer "F.SilkS")
		)
		(fp_line
			(start 15.111476 -1.106424)
			(end 15.09903 -1.036828)
			(stroke
				(width 0.1)
				(type default)
			)
			(layer "F.SilkS")
		)
		(fp_line
			(start 15.111476 -1.106424)
			(end 15.09903 -1.036828)
			(stroke
				(width 0.1)
				(type default)
			)
			(layer "F.SilkS")
		)
		(fp_line
			(start 15.123922 -1.17602)
			(end 15.111476 -1.106424)
			(stroke
				(width 0.1)
				(type default)
			)
			(layer "F.SilkS")
		)
		(fp_line
			(start 15.123922 -1.17602)
			(end 15.111476 -1.106424)
			(stroke
				(width 0.1)
				(type default)
			)
			(layer "F.SilkS")
		)
		(fp_line
			(start 15.13586 -1.245362)
			(end 15.123922 -1.17602)
			(stroke
				(width 0.1)
				(type default)
			)
			(layer "F.SilkS")
		)
		(fp_line
			(start 15.13586 -1.245362)
			(end 15.123922 -1.17602)
			(stroke
				(width 0.1)
				(type default)
			)
			(layer "F.SilkS")
		)
		(fp_line
			(start 15.137892 -5.171694)
			(end 14.608556 -4.663948)
			(stroke
				(width 0.1)
				(type default)
			)
			(layer "F.SilkS")
		)
		(fp_line
			(start 15.137892 -5.171694)
			(end 14.608556 -4.663948)
			(stroke
				(width 0.1)
				(type default)
			)
			(layer "F.SilkS")
		)
		(fp_line
			(start 15.137892 -5.171694)
			(end 15.077694 -5.171694)
			(stroke
				(width 0.1)
				(type default)
			)
			(layer "F.SilkS")
		)
		(fp_line
			(start 15.137892 -5.171694)
			(end 15.077694 -5.171694)
			(stroke
				(width 0.1)
				(type default)
			)
			(layer "F.SilkS")
		)
		(fp_line
			(start 15.148052 -1.314704)
			(end 15.13586 -1.245362)
			(stroke
				(width 0.1)
				(type default)
			)
			(layer "F.SilkS")
		)
		(fp_line
			(start 15.148052 -1.314704)
			(end 15.13586 -1.245362)
			(stroke
				(width 0.1)
				(type default)
			)
			(layer "F.SilkS")
		)
		(fp_line
			(start 15.160498 -1.384046)
			(end 15.148052 -1.314704)
			(stroke
				(width 0.1)
				(type default)
			)
			(layer "F.SilkS")
		)
		(fp_line
			(start 15.160498 -1.384046)
			(end 15.148052 -1.314704)
			(stroke
				(width 0.1)
				(type default)
			)
			(layer "F.SilkS")
		)
		(fp_line
			(start 15.17269 -1.453642)
			(end 15.160498 -1.384046)
			(stroke
				(width 0.1)
				(type default)
			)
			(layer "F.SilkS")
		)
		(fp_line
			(start 15.17269 -1.453642)
			(end 15.160498 -1.384046)
			(stroke
				(width 0.1)
				(type default)
			)
			(layer "F.SilkS")
		)
		(fp_line
			(start 15.184882 -1.522984)
			(end 15.17269 -1.453642)
			(stroke
				(width 0.1)
				(type default)
			)
			(layer "F.SilkS")
		)
		(fp_line
			(start 15.184882 -1.522984)
			(end 15.17269 -1.453642)
			(stroke
				(width 0.1)
				(type default)
			)
			(layer "F.SilkS")
		)
		(fp_line
			(start 15.184882 -1.522984)
			(end 15.19682 -1.592326)
			(stroke
				(width 0.1)
				(type default)
			)
			(layer "F.SilkS")
		)
		(fp_line
			(start 15.184882 -1.522984)
			(end 15.19682 -1.592326)
			(stroke
				(width 0.1)
				(type default)
			)
			(layer "F.SilkS")
		)
		(fp_line
			(start 15.19682 -1.592326)
			(end 15.209266 -1.661922)
			(stroke
				(width 0.1)
				(type default)
			)
			(layer "F.SilkS")
		)
		(fp_line
			(start 15.19682 -1.592326)
			(end 15.209266 -1.661922)
			(stroke
				(width 0.1)
				(type default)
			)
			(layer "F.SilkS")
		)
		(fp_line
			(start 15.198344 -5.171694)
			(end 14.596364 -4.594352)
			(stroke
				(width 0.1)
				(type default)
			)
			(layer "F.SilkS")
		)
		(fp_line
			(start 15.198344 -5.171694)
			(end 14.596364 -4.594352)
			(stroke
				(width 0.1)
				(type default)
			)
			(layer "F.SilkS")
		)
		(fp_line
			(start 15.198344 -5.171694)
			(end 15.137892 -5.171694)
			(stroke
				(width 0.1)
				(type default)
			)
			(layer "F.SilkS")
		)
		(fp_line
			(start 15.198344 -5.171694)
			(end 15.137892 -5.171694)
			(stroke
				(width 0.1)
				(type default)
			)
			(layer "F.SilkS")
		)
		(fp_line
			(start 15.209266 -1.661922)
			(end 15.221458 -1.731518)
			(stroke
				(width 0.1)
				(type default)
			)
			(layer "F.SilkS")
		)
		(fp_line
			(start 15.209266 -1.661922)
			(end 15.221458 -1.731518)
			(stroke
				(width 0.1)
				(type default)
			)
			(layer "F.SilkS")
		)
		(fp_line
			(start 15.221458 -1.731518)
			(end 15.233396 -1.800606)
			(stroke
				(width 0.1)
				(type default)
			)
			(layer "F.SilkS")
		)
		(fp_line
			(start 15.221458 -1.731518)
			(end 15.233396 -1.800606)
			(stroke
				(width 0.1)
				(type default)
			)
			(layer "F.SilkS")
		)
		(fp_line
			(start 15.233396 -1.800606)
			(end 15.245842 -1.869948)
			(stroke
				(width 0.1)
				(type default)
			)
			(layer "F.SilkS")
		)
		(fp_line
			(start 15.233396 -1.800606)
			(end 15.245842 -1.869948)
			(stroke
				(width 0.1)
				(type default)
			)
			(layer "F.SilkS")
		)
		(fp_line
			(start 15.245842 -1.869948)
			(end 15.258288 -1.939544)
			(stroke
				(width 0.1)
				(type default)
			)
			(layer "F.SilkS")
		)
		(fp_line
			(start 15.245842 -1.869948)
			(end 15.258288 -1.939544)
			(stroke
				(width 0.1)
				(type default)
			)
			(layer "F.SilkS")
		)
		(fp_line
			(start 15.258288 -5.171694)
			(end 14.584426 -4.52501)
			(stroke
				(width 0.1)
				(type default)
			)
			(layer "F.SilkS")
		)
		(fp_line
			(start 15.258288 -5.171694)
			(end 14.584426 -4.52501)
			(stroke
				(width 0.1)
				(type default)
			)
			(layer "F.SilkS")
		)
		(fp_line
			(start 15.258288 -5.171694)
			(end 15.198344 -5.171694)
			(stroke
				(width 0.1)
				(type default)
			)
			(layer "F.SilkS")
		)
		(fp_line
			(start 15.258288 -5.171694)
			(end 15.198344 -5.171694)
			(stroke
				(width 0.1)
				(type default)
			)
			(layer "F.SilkS")
		)
		(fp_line
			(start 15.258288 -1.939544)
			(end 15.270226 -2.00914)
			(stroke
				(width 0.1)
				(type default)
			)
			(layer "F.SilkS")
		)
		(fp_line
			(start 15.258288 -1.939544)
			(end 15.270226 -2.00914)
			(stroke
				(width 0.1)
				(type default)
			)
			(layer "F.SilkS")
		)
		(fp_line
			(start 15.270226 -2.00914)
			(end 15.282418 -2.078482)
			(stroke
				(width 0.1)
				(type default)
			)
			(layer "F.SilkS")
		)
		(fp_line
			(start 15.270226 -2.00914)
			(end 15.282418 -2.078482)
			(stroke
				(width 0.1)
				(type default)
			)
			(layer "F.SilkS")
		)
		(fp_line
			(start 15.282418 -2.078482)
			(end 15.294864 -2.147824)
			(stroke
				(width 0.1)
				(type default)
			)
			(layer "F.SilkS")
		)
		(fp_line
			(start 15.282418 -2.078482)
			(end 15.294864 -2.147824)
			(stroke
				(width 0.1)
				(type default)
			)
			(layer "F.SilkS")
		)
		(fp_line
			(start 15.294864 -2.147824)
			(end 15.307056 -2.21742)
			(stroke
				(width 0.1)
				(type default)
			)
			(layer "F.SilkS")
		)
		(fp_line
			(start 15.294864 -2.147824)
			(end 15.307056 -2.21742)
			(stroke
				(width 0.1)
				(type default)
			)
			(layer "F.SilkS")
		)
		(fp_line
			(start 15.307056 -2.21742)
			(end 15.319248 -2.286762)
			(stroke
				(width 0.1)
				(type default)
			)
			(layer "F.SilkS")
		)
		(fp_line
			(start 15.307056 -2.21742)
			(end 15.319248 -2.286762)
			(stroke
				(width 0.1)
				(type default)
			)
			(layer "F.SilkS")
		)
		(fp_line
			(start 15.318486 -5.171694)
			(end 14.57198 -4.455668)
			(stroke
				(width 0.1)
				(type default)
			)
			(layer "F.SilkS")
		)
		(fp_line
			(start 15.318486 -5.171694)
			(end 14.57198 -4.455668)
			(stroke
				(width 0.1)
				(type default)
			)
			(layer "F.SilkS")
		)
		(fp_line
			(start 15.318486 -5.171694)
			(end 15.258288 -5.171694)
			(stroke
				(width 0.1)
				(type default)
			)
			(layer "F.SilkS")
		)
		(fp_line
			(start 15.318486 -5.171694)
			(end 15.258288 -5.171694)
			(stroke
				(width 0.1)
				(type default)
			)
			(layer "F.SilkS")
		)
		(fp_line
			(start 15.319248 -2.286762)
			(end 15.331186 -2.356104)
			(stroke
				(width 0.1)
				(type default)
			)
			(layer "F.SilkS")
		)
		(fp_line
			(start 15.319248 -2.286762)
			(end 15.331186 -2.356104)
			(stroke
				(width 0.1)
				(type default)
			)
			(layer "F.SilkS")
		)
		(fp_line
			(start 15.331186 -2.356104)
			(end 15.343632 -2.425446)
			(stroke
				(width 0.1)
				(type default)
			)
			(layer "F.SilkS")
		)
		(fp_line
			(start 15.331186 -2.356104)
			(end 15.343632 -2.425446)
			(stroke
				(width 0.1)
				(type default)
			)
			(layer "F.SilkS")
		)
		(fp_line
			(start 15.343632 -2.425446)
			(end 15.355824 -2.495042)
			(stroke
				(width 0.1)
				(type default)
			)
			(layer "F.SilkS")
		)
		(fp_line
			(start 15.343632 -2.425446)
			(end 15.355824 -2.495042)
			(stroke
				(width 0.1)
				(type default)
			)
			(layer "F.SilkS")
		)
		(fp_line
			(start 15.355824 -2.495042)
			(end 15.367762 -2.564384)
			(stroke
				(width 0.1)
				(type default)
			)
			(layer "F.SilkS")
		)
		(fp_line
			(start 15.355824 -2.495042)
			(end 15.367762 -2.564384)
			(stroke
				(width 0.1)
				(type default)
			)
			(layer "F.SilkS")
		)
		(fp_line
			(start 15.367762 -2.564384)
			(end 15.380208 -2.633726)
			(stroke
				(width 0.1)
				(type default)
			)
			(layer "F.SilkS")
		)
		(fp_line
			(start 15.367762 -2.564384)
			(end 15.380208 -2.633726)
			(stroke
				(width 0.1)
				(type default)
			)
			(layer "F.SilkS")
		)
		(fp_line
			(start 15.378938 -5.171694)
			(end 14.560042 -4.386326)
			(stroke
				(width 0.1)
				(type default)
			)
			(layer "F.SilkS")
		)
		(fp_line
			(start 15.378938 -5.171694)
			(end 14.560042 -4.386326)
			(stroke
				(width 0.1)
				(type default)
			)
			(layer "F.SilkS")
		)
		(fp_line
			(start 15.378938 -5.171694)
			(end 15.318486 -5.171694)
			(stroke
				(width 0.1)
				(type default)
			)
			(layer "F.SilkS")
		)
		(fp_line
			(start 15.378938 -5.171694)
			(end 15.318486 -5.171694)
			(stroke
				(width 0.1)
				(type default)
			)
			(layer "F.SilkS")
		)
		(fp_line
			(start 15.380208 -2.633726)
			(end 15.392654 -2.703322)
			(stroke
				(width 0.1)
				(type default)
			)
			(layer "F.SilkS")
		)
		(fp_line
			(start 15.380208 -2.633726)
			(end 15.392654 -2.703322)
			(stroke
				(width 0.1)
				(type default)
			)
			(layer "F.SilkS")
		)
		(fp_line
			(start 15.392654 -2.703322)
			(end 15.404592 -2.772664)
			(stroke
				(width 0.1)
				(type default)
			)
			(layer "F.SilkS")
		)
		(fp_line
			(start 15.392654 -2.703322)
			(end 15.404592 -2.772664)
			(stroke
				(width 0.1)
				(type default)
			)
			(layer "F.SilkS")
		)
		(fp_line
			(start 15.404592 -2.772664)
			(end 15.416784 -2.84226)
			(stroke
				(width 0.1)
				(type default)
			)
			(layer "F.SilkS")
		)
		(fp_line
			(start 15.404592 -2.772664)
			(end 15.416784 -2.84226)
			(stroke
				(width 0.1)
				(type default)
			)
			(layer "F.SilkS")
		)
		(fp_line
			(start 15.42923 -2.911602)
			(end 15.416784 -2.84226)
			(stroke
				(width 0.1)
				(type default)
			)
			(layer "F.SilkS")
		)
		(fp_line
			(start 15.42923 -2.911602)
			(end 15.416784 -2.84226)
			(stroke
				(width 0.1)
				(type default)
			)
			(layer "F.SilkS")
		)
		(fp_line
			(start 15.438882 -5.171694)
			(end 14.54785 -4.316984)
			(stroke
				(width 0.1)
				(type default)
			)
			(layer "F.SilkS")
		)
		(fp_line
			(start 15.438882 -5.171694)
			(end 14.54785 -4.316984)
			(stroke
				(width 0.1)
				(type default)
			)
			(layer "F.SilkS")
		)
		(fp_line
			(start 15.438882 -5.171694)
			(end 15.378938 -5.171694)
			(stroke
				(width 0.1)
				(type default)
			)
			(layer "F.SilkS")
		)
		(fp_line
			(start 15.438882 -5.171694)
			(end 15.378938 -5.171694)
			(stroke
				(width 0.1)
				(type default)
			)
			(layer "F.SilkS")
		)
		(fp_line
			(start 15.441168 -2.980944)
			(end 14.084808 -1.679702)
			(stroke
				(width 0.1)
				(type default)
			)
			(layer "F.SilkS")
		)
		(fp_line
			(start 15.441168 -2.980944)
			(end 14.084808 -1.679702)
			(stroke
				(width 0.1)
				(type default)
			)
			(layer "F.SilkS")
		)
		(fp_line
			(start 15.441168 -2.980944)
			(end 15.42923 -2.911602)
			(stroke
				(width 0.1)
				(type default)
			)
			(layer "F.SilkS")
		)
		(fp_line
			(start 15.441168 -2.980944)
			(end 15.42923 -2.911602)
			(stroke
				(width 0.1)
				(type default)
			)
			(layer "F.SilkS")
		)
		(fp_line
			(start 15.45336 -3.050286)
			(end 14.097254 -1.749044)
			(stroke
				(width 0.1)
				(type default)
			)
			(layer "F.SilkS")
		)
		(fp_line
			(start 15.45336 -3.050286)
			(end 14.097254 -1.749044)
			(stroke
				(width 0.1)
				(type default)
			)
			(layer "F.SilkS")
		)
		(fp_line
			(start 15.45336 -3.050286)
			(end 15.441168 -2.980944)
			(stroke
				(width 0.1)
				(type default)
			)
			(layer "F.SilkS")
		)
		(fp_line
			(start 15.45336 -3.050286)
			(end 15.441168 -2.980944)
			(stroke
				(width 0.1)
				(type default)
			)
			(layer "F.SilkS")
		)
		(fp_line
			(start 15.465552 -3.119882)
			(end 14.109192 -1.81864)
			(stroke
				(width 0.1)
				(type default)
			)
			(layer "F.SilkS")
		)
		(fp_line
			(start 15.465552 -3.119882)
			(end 14.109192 -1.81864)
			(stroke
				(width 0.1)
				(type default)
			)
			(layer "F.SilkS")
		)
		(fp_line
			(start 15.465552 -3.119882)
			(end 15.45336 -3.050286)
			(stroke
				(width 0.1)
				(type default)
			)
			(layer "F.SilkS")
		)
		(fp_line
			(start 15.465552 -3.119882)
			(end 15.45336 -3.050286)
			(stroke
				(width 0.1)
				(type default)
			)
			(layer "F.SilkS")
		)
		(fp_line
			(start 15.477998 -3.189224)
			(end 14.121384 -1.887982)
			(stroke
				(width 0.1)
				(type default)
			)
			(layer "F.SilkS")
		)
		(fp_line
			(start 15.477998 -3.189224)
			(end 14.121384 -1.887982)
			(stroke
				(width 0.1)
				(type default)
			)
			(layer "F.SilkS")
		)
		(fp_line
			(start 15.477998 -3.189224)
			(end 15.465552 -3.119882)
			(stroke
				(width 0.1)
				(type default)
			)
			(layer "F.SilkS")
		)
		(fp_line
			(start 15.477998 -3.189224)
			(end 15.465552 -3.119882)
			(stroke
				(width 0.1)
				(type default)
			)
			(layer "F.SilkS")
		)
		(fp_line
			(start 15.491714 -3.260344)
			(end 14.13383 -1.957324)
			(stroke
				(width 0.1)
				(type default)
			)
			(layer "F.SilkS")
		)
		(fp_line
			(start 15.491714 -3.260344)
			(end 14.13383 -1.957324)
			(stroke
				(width 0.1)
				(type default)
			)
			(layer "F.SilkS")
		)
		(fp_line
			(start 15.49908 -5.171694)
			(end 14.535404 -4.247388)
			(stroke
				(width 0.1)
				(type default)
			)
			(layer "F.SilkS")
		)
		(fp_line
			(start 15.49908 -5.171694)
			(end 14.535404 -4.247388)
			(stroke
				(width 0.1)
				(type default)
			)
			(layer "F.SilkS")
		)
		(fp_line
			(start 15.49908 -5.171694)
			(end 15.438882 -5.171694)
			(stroke
				(width 0.1)
				(type default)
			)
			(layer "F.SilkS")
		)
		(fp_line
			(start 15.49908 -5.171694)
			(end 15.438882 -5.171694)
			(stroke
				(width 0.1)
				(type default)
			)
			(layer "F.SilkS")
		)
		(fp_line
			(start 15.508478 -3.334004)
			(end 14.145768 -2.02692)
			(stroke
				(width 0.1)
				(type default)
			)
			(layer "F.SilkS")
		)
		(fp_line
			(start 15.508478 -3.334004)
			(end 14.145768 -2.02692)
			(stroke
				(width 0.1)
				(type default)
			)
			(layer "F.SilkS")
		)
		(fp_line
			(start 15.524988 -3.40741)
			(end 14.15796 -2.096262)
			(stroke
				(width 0.1)
				(type default)
			)
			(layer "F.SilkS")
		)
		(fp_line
			(start 15.524988 -3.40741)
			(end 14.15796 -2.096262)
			(stroke
				(width 0.1)
				(type default)
			)
			(layer "F.SilkS")
		)
		(fp_line
			(start 15.54099 -3.480562)
			(end 14.170406 -2.165604)
			(stroke
				(width 0.1)
				(type default)
			)
			(layer "F.SilkS")
		)
		(fp_line
			(start 15.54099 -3.480562)
			(end 14.170406 -2.165604)
			(stroke
				(width 0.1)
				(type default)
			)
			(layer "F.SilkS")
		)
		(fp_line
			(start 15.559278 -5.171694)
			(end 14.523466 -4.178046)
			(stroke
				(width 0.1)
				(type default)
			)
			(layer "F.SilkS")
		)
		(fp_line
			(start 15.559278 -5.171694)
			(end 14.523466 -4.178046)
			(stroke
				(width 0.1)
				(type default)
			)
			(layer "F.SilkS")
		)
		(fp_line
			(start 15.559278 -5.171694)
			(end 15.49908 -5.171694)
			(stroke
				(width 0.1)
				(type default)
			)
			(layer "F.SilkS")
		)
		(fp_line
			(start 15.559278 -5.171694)
			(end 15.49908 -5.171694)
			(stroke
				(width 0.1)
				(type default)
			)
			(layer "F.SilkS")
		)
		(fp_line
			(start 15.570962 -3.566922)
			(end 14.182344 -2.234946)
			(stroke
				(width 0.1)
				(type default)
			)
			(layer "F.SilkS")
		)
		(fp_line
			(start 15.570962 -3.566922)
			(end 14.182344 -2.234946)
			(stroke
				(width 0.1)
				(type default)
			)
			(layer "F.SilkS")
		)
		(fp_line
			(start 15.601442 -3.654044)
			(end 14.194282 -2.304288)
			(stroke
				(width 0.1)
				(type default)
			)
			(layer "F.SilkS")
		)
		(fp_line
			(start 15.601442 -3.654044)
			(end 14.194282 -2.304288)
			(stroke
				(width 0.1)
				(type default)
			)
			(layer "F.SilkS")
		)
		(fp_line
			(start 15.619222 -5.171694)
			(end 14.511274 -4.108704)
			(stroke
				(width 0.1)
				(type default)
			)
			(layer "F.SilkS")
		)
		(fp_line
			(start 15.619222 -5.171694)
			(end 14.511274 -4.108704)
			(stroke
				(width 0.1)
				(type default)
			)
			(layer "F.SilkS")
		)
		(fp_line
			(start 15.619222 -5.171694)
			(end 15.559278 -5.171694)
			(stroke
				(width 0.1)
				(type default)
			)
			(layer "F.SilkS")
		)
		(fp_line
			(start 15.619222 -5.171694)
			(end 15.559278 -5.171694)
			(stroke
				(width 0.1)
				(type default)
			)
			(layer "F.SilkS")
		)
		(fp_line
			(start 15.649702 -3.75793)
			(end 14.206728 -2.373884)
			(stroke
				(width 0.1)
				(type default)
			)
			(layer "F.SilkS")
		)
		(fp_line
			(start 15.649702 -3.75793)
			(end 14.206728 -2.373884)
			(stroke
				(width 0.1)
				(type default)
			)
			(layer "F.SilkS")
		)
		(fp_line
			(start 15.679166 -5.171694)
			(end 14.498828 -4.039362)
			(stroke
				(width 0.1)
				(type default)
			)
			(layer "F.SilkS")
		)
		(fp_line
			(start 15.679166 -5.171694)
			(end 14.498828 -4.039362)
			(stroke
				(width 0.1)
				(type default)
			)
			(layer "F.SilkS")
		)
		(fp_line
			(start 15.679166 -5.171694)
			(end 15.619222 -5.171694)
			(stroke
				(width 0.1)
				(type default)
			)
			(layer "F.SilkS")
		)
		(fp_line
			(start 15.679166 -5.171694)
			(end 15.619222 -5.171694)
			(stroke
				(width 0.1)
				(type default)
			)
			(layer "F.SilkS")
		)
		(fp_line
			(start 15.729458 -3.892296)
			(end 14.21892 -2.443226)
			(stroke
				(width 0.1)
				(type default)
			)
			(layer "F.SilkS")
		)
		(fp_line
			(start 15.729458 -3.892296)
			(end 14.21892 -2.443226)
			(stroke
				(width 0.1)
				(type default)
			)
			(layer "F.SilkS")
		)
		(fp_line
			(start 15.739618 -5.171694)
			(end 14.486636 -3.969766)
			(stroke
				(width 0.1)
				(type default)
			)
			(layer "F.SilkS")
		)
		(fp_line
			(start 15.739618 -5.171694)
			(end 14.486636 -3.969766)
			(stroke
				(width 0.1)
				(type default)
			)
			(layer "F.SilkS")
		)
		(fp_line
			(start 15.739618 -5.171694)
			(end 15.679166 -5.171694)
			(stroke
				(width 0.1)
				(type default)
			)
			(layer "F.SilkS")
		)
		(fp_line
			(start 15.739618 -5.171694)
			(end 15.679166 -5.171694)
			(stroke
				(width 0.1)
				(type default)
			)
			(layer "F.SilkS")
		)
		(fp_line
			(start 15.781274 -4.923028)
			(end 14.42593 -3.622802)
			(stroke
				(width 0.1)
				(type default)
			)
			(layer "F.SilkS")
		)
		(fp_line
			(start 15.781274 -4.923028)
			(end 14.42593 -3.622802)
			(stroke
				(width 0.1)
				(type default)
			)
			(layer "F.SilkS")
		)
		(fp_line
			(start 15.781274 -4.923028)
			(end 15.79372 -4.992624)
			(stroke
				(width 0.1)
				(type default)
			)
			(layer "F.SilkS")
		)
		(fp_line
			(start 15.781274 -4.923028)
			(end 15.79372 -4.992624)
			(stroke
				(width 0.1)
				(type default)
			)
			(layer "F.SilkS")
		)
		(fp_line
			(start 15.79372 -4.992624)
			(end 14.438376 -3.692398)
			(stroke
				(width 0.1)
				(type default)
			)
			(layer "F.SilkS")
		)
		(fp_line
			(start 15.79372 -4.992624)
			(end 14.438376 -3.692398)
			(stroke
				(width 0.1)
				(type default)
			)
			(layer "F.SilkS")
		)
		(fp_line
			(start 15.79372 -4.992624)
			(end 15.805658 -5.061966)
			(stroke
				(width 0.1)
				(type default)
			)
			(layer "F.SilkS")
		)
		(fp_line
			(start 15.79372 -4.992624)
			(end 15.805658 -5.061966)
			(stroke
				(width 0.1)
				(type default)
			)
			(layer "F.SilkS")
		)
		(fp_line
			(start 15.799816 -5.171694)
			(end 14.474952 -3.900424)
			(stroke
				(width 0.1)
				(type default)
			)
			(layer "F.SilkS")
		)
		(fp_line
			(start 15.799816 -5.171694)
			(end 14.474952 -3.900424)
			(stroke
				(width 0.1)
				(type default)
			)
			(layer "F.SilkS")
		)
		(fp_line
			(start 15.799816 -5.171694)
			(end 15.739618 -5.171694)
			(stroke
				(width 0.1)
				(type default)
			)
			(layer "F.SilkS")
		)
		(fp_line
			(start 15.799816 -5.171694)
			(end 15.739618 -5.171694)
			(stroke
				(width 0.1)
				(type default)
			)
			(layer "F.SilkS")
		)
		(fp_line
			(start 15.805658 -5.061966)
			(end 14.45006 -3.76174)
			(stroke
				(width 0.1)
				(type default)
			)
			(layer "F.SilkS")
		)
		(fp_line
			(start 15.805658 -5.061966)
			(end 14.45006 -3.76174)
			(stroke
				(width 0.1)
				(type default)
			)
			(layer "F.SilkS")
		)
		(fp_line
			(start 15.805658 -5.061966)
			(end 15.81785 -5.131308)
			(stroke
				(width 0.1)
				(type default)
			)
			(layer "F.SilkS")
		)
		(fp_line
			(start 15.805658 -5.061966)
			(end 15.81785 -5.131308)
			(stroke
				(width 0.1)
				(type default)
			)
			(layer "F.SilkS")
		)
		(fp_line
			(start 15.81785 -5.131308)
			(end 14.462506 -3.831082)
			(stroke
				(width 0.1)
				(type default)
			)
			(layer "F.SilkS")
		)
		(fp_line
			(start 15.81785 -5.131308)
			(end 14.462506 -3.831082)
			(stroke
				(width 0.1)
				(type default)
			)
			(layer "F.SilkS")
		)
		(fp_line
			(start 15.81785 -5.131308)
			(end 15.824962 -5.171694)
			(stroke
				(width 0.1)
				(type default)
			)
			(layer "F.SilkS")
		)
		(fp_line
			(start 15.81785 -5.131308)
			(end 15.824962 -5.171694)
			(stroke
				(width 0.1)
				(type default)
			)
			(layer "F.SilkS")
		)
		(fp_line
			(start 15.824962 -5.171694)
			(end 15.799816 -5.171694)
			(stroke
				(width 0.1)
				(type default)
			)
			(layer "F.SilkS")
		)
		(fp_line
			(start 15.824962 -5.171694)
			(end 15.799816 -5.171694)
			(stroke
				(width 0.1)
				(type default)
			)
			(layer "F.SilkS")
		)
		(fp_line
			(start 15.884652 -4.96443)
			(end 14.413484 -3.55346)
			(stroke
				(width 0.1)
				(type default)
			)
			(layer "F.SilkS")
		)
		(fp_line
			(start 15.884652 -4.96443)
			(end 14.413484 -3.55346)
			(stroke
				(width 0.1)
				(type default)
			)
			(layer "F.SilkS")
		)
		(fp_line
			(start 16.049498 -5.065268)
			(end 14.401546 -3.484118)
			(stroke
				(width 0.1)
				(type default)
			)
			(layer "F.SilkS")
		)
		(fp_line
			(start 16.049498 -5.065268)
			(end 14.401546 -3.484118)
			(stroke
				(width 0.1)
				(type default)
			)
			(layer "F.SilkS")
		)
		(fp_line
			(start 16.169132 -5.12191)
			(end 14.389354 -3.414776)
			(stroke
				(width 0.1)
				(type default)
			)
			(layer "F.SilkS")
		)
		(fp_line
			(start 16.169132 -5.12191)
			(end 14.389354 -3.414776)
			(stroke
				(width 0.1)
				(type default)
			)
			(layer "F.SilkS")
		)
		(fp_line
			(start 16.270986 -5.161788)
			(end 14.376908 -3.34518)
			(stroke
				(width 0.1)
				(type default)
			)
			(layer "F.SilkS")
		)
		(fp_line
			(start 16.270986 -5.161788)
			(end 14.376908 -3.34518)
			(stroke
				(width 0.1)
				(type default)
			)
			(layer "F.SilkS")
		)
		(fp_line
			(start 16.355568 -5.18541)
			(end 14.36497 -3.275838)
			(stroke
				(width 0.1)
				(type default)
			)
			(layer "F.SilkS")
		)
		(fp_line
			(start 16.355568 -5.18541)
			(end 14.36497 -3.275838)
			(stroke
				(width 0.1)
				(type default)
			)
			(layer "F.SilkS")
		)
		(fp_line
			(start 16.439896 -5.208778)
			(end 14.352778 -3.206496)
			(stroke
				(width 0.1)
				(type default)
			)
			(layer "F.SilkS")
		)
		(fp_line
			(start 16.439896 -5.208778)
			(end 14.352778 -3.206496)
			(stroke
				(width 0.1)
				(type default)
			)
			(layer "F.SilkS")
		)
		(fp_line
			(start 16.52397 -5.231638)
			(end 14.340586 -3.137154)
			(stroke
				(width 0.1)
				(type default)
			)
			(layer "F.SilkS")
		)
		(fp_line
			(start 16.52397 -5.231638)
			(end 14.340586 -3.137154)
			(stroke
				(width 0.1)
				(type default)
			)
			(layer "F.SilkS")
		)
		(fp_line
			(start 16.533622 -0.882904)
			(end 16.562832 -0.882904)
			(stroke
				(width 0.1)
				(type default)
			)
			(layer "F.SilkS")
		)
		(fp_line
			(start 16.533622 -0.882904)
			(end 16.562832 -0.882904)
			(stroke
				(width 0.1)
				(type default)
			)
			(layer "F.SilkS")
		)
		(fp_line
			(start 16.539718 -0.918464)
			(end 16.533622 -0.882904)
			(stroke
				(width 0.1)
				(type default)
			)
			(layer "F.SilkS")
		)
		(fp_line
			(start 16.539718 -0.918464)
			(end 16.533622 -0.882904)
			(stroke
				(width 0.1)
				(type default)
			)
			(layer "F.SilkS")
		)
		(fp_line
			(start 16.539718 -0.918464)
			(end 17.896586 -2.21996)
			(stroke
				(width 0.1)
				(type default)
			)
			(layer "F.SilkS")
		)
		(fp_line
			(start 16.539718 -0.918464)
			(end 17.896586 -2.21996)
			(stroke
				(width 0.1)
				(type default)
			)
			(layer "F.SilkS")
		)
		(fp_line
			(start 16.552164 -0.987806)
			(end 16.539718 -0.918464)
			(stroke
				(width 0.1)
				(type default)
			)
			(layer "F.SilkS")
		)
		(fp_line
			(start 16.552164 -0.987806)
			(end 16.539718 -0.918464)
			(stroke
				(width 0.1)
				(type default)
			)
			(layer "F.SilkS")
		)
		(fp_line
			(start 16.552164 -0.987806)
			(end 17.908524 -2.289048)
			(stroke
				(width 0.1)
				(type default)
			)
			(layer "F.SilkS")
		)
		(fp_line
			(start 16.552164 -0.987806)
			(end 17.908524 -2.289048)
			(stroke
				(width 0.1)
				(type default)
			)
			(layer "F.SilkS")
		)
		(fp_line
			(start 16.562832 -0.882904)
			(end 16.623284 -0.882904)
			(stroke
				(width 0.1)
				(type default)
			)
			(layer "F.SilkS")
		)
		(fp_line
			(start 16.562832 -0.882904)
			(end 16.623284 -0.882904)
			(stroke
				(width 0.1)
				(type default)
			)
			(layer "F.SilkS")
		)
		(fp_line
			(start 16.562832 -0.882904)
			(end 17.88414 -2.150364)
			(stroke
				(width 0.1)
				(type default)
			)
			(layer "F.SilkS")
		)
		(fp_line
			(start 16.562832 -0.882904)
			(end 17.88414 -2.150364)
			(stroke
				(width 0.1)
				(type default)
			)
			(layer "F.SilkS")
		)
		(fp_line
			(start 16.564356 -1.057148)
			(end 16.552164 -0.987806)
			(stroke
				(width 0.1)
				(type default)
			)
			(layer "F.SilkS")
		)
		(fp_line
			(start 16.564356 -1.057148)
			(end 16.552164 -0.987806)
			(stroke
				(width 0.1)
				(type default)
			)
			(layer "F.SilkS")
		)
		(fp_line
			(start 16.564356 -1.057148)
			(end 17.920716 -2.35839)
			(stroke
				(width 0.1)
				(type default)
			)
			(layer "F.SilkS")
		)
		(fp_line
			(start 16.564356 -1.057148)
			(end 17.920716 -2.35839)
			(stroke
				(width 0.1)
				(type default)
			)
			(layer "F.SilkS")
		)
		(fp_line
			(start 16.576294 -1.126744)
			(end 16.564356 -1.057148)
			(stroke
				(width 0.1)
				(type default)
			)
			(layer "F.SilkS")
		)
		(fp_line
			(start 16.576294 -1.126744)
			(end 16.564356 -1.057148)
			(stroke
				(width 0.1)
				(type default)
			)
			(layer "F.SilkS")
		)
		(fp_line
			(start 16.576294 -1.126744)
			(end 17.932908 -2.427732)
			(stroke
				(width 0.1)
				(type default)
			)
			(layer "F.SilkS")
		)
		(fp_line
			(start 16.576294 -1.126744)
			(end 17.932908 -2.427732)
			(stroke
				(width 0.1)
				(type default)
			)
			(layer "F.SilkS")
		)
		(fp_line
			(start 16.58874 -1.196086)
			(end 16.576294 -1.126744)
			(stroke
				(width 0.1)
				(type default)
			)
			(layer "F.SilkS")
		)
		(fp_line
			(start 16.58874 -1.196086)
			(end 16.576294 -1.126744)
			(stroke
				(width 0.1)
				(type default)
			)
			(layer "F.SilkS")
		)
		(fp_line
			(start 16.58874 -1.196086)
			(end 17.9451 -2.497328)
			(stroke
				(width 0.1)
				(type default)
			)
			(layer "F.SilkS")
		)
		(fp_line
			(start 16.58874 -1.196086)
			(end 17.9451 -2.497328)
			(stroke
				(width 0.1)
				(type default)
			)
			(layer "F.SilkS")
		)
		(fp_line
			(start 16.590772 -5.237734)
			(end 14.328394 -3.067558)
			(stroke
				(width 0.1)
				(type default)
			)
			(layer "F.SilkS")
		)
		(fp_line
			(start 16.590772 -5.237734)
			(end 14.328394 -3.067558)
			(stroke
				(width 0.1)
				(type default)
			)
			(layer "F.SilkS")
		)
		(fp_line
			(start 16.600932 -1.265428)
			(end 16.58874 -1.196086)
			(stroke
				(width 0.1)
				(type default)
			)
			(layer "F.SilkS")
		)
		(fp_line
			(start 16.600932 -1.265428)
			(end 16.58874 -1.196086)
			(stroke
				(width 0.1)
				(type default)
			)
			(layer "F.SilkS")
		)
		(fp_line
			(start 16.600932 -1.265428)
			(end 17.957038 -2.56667)
			(stroke
				(width 0.1)
				(type default)
			)
			(layer "F.SilkS")
		)
		(fp_line
			(start 16.600932 -1.265428)
			(end 17.957038 -2.56667)
			(stroke
				(width 0.1)
				(type default)
			)
			(layer "F.SilkS")
		)
		(fp_line
			(start 16.61287 -1.33477)
			(end 16.600932 -1.265428)
			(stroke
				(width 0.1)
				(type default)
			)
			(layer "F.SilkS")
		)
		(fp_line
			(start 16.61287 -1.33477)
			(end 16.600932 -1.265428)
			(stroke
				(width 0.1)
				(type default)
			)
			(layer "F.SilkS")
		)
		(fp_line
			(start 16.61287 -1.33477)
			(end 17.969484 -2.636012)
			(stroke
				(width 0.1)
				(type default)
			)
			(layer "F.SilkS")
		)
		(fp_line
			(start 16.61287 -1.33477)
			(end 17.969484 -2.636012)
			(stroke
				(width 0.1)
				(type default)
			)
			(layer "F.SilkS")
		)
		(fp_line
			(start 16.623284 -0.882904)
			(end 16.683228 -0.882904)
			(stroke
				(width 0.1)
				(type default)
			)
			(layer "F.SilkS")
		)
		(fp_line
			(start 16.623284 -0.882904)
			(end 16.683228 -0.882904)
			(stroke
				(width 0.1)
				(type default)
			)
			(layer "F.SilkS")
		)
		(fp_line
			(start 16.623284 -0.882904)
			(end 17.871948 -2.081022)
			(stroke
				(width 0.1)
				(type default)
			)
			(layer "F.SilkS")
		)
		(fp_line
			(start 16.623284 -0.882904)
			(end 17.871948 -2.081022)
			(stroke
				(width 0.1)
				(type default)
			)
			(layer "F.SilkS")
		)
		(fp_line
			(start 16.625316 -1.404366)
			(end 16.61287 -1.33477)
			(stroke
				(width 0.1)
				(type default)
			)
			(layer "F.SilkS")
		)
		(fp_line
			(start 16.625316 -1.404366)
			(end 16.61287 -1.33477)
			(stroke
				(width 0.1)
				(type default)
			)
			(layer "F.SilkS")
		)
		(fp_line
			(start 16.625316 -1.404366)
			(end 17.981676 -2.705608)
			(stroke
				(width 0.1)
				(type default)
			)
			(layer "F.SilkS")
		)
		(fp_line
			(start 16.625316 -1.404366)
			(end 17.981676 -2.705608)
			(stroke
				(width 0.1)
				(type default)
			)
			(layer "F.SilkS")
		)
		(fp_line
			(start 16.637762 -1.473962)
			(end 16.625316 -1.404366)
			(stroke
				(width 0.1)
				(type default)
			)
			(layer "F.SilkS")
		)
		(fp_line
			(start 16.637762 -1.473962)
			(end 16.625316 -1.404366)
			(stroke
				(width 0.1)
				(type default)
			)
			(layer "F.SilkS")
		)
		(fp_line
			(start 16.637762 -1.473962)
			(end 17.993614 -2.77495)
			(stroke
				(width 0.1)
				(type default)
			)
			(layer "F.SilkS")
		)
		(fp_line
			(start 16.637762 -1.473962)
			(end 17.993614 -2.77495)
			(stroke
				(width 0.1)
				(type default)
			)
			(layer "F.SilkS")
		)
		(fp_line
			(start 16.6497 -1.54305)
			(end 16.637762 -1.473962)
			(stroke
				(width 0.1)
				(type default)
			)
			(layer "F.SilkS")
		)
		(fp_line
			(start 16.6497 -1.54305)
			(end 16.637762 -1.473962)
			(stroke
				(width 0.1)
				(type default)
			)
			(layer "F.SilkS")
		)
		(fp_line
			(start 16.6497 -1.54305)
			(end 18.00606 -2.844292)
			(stroke
				(width 0.1)
				(type default)
			)
			(layer "F.SilkS")
		)
		(fp_line
			(start 16.6497 -1.54305)
			(end 18.00606 -2.844292)
			(stroke
				(width 0.1)
				(type default)
			)
			(layer "F.SilkS")
		)
		(fp_line
			(start 16.657066 -5.24383)
			(end 14.316456 -2.998216)
			(stroke
				(width 0.1)
				(type default)
			)
			(layer "F.SilkS")
		)
		(fp_line
			(start 16.657066 -5.24383)
			(end 14.316456 -2.998216)
			(stroke
				(width 0.1)
				(type default)
			)
			(layer "F.SilkS")
		)
		(fp_line
			(start 16.661892 -1.612646)
			(end 16.6497 -1.54305)
			(stroke
				(width 0.1)
				(type default)
			)
			(layer "F.SilkS")
		)
		(fp_line
			(start 16.661892 -1.612646)
			(end 16.6497 -1.54305)
			(stroke
				(width 0.1)
				(type default)
			)
			(layer "F.SilkS")
		)
		(fp_line
			(start 16.661892 -1.612646)
			(end 18.017998 -2.913634)
			(stroke
				(width 0.1)
				(type default)
			)
			(layer "F.SilkS")
		)
		(fp_line
			(start 16.661892 -1.612646)
			(end 18.017998 -2.913634)
			(stroke
				(width 0.1)
				(type default)
			)
			(layer "F.SilkS")
		)
		(fp_line
			(start 16.674084 -1.681988)
			(end 16.661892 -1.612646)
			(stroke
				(width 0.1)
				(type default)
			)
			(layer "F.SilkS")
		)
		(fp_line
			(start 16.674084 -1.681988)
			(end 16.661892 -1.612646)
			(stroke
				(width 0.1)
				(type default)
			)
			(layer "F.SilkS")
		)
		(fp_line
			(start 16.674084 -1.681988)
			(end 18.03019 -2.982976)
			(stroke
				(width 0.1)
				(type default)
			)
			(layer "F.SilkS")
		)
		(fp_line
			(start 16.674084 -1.681988)
			(end 18.03019 -2.982976)
			(stroke
				(width 0.1)
				(type default)
			)
			(layer "F.SilkS")
		)
		(fp_line
			(start 16.683228 -0.882904)
			(end 16.743426 -0.882904)
			(stroke
				(width 0.1)
				(type default)
			)
			(layer "F.SilkS")
		)
		(fp_line
			(start 16.683228 -0.882904)
			(end 16.743426 -0.882904)
			(stroke
				(width 0.1)
				(type default)
			)
			(layer "F.SilkS")
		)
		(fp_line
			(start 16.683228 -0.882904)
			(end 17.86001 -2.011426)
			(stroke
				(width 0.1)
				(type default)
			)
			(layer "F.SilkS")
		)
		(fp_line
			(start 16.683228 -0.882904)
			(end 17.86001 -2.011426)
			(stroke
				(width 0.1)
				(type default)
			)
			(layer "F.SilkS")
		)
		(fp_line
			(start 16.686276 -1.751584)
			(end 16.674084 -1.681988)
			(stroke
				(width 0.1)
				(type default)
			)
			(layer "F.SilkS")
		)
		(fp_line
			(start 16.686276 -1.751584)
			(end 16.674084 -1.681988)
			(stroke
				(width 0.1)
				(type default)
			)
			(layer "F.SilkS")
		)
		(fp_line
			(start 16.686276 -1.751584)
			(end 18.042636 -3.052572)
			(stroke
				(width 0.1)
				(type default)
			)
			(layer "F.SilkS")
		)
		(fp_line
			(start 16.686276 -1.751584)
			(end 18.042636 -3.052572)
			(stroke
				(width 0.1)
				(type default)
			)
			(layer "F.SilkS")
		)
		(fp_line
			(start 16.698214 -1.820926)
			(end 16.686276 -1.751584)
			(stroke
				(width 0.1)
				(type default)
			)
			(layer "F.SilkS")
		)
		(fp_line
			(start 16.698214 -1.820926)
			(end 16.686276 -1.751584)
			(stroke
				(width 0.1)
				(type default)
			)
			(layer "F.SilkS")
		)
		(fp_line
			(start 16.698214 -1.820926)
			(end 18.054574 -3.121914)
			(stroke
				(width 0.1)
				(type default)
			)
			(layer "F.SilkS")
		)
		(fp_line
			(start 16.698214 -1.820926)
			(end 18.054574 -3.121914)
			(stroke
				(width 0.1)
				(type default)
			)
			(layer "F.SilkS")
		)
		(fp_line
			(start 16.71066 -1.890268)
			(end 16.698214 -1.820926)
			(stroke
				(width 0.1)
				(type default)
			)
			(layer "F.SilkS")
		)
		(fp_line
			(start 16.71066 -1.890268)
			(end 16.698214 -1.820926)
			(stroke
				(width 0.1)
				(type default)
			)
			(layer "F.SilkS")
		)
		(fp_line
			(start 16.71066 -1.890268)
			(end 18.066766 -3.191002)
			(stroke
				(width 0.1)
				(type default)
			)
			(layer "F.SilkS")
		)
		(fp_line
			(start 16.71066 -1.890268)
			(end 18.066766 -3.191002)
			(stroke
				(width 0.1)
				(type default)
			)
			(layer "F.SilkS")
		)
		(fp_line
			(start 16.723106 -1.95961)
			(end 16.71066 -1.890268)
			(stroke
				(width 0.1)
				(type default)
			)
			(layer "F.SilkS")
		)
		(fp_line
			(start 16.723106 -1.95961)
			(end 16.71066 -1.890268)
			(stroke
				(width 0.1)
				(type default)
			)
			(layer "F.SilkS")
		)
		(fp_line
			(start 16.723106 -1.95961)
			(end 18.079212 -3.260598)
			(stroke
				(width 0.1)
				(type default)
			)
			(layer "F.SilkS")
		)
		(fp_line
			(start 16.723106 -1.95961)
			(end 18.079212 -3.260598)
			(stroke
				(width 0.1)
				(type default)
			)
			(layer "F.SilkS")
		)
		(fp_line
			(start 16.723868 -5.25018)
			(end 14.30401 -2.928874)
			(stroke
				(width 0.1)
				(type default)
			)
			(layer "F.SilkS")
		)
		(fp_line
			(start 16.723868 -5.25018)
			(end 14.30401 -2.928874)
			(stroke
				(width 0.1)
				(type default)
			)
			(layer "F.SilkS")
		)
		(fp_line
			(start 16.735044 -2.028952)
			(end 16.723106 -1.95961)
			(stroke
				(width 0.1)
				(type default)
			)
			(layer "F.SilkS")
		)
		(fp_line
			(start 16.735044 -2.028952)
			(end 16.723106 -1.95961)
			(stroke
				(width 0.1)
				(type default)
			)
			(layer "F.SilkS")
		)
		(fp_line
			(start 16.735044 -2.028952)
			(end 18.089372 -3.328416)
			(stroke
				(width 0.1)
				(type default)
			)
			(layer "F.SilkS")
		)
		(fp_line
			(start 16.735044 -2.028952)
			(end 18.089372 -3.328416)
			(stroke
				(width 0.1)
				(type default)
			)
			(layer "F.SilkS")
		)
		(fp_line
			(start 16.743426 -0.882904)
			(end 16.803624 -0.882904)
			(stroke
				(width 0.1)
				(type default)
			)
			(layer "F.SilkS")
		)
		(fp_line
			(start 16.743426 -0.882904)
			(end 16.803624 -0.882904)
			(stroke
				(width 0.1)
				(type default)
			)
			(layer "F.SilkS")
		)
		(fp_line
			(start 16.743426 -0.882904)
			(end 17.847564 -1.942338)
			(stroke
				(width 0.1)
				(type default)
			)
			(layer "F.SilkS")
		)
		(fp_line
			(start 16.743426 -0.882904)
			(end 17.847564 -1.942338)
			(stroke
				(width 0.1)
				(type default)
			)
			(layer "F.SilkS")
		)
		(fp_line
			(start 16.747236 -2.098548)
			(end 16.735044 -2.028952)
			(stroke
				(width 0.1)
				(type default)
			)
			(layer "F.SilkS")
		)
		(fp_line
			(start 16.747236 -2.098548)
			(end 16.735044 -2.028952)
			(stroke
				(width 0.1)
				(type default)
			)
			(layer "F.SilkS")
		)
		(fp_line
			(start 16.747236 -2.098548)
			(end 18.097246 -3.393694)
			(stroke
				(width 0.1)
				(type default)
			)
			(layer "F.SilkS")
		)
		(fp_line
			(start 16.747236 -2.098548)
			(end 18.097246 -3.393694)
			(stroke
				(width 0.1)
				(type default)
			)
			(layer "F.SilkS")
		)
		(fp_line
			(start 16.759682 -2.16789)
			(end 16.747236 -2.098548)
			(stroke
				(width 0.1)
				(type default)
			)
			(layer "F.SilkS")
		)
		(fp_line
			(start 16.759682 -2.16789)
			(end 16.747236 -2.098548)
			(stroke
				(width 0.1)
				(type default)
			)
			(layer "F.SilkS")
		)
		(fp_line
			(start 16.759682 -2.16789)
			(end 18.105374 -3.458718)
			(stroke
				(width 0.1)
				(type default)
			)
			(layer "F.SilkS")
		)
		(fp_line
			(start 16.759682 -2.16789)
			(end 18.105374 -3.458718)
			(stroke
				(width 0.1)
				(type default)
			)
			(layer "F.SilkS")
		)
		(fp_line
			(start 16.77162 -2.237232)
			(end 16.759682 -2.16789)
			(stroke
				(width 0.1)
				(type default)
			)
			(layer "F.SilkS")
		)
		(fp_line
			(start 16.77162 -2.237232)
			(end 16.759682 -2.16789)
			(stroke
				(width 0.1)
				(type default)
			)
			(layer "F.SilkS")
		)
		(fp_line
			(start 16.77162 -2.237232)
			(end 18.113248 -3.52425)
			(stroke
				(width 0.1)
				(type default)
			)
			(layer "F.SilkS")
		)
		(fp_line
			(start 16.77162 -2.237232)
			(end 18.113248 -3.52425)
			(stroke
				(width 0.1)
				(type default)
			)
			(layer "F.SilkS")
		)
		(fp_line
			(start 16.783812 -2.306828)
			(end 16.77162 -2.237232)
			(stroke
				(width 0.1)
				(type default)
			)
			(layer "F.SilkS")
		)
		(fp_line
			(start 16.783812 -2.306828)
			(end 16.77162 -2.237232)
			(stroke
				(width 0.1)
				(type default)
			)
			(layer "F.SilkS")
		)
		(fp_line
			(start 16.783812 -2.306828)
			(end 18.121122 -3.589782)
			(stroke
				(width 0.1)
				(type default)
			)
			(layer "F.SilkS")
		)
		(fp_line
			(start 16.783812 -2.306828)
			(end 18.121122 -3.589782)
			(stroke
				(width 0.1)
				(type default)
			)
			(layer "F.SilkS")
		)
		(fp_line
			(start 16.790162 -5.256022)
			(end 14.291818 -2.859532)
			(stroke
				(width 0.1)
				(type default)
			)
			(layer "F.SilkS")
		)
		(fp_line
			(start 16.790162 -5.256022)
			(end 14.291818 -2.859532)
			(stroke
				(width 0.1)
				(type default)
			)
			(layer "F.SilkS")
		)
		(fp_line
			(start 16.796258 -2.37617)
			(end 16.783812 -2.306828)
			(stroke
				(width 0.1)
				(type default)
			)
			(layer "F.SilkS")
		)
		(fp_line
			(start 16.796258 -2.37617)
			(end 16.783812 -2.306828)
			(stroke
				(width 0.1)
				(type default)
			)
			(layer "F.SilkS")
		)
		(fp_line
			(start 16.796258 -2.37617)
			(end 18.129504 -3.65506)
			(stroke
				(width 0.1)
				(type default)
			)
			(layer "F.SilkS")
		)
		(fp_line
			(start 16.796258 -2.37617)
			(end 18.129504 -3.65506)
			(stroke
				(width 0.1)
				(type default)
			)
			(layer "F.SilkS")
		)
		(fp_line
			(start 16.803624 -0.882904)
			(end 16.863568 -0.882904)
			(stroke
				(width 0.1)
				(type default)
			)
			(layer "F.SilkS")
		)
		(fp_line
			(start 16.803624 -0.882904)
			(end 16.863568 -0.882904)
			(stroke
				(width 0.1)
				(type default)
			)
			(layer "F.SilkS")
		)
		(fp_line
			(start 16.803624 -0.882904)
			(end 17.835626 -1.872742)
			(stroke
				(width 0.1)
				(type default)
			)
			(layer "F.SilkS")
		)
		(fp_line
			(start 16.803624 -0.882904)
			(end 17.835626 -1.872742)
			(stroke
				(width 0.1)
				(type default)
			)
			(layer "F.SilkS")
		)
		(fp_line
			(start 16.808196 -2.445512)
			(end 16.796258 -2.37617)
			(stroke
				(width 0.1)
				(type default)
			)
			(layer "F.SilkS")
		)
		(fp_line
			(start 16.808196 -2.445512)
			(end 16.796258 -2.37617)
			(stroke
				(width 0.1)
				(type default)
			)
			(layer "F.SilkS")
		)
		(fp_line
			(start 16.808196 -2.445512)
			(end 18.13687 -3.720338)
			(stroke
				(width 0.1)
				(type default)
			)
			(layer "F.SilkS")
		)
		(fp_line
			(start 16.808196 -2.445512)
			(end 18.13687 -3.720338)
			(stroke
				(width 0.1)
				(type default)
			)
			(layer "F.SilkS")
		)
		(fp_line
			(start 16.820134 -2.515108)
			(end 16.808196 -2.445512)
			(stroke
				(width 0.1)
				(type default)
			)
			(layer "F.SilkS")
		)
		(fp_line
			(start 16.820134 -2.515108)
			(end 16.808196 -2.445512)
			(stroke
				(width 0.1)
				(type default)
			)
			(layer "F.SilkS")
		)
		(fp_line
			(start 16.820134 -2.515108)
			(end 16.83258 -2.58445)
			(stroke
				(width 0.1)
				(type default)
			)
			(layer "F.SilkS")
		)
		(fp_line
			(start 16.820134 -2.515108)
			(end 16.83258 -2.58445)
			(stroke
				(width 0.1)
				(type default)
			)
			(layer "F.SilkS")
		)
		(fp_line
			(start 16.820134 -2.515108)
			(end 18.138394 -3.779266)
			(stroke
				(width 0.1)
				(type default)
			)
			(layer "F.SilkS")
		)
		(fp_line
			(start 16.820134 -2.515108)
			(end 18.138394 -3.779266)
			(stroke
				(width 0.1)
				(type default)
			)
			(layer "F.SilkS")
		)
		(fp_line
			(start 16.845026 -2.653792)
			(end 16.83258 -2.58445)
			(stroke
				(width 0.1)
				(type default)
			)
			(layer "F.SilkS")
		)
		(fp_line
			(start 16.845026 -2.653792)
			(end 16.83258 -2.58445)
			(stroke
				(width 0.1)
				(type default)
			)
			(layer "F.SilkS")
		)
		(fp_line
			(start 16.845026 -2.653792)
			(end 18.137378 -3.89382)
			(stroke
				(width 0.1)
				(type default)
			)
			(layer "F.SilkS")
		)
		(fp_line
			(start 16.845026 -2.653792)
			(end 18.137378 -3.89382)
			(stroke
				(width 0.1)
				(type default)
			)
			(layer "F.SilkS")
		)
		(fp_line
			(start 16.854678 -5.26034)
			(end 14.27988 -2.79019)
			(stroke
				(width 0.1)
				(type default)
			)
			(layer "F.SilkS")
		)
		(fp_line
			(start 16.854678 -5.26034)
			(end 14.27988 -2.79019)
			(stroke
				(width 0.1)
				(type default)
			)
			(layer "F.SilkS")
		)
		(fp_line
			(start 16.857218 -2.723134)
			(end 16.845026 -2.653792)
			(stroke
				(width 0.1)
				(type default)
			)
			(layer "F.SilkS")
		)
		(fp_line
			(start 16.857218 -2.723134)
			(end 16.845026 -2.653792)
			(stroke
				(width 0.1)
				(type default)
			)
			(layer "F.SilkS")
		)
		(fp_line
			(start 16.857218 -2.723134)
			(end 18.13687 -3.95097)
			(stroke
				(width 0.1)
				(type default)
			)
			(layer "F.SilkS")
		)
		(fp_line
			(start 16.857218 -2.723134)
			(end 18.13687 -3.95097)
			(stroke
				(width 0.1)
				(type default)
			)
			(layer "F.SilkS")
		)
		(fp_line
			(start 16.863568 -0.882904)
			(end 16.92402 -0.882904)
			(stroke
				(width 0.1)
				(type default)
			)
			(layer "F.SilkS")
		)
		(fp_line
			(start 16.863568 -0.882904)
			(end 16.92402 -0.882904)
			(stroke
				(width 0.1)
				(type default)
			)
			(layer "F.SilkS")
		)
		(fp_line
			(start 16.863568 -0.882904)
			(end 17.823434 -1.8034)
			(stroke
				(width 0.1)
				(type default)
			)
			(layer "F.SilkS")
		)
		(fp_line
			(start 16.863568 -0.882904)
			(end 17.823434 -1.8034)
			(stroke
				(width 0.1)
				(type default)
			)
			(layer "F.SilkS")
		)
		(fp_line
			(start 16.869156 -2.79273)
			(end 16.857218 -2.723134)
			(stroke
				(width 0.1)
				(type default)
			)
			(layer "F.SilkS")
		)
		(fp_line
			(start 16.869156 -2.79273)
			(end 16.857218 -2.723134)
			(stroke
				(width 0.1)
				(type default)
			)
			(layer "F.SilkS")
		)
		(fp_line
			(start 16.869156 -2.79273)
			(end 18.136362 -4.008374)
			(stroke
				(width 0.1)
				(type default)
			)
			(layer "F.SilkS")
		)
		(fp_line
			(start 16.869156 -2.79273)
			(end 18.136362 -4.008374)
			(stroke
				(width 0.1)
				(type default)
			)
			(layer "F.SilkS")
		)
		(fp_line
			(start 16.881602 -2.862072)
			(end 16.869156 -2.79273)
			(stroke
				(width 0.1)
				(type default)
			)
			(layer "F.SilkS")
		)
		(fp_line
			(start 16.881602 -2.862072)
			(end 16.869156 -2.79273)
			(stroke
				(width 0.1)
				(type default)
			)
			(layer "F.SilkS")
		)
		(fp_line
			(start 16.881602 -2.862072)
			(end 18.136362 -4.065524)
			(stroke
				(width 0.1)
				(type default)
			)
			(layer "F.SilkS")
		)
		(fp_line
			(start 16.881602 -2.862072)
			(end 18.136362 -4.065524)
			(stroke
				(width 0.1)
				(type default)
			)
			(layer "F.SilkS")
		)
		(fp_line
			(start 16.89354 -2.931414)
			(end 16.881602 -2.862072)
			(stroke
				(width 0.1)
				(type default)
			)
			(layer "F.SilkS")
		)
		(fp_line
			(start 16.89354 -2.931414)
			(end 16.881602 -2.862072)
			(stroke
				(width 0.1)
				(type default)
			)
			(layer "F.SilkS")
		)
		(fp_line
			(start 16.89354 -2.931414)
			(end 18.134838 -4.121912)
			(stroke
				(width 0.1)
				(type default)
			)
			(layer "F.SilkS")
		)
		(fp_line
			(start 16.89354 -2.931414)
			(end 18.134838 -4.121912)
			(stroke
				(width 0.1)
				(type default)
			)
			(layer "F.SilkS")
		)
		(fp_line
			(start 16.905732 -3.000756)
			(end 16.89354 -2.931414)
			(stroke
				(width 0.1)
				(type default)
			)
			(layer "F.SilkS")
		)
		(fp_line
			(start 16.905732 -3.000756)
			(end 16.89354 -2.931414)
			(stroke
				(width 0.1)
				(type default)
			)
			(layer "F.SilkS")
		)
		(fp_line
			(start 16.905732 -3.000756)
			(end 18.125948 -4.171188)
			(stroke
				(width 0.1)
				(type default)
			)
			(layer "F.SilkS")
		)
		(fp_line
			(start 16.905732 -3.000756)
			(end 18.125948 -4.171188)
			(stroke
				(width 0.1)
				(type default)
			)
			(layer "F.SilkS")
		)
		(fp_line
			(start 16.909796 -5.255514)
			(end 14.267434 -2.720594)
			(stroke
				(width 0.1)
				(type default)
			)
			(layer "F.SilkS")
		)
		(fp_line
			(start 16.909796 -5.255514)
			(end 14.267434 -2.720594)
			(stroke
				(width 0.1)
				(type default)
			)
			(layer "F.SilkS")
		)
		(fp_line
			(start 16.918178 -3.070352)
			(end 16.905732 -3.000756)
			(stroke
				(width 0.1)
				(type default)
			)
			(layer "F.SilkS")
		)
		(fp_line
			(start 16.918178 -3.070352)
			(end 16.905732 -3.000756)
			(stroke
				(width 0.1)
				(type default)
			)
			(layer "F.SilkS")
		)
		(fp_line
			(start 16.918178 -3.070352)
			(end 18.117058 -4.220464)
			(stroke
				(width 0.1)
				(type default)
			)
			(layer "F.SilkS")
		)
		(fp_line
			(start 16.918178 -3.070352)
			(end 18.117058 -4.220464)
			(stroke
				(width 0.1)
				(type default)
			)
			(layer "F.SilkS")
		)
		(fp_line
			(start 16.92402 -0.882904)
			(end 16.984218 -0.882904)
			(stroke
				(width 0.1)
				(type default)
			)
			(layer "F.SilkS")
		)
		(fp_line
			(start 16.92402 -0.882904)
			(end 16.984218 -0.882904)
			(stroke
				(width 0.1)
				(type default)
			)
			(layer "F.SilkS")
		)
		(fp_line
			(start 16.92402 -0.882904)
			(end 17.810988 -1.734058)
			(stroke
				(width 0.1)
				(type default)
			)
			(layer "F.SilkS")
		)
		(fp_line
			(start 16.92402 -0.882904)
			(end 17.810988 -1.734058)
			(stroke
				(width 0.1)
				(type default)
			)
			(layer "F.SilkS")
		)
		(fp_line
			(start 16.930624 -3.139694)
			(end 16.918178 -3.070352)
			(stroke
				(width 0.1)
				(type default)
			)
			(layer "F.SilkS")
		)
		(fp_line
			(start 16.930624 -3.139694)
			(end 16.918178 -3.070352)
			(stroke
				(width 0.1)
				(type default)
			)
			(layer "F.SilkS")
		)
		(fp_line
			(start 16.96466 -5.25018)
			(end 14.255496 -2.651506)
			(stroke
				(width 0.1)
				(type default)
			)
			(layer "F.SilkS")
		)
		(fp_line
			(start 16.96466 -5.25018)
			(end 14.255496 -2.651506)
			(stroke
				(width 0.1)
				(type default)
			)
			(layer "F.SilkS")
		)
		(fp_line
			(start 16.984218 -0.882904)
			(end 17.044162 -0.882904)
			(stroke
				(width 0.1)
				(type default)
			)
			(layer "F.SilkS")
		)
		(fp_line
			(start 16.984218 -0.882904)
			(end 17.044162 -0.882904)
			(stroke
				(width 0.1)
				(type default)
			)
			(layer "F.SilkS")
		)
		(fp_line
			(start 16.984218 -0.882904)
			(end 17.79905 -1.664716)
			(stroke
				(width 0.1)
				(type default)
			)
			(layer "F.SilkS")
		)
		(fp_line
			(start 16.984218 -0.882904)
			(end 17.79905 -1.664716)
			(stroke
				(width 0.1)
				(type default)
			)
			(layer "F.SilkS")
		)
		(fp_line
			(start 17.01927 -5.245354)
			(end 14.243304 -2.58191)
			(stroke
				(width 0.1)
				(type default)
			)
			(layer "F.SilkS")
		)
		(fp_line
			(start 17.01927 -5.245354)
			(end 14.243304 -2.58191)
			(stroke
				(width 0.1)
				(type default)
			)
			(layer "F.SilkS")
		)
		(fp_line
			(start 17.044162 -0.882904)
			(end 17.10436 -0.882904)
			(stroke
				(width 0.1)
				(type default)
			)
			(layer "F.SilkS")
		)
		(fp_line
			(start 17.044162 -0.882904)
			(end 17.10436 -0.882904)
			(stroke
				(width 0.1)
				(type default)
			)
			(layer "F.SilkS")
		)
		(fp_line
			(start 17.044162 -0.882904)
			(end 17.786858 -1.595374)
			(stroke
				(width 0.1)
				(type default)
			)
			(layer "F.SilkS")
		)
		(fp_line
			(start 17.044162 -0.882904)
			(end 17.786858 -1.595374)
			(stroke
				(width 0.1)
				(type default)
			)
			(layer "F.SilkS")
		)
		(fp_line
			(start 17.074388 -5.240274)
			(end 14.230858 -2.512314)
			(stroke
				(width 0.1)
				(type default)
			)
			(layer "F.SilkS")
		)
		(fp_line
			(start 17.074388 -5.240274)
			(end 14.230858 -2.512314)
			(stroke
				(width 0.1)
				(type default)
			)
			(layer "F.SilkS")
		)
		(fp_line
			(start 17.10436 -0.882904)
			(end 17.164812 -0.882904)
			(stroke
				(width 0.1)
				(type default)
			)
			(layer "F.SilkS")
		)
		(fp_line
			(start 17.10436 -0.882904)
			(end 17.164812 -0.882904)
			(stroke
				(width 0.1)
				(type default)
			)
			(layer "F.SilkS")
		)
		(fp_line
			(start 17.10436 -0.882904)
			(end 17.774666 -1.525778)
			(stroke
				(width 0.1)
				(type default)
			)
			(layer "F.SilkS")
		)
		(fp_line
			(start 17.10436 -0.882904)
			(end 17.774666 -1.525778)
			(stroke
				(width 0.1)
				(type default)
			)
			(layer "F.SilkS")
		)
		(fp_line
			(start 17.129252 -5.235194)
			(end 15.934944 -4.0894)
			(stroke
				(width 0.1)
				(type default)
			)
			(layer "F.SilkS")
		)
		(fp_line
			(start 17.129252 -5.235194)
			(end 15.934944 -4.0894)
			(stroke
				(width 0.1)
				(type default)
			)
			(layer "F.SilkS")
		)
		(fp_line
			(start 17.164812 -0.882904)
			(end 17.224756 -0.882904)
			(stroke
				(width 0.1)
				(type default)
			)
			(layer "F.SilkS")
		)
		(fp_line
			(start 17.164812 -0.882904)
			(end 17.224756 -0.882904)
			(stroke
				(width 0.1)
				(type default)
			)
			(layer "F.SilkS")
		)
		(fp_line
			(start 17.164812 -0.882904)
			(end 17.762474 -1.456436)
			(stroke
				(width 0.1)
				(type default)
			)
			(layer "F.SilkS")
		)
		(fp_line
			(start 17.164812 -0.882904)
			(end 17.762474 -1.456436)
			(stroke
				(width 0.1)
				(type default)
			)
			(layer "F.SilkS")
		)
		(fp_line
			(start 17.184116 -5.230114)
			(end 16.052292 -4.144264)
			(stroke
				(width 0.1)
				(type default)
			)
			(layer "F.SilkS")
		)
		(fp_line
			(start 17.184116 -5.230114)
			(end 16.052292 -4.144264)
			(stroke
				(width 0.1)
				(type default)
			)
			(layer "F.SilkS")
		)
		(fp_line
			(start 17.224756 -0.882904)
			(end 17.284954 -0.882904)
			(stroke
				(width 0.1)
				(type default)
			)
			(layer "F.SilkS")
		)
		(fp_line
			(start 17.224756 -0.882904)
			(end 17.284954 -0.882904)
			(stroke
				(width 0.1)
				(type default)
			)
			(layer "F.SilkS")
		)
		(fp_line
			(start 17.224756 -0.882904)
			(end 17.750536 -1.387348)
			(stroke
				(width 0.1)
				(type default)
			)
			(layer "F.SilkS")
		)
		(fp_line
			(start 17.224756 -0.882904)
			(end 17.750536 -1.387348)
			(stroke
				(width 0.1)
				(type default)
			)
			(layer "F.SilkS")
		)
		(fp_line
			(start 17.235678 -5.221986)
			(end 16.13789 -4.168648)
			(stroke
				(width 0.1)
				(type default)
			)
			(layer "F.SilkS")
		)
		(fp_line
			(start 17.235678 -5.221986)
			(end 16.13789 -4.168648)
			(stroke
				(width 0.1)
				(type default)
			)
			(layer "F.SilkS")
		)
		(fp_line
			(start 17.280636 -5.207254)
			(end 16.218154 -4.187698)
			(stroke
				(width 0.1)
				(type default)
			)
			(layer "F.SilkS")
		)
		(fp_line
			(start 17.280636 -5.207254)
			(end 16.218154 -4.187698)
			(stroke
				(width 0.1)
				(type default)
			)
			(layer "F.SilkS")
		)
		(fp_line
			(start 17.284954 -0.882904)
			(end 17.345406 -0.882904)
			(stroke
				(width 0.1)
				(type default)
			)
			(layer "F.SilkS")
		)
		(fp_line
			(start 17.284954 -0.882904)
			(end 17.345406 -0.882904)
			(stroke
				(width 0.1)
				(type default)
			)
			(layer "F.SilkS")
		)
		(fp_line
			(start 17.284954 -0.882904)
			(end 17.73809 -1.317752)
			(stroke
				(width 0.1)
				(type default)
			)
			(layer "F.SilkS")
		)
		(fp_line
			(start 17.284954 -0.882904)
			(end 17.73809 -1.317752)
			(stroke
				(width 0.1)
				(type default)
			)
			(layer "F.SilkS")
		)
		(fp_line
			(start 17.32534 -5.192522)
			(end 16.283178 -4.192524)
			(stroke
				(width 0.1)
				(type default)
			)
			(layer "F.SilkS")
		)
		(fp_line
			(start 17.32534 -5.192522)
			(end 16.283178 -4.192524)
			(stroke
				(width 0.1)
				(type default)
			)
			(layer "F.SilkS")
		)
		(fp_line
			(start 17.345406 -0.882904)
			(end 17.40535 -0.882904)
			(stroke
				(width 0.1)
				(type default)
			)
			(layer "F.SilkS")
		)
		(fp_line
			(start 17.345406 -0.882904)
			(end 17.40535 -0.882904)
			(stroke
				(width 0.1)
				(type default)
			)
			(layer "F.SilkS")
		)
		(fp_line
			(start 17.345406 -0.882904)
			(end 17.725898 -1.248156)
			(stroke
				(width 0.1)
				(type default)
			)
			(layer "F.SilkS")
		)
		(fp_line
			(start 17.345406 -0.882904)
			(end 17.725898 -1.248156)
			(stroke
				(width 0.1)
				(type default)
			)
			(layer "F.SilkS")
		)
		(fp_line
			(start 17.370044 -5.17779)
			(end 16.347948 -4.197096)
			(stroke
				(width 0.1)
				(type default)
			)
			(layer "F.SilkS")
		)
		(fp_line
			(start 17.370044 -5.17779)
			(end 16.347948 -4.197096)
			(stroke
				(width 0.1)
				(type default)
			)
			(layer "F.SilkS")
		)
		(fp_line
			(start 17.40535 -0.882904)
			(end 17.465294 -0.882904)
			(stroke
				(width 0.1)
				(type default)
			)
			(layer "F.SilkS")
		)
		(fp_line
			(start 17.40535 -0.882904)
			(end 17.465294 -0.882904)
			(stroke
				(width 0.1)
				(type default)
			)
			(layer "F.SilkS")
		)
		(fp_line
			(start 17.40535 -0.882904)
			(end 17.71396 -1.178814)
			(stroke
				(width 0.1)
				(type default)
			)
			(layer "F.SilkS")
		)
		(fp_line
			(start 17.40535 -0.882904)
			(end 17.71396 -1.178814)
			(stroke
				(width 0.1)
				(type default)
			)
			(layer "F.SilkS")
		)
		(fp_line
			(start 17.415002 -5.163058)
			(end 16.40967 -4.198366)
			(stroke
				(width 0.1)
				(type default)
			)
			(layer "F.SilkS")
		)
		(fp_line
			(start 17.415002 -5.163058)
			(end 16.40967 -4.198366)
			(stroke
				(width 0.1)
				(type default)
			)
			(layer "F.SilkS")
		)
		(fp_line
			(start 17.45996 -5.148326)
			(end 16.465804 -4.194556)
			(stroke
				(width 0.1)
				(type default)
			)
			(layer "F.SilkS")
		)
		(fp_line
			(start 17.45996 -5.148326)
			(end 16.465804 -4.194556)
			(stroke
				(width 0.1)
				(type default)
			)
			(layer "F.SilkS")
		)
		(fp_line
			(start 17.465294 -0.882904)
			(end 17.525746 -0.882904)
			(stroke
				(width 0.1)
				(type default)
			)
			(layer "F.SilkS")
		)
		(fp_line
			(start 17.465294 -0.882904)
			(end 17.525746 -0.882904)
			(stroke
				(width 0.1)
				(type default)
			)
			(layer "F.SilkS")
		)
		(fp_line
			(start 17.465294 -0.882904)
			(end 17.701514 -1.109472)
			(stroke
				(width 0.1)
				(type default)
			)
			(layer "F.SilkS")
		)
		(fp_line
			(start 17.465294 -0.882904)
			(end 17.701514 -1.109472)
			(stroke
				(width 0.1)
				(type default)
			)
			(layer "F.SilkS")
		)
		(fp_line
			(start 17.50441 -5.13334)
			(end 16.521938 -4.190746)
			(stroke
				(width 0.1)
				(type default)
			)
			(layer "F.SilkS")
		)
		(fp_line
			(start 17.50441 -5.13334)
			(end 16.521938 -4.190746)
			(stroke
				(width 0.1)
				(type default)
			)
			(layer "F.SilkS")
		)
		(fp_line
			(start 17.525746 -0.882904)
			(end 17.58569 -0.882904)
			(stroke
				(width 0.1)
				(type default)
			)
			(layer "F.SilkS")
		)
		(fp_line
			(start 17.525746 -0.882904)
			(end 17.58569 -0.882904)
			(stroke
				(width 0.1)
				(type default)
			)
			(layer "F.SilkS")
		)
		(fp_line
			(start 17.525746 -0.882904)
			(end 17.689576 -1.04013)
			(stroke
				(width 0.1)
				(type default)
			)
			(layer "F.SilkS")
		)
		(fp_line
			(start 17.525746 -0.882904)
			(end 17.689576 -1.04013)
			(stroke
				(width 0.1)
				(type default)
			)
			(layer "F.SilkS")
		)
		(fp_line
			(start 17.545558 -5.115052)
			(end 16.5735 -4.182872)
			(stroke
				(width 0.1)
				(type default)
			)
			(layer "F.SilkS")
		)
		(fp_line
			(start 17.545558 -5.115052)
			(end 16.5735 -4.182872)
			(stroke
				(width 0.1)
				(type default)
			)
			(layer "F.SilkS")
		)
		(fp_line
			(start 17.580864 -5.091176)
			(end 16.621252 -4.170426)
			(stroke
				(width 0.1)
				(type default)
			)
			(layer "F.SilkS")
		)
		(fp_line
			(start 17.580864 -5.091176)
			(end 16.621252 -4.170426)
			(stroke
				(width 0.1)
				(type default)
			)
			(layer "F.SilkS")
		)
		(fp_line
			(start 17.58569 -0.882904)
			(end 17.645634 -0.882904)
			(stroke
				(width 0.1)
				(type default)
			)
			(layer "F.SilkS")
		)
		(fp_line
			(start 17.58569 -0.882904)
			(end 17.645634 -0.882904)
			(stroke
				(width 0.1)
				(type default)
			)
			(layer "F.SilkS")
		)
		(fp_line
			(start 17.58569 -0.882904)
			(end 17.677384 -0.970788)
			(stroke
				(width 0.1)
				(type default)
			)
			(layer "F.SilkS")
		)
		(fp_line
			(start 17.58569 -0.882904)
			(end 17.677384 -0.970788)
			(stroke
				(width 0.1)
				(type default)
			)
			(layer "F.SilkS")
		)
		(fp_line
			(start 17.61617 -5.067046)
			(end 16.668242 -4.15798)
			(stroke
				(width 0.1)
				(type default)
			)
			(layer "F.SilkS")
		)
		(fp_line
			(start 17.61617 -5.067046)
			(end 16.668242 -4.15798)
			(stroke
				(width 0.1)
				(type default)
			)
			(layer "F.SilkS")
		)
		(fp_line
			(start 17.645634 -0.882904)
			(end 17.66189 -0.882904)
			(stroke
				(width 0.1)
				(type default)
			)
			(layer "F.SilkS")
		)
		(fp_line
			(start 17.645634 -0.882904)
			(end 17.66189 -0.882904)
			(stroke
				(width 0.1)
				(type default)
			)
			(layer "F.SilkS")
		)
		(fp_line
			(start 17.645634 -0.882904)
			(end 17.664938 -0.901192)
			(stroke
				(width 0.1)
				(type default)
			)
			(layer "F.SilkS")
		)
		(fp_line
			(start 17.645634 -0.882904)
			(end 17.664938 -0.901192)
			(stroke
				(width 0.1)
				(type default)
			)
			(layer "F.SilkS")
		)
		(fp_line
			(start 17.651222 -5.043424)
			(end 16.71066 -4.140962)
			(stroke
				(width 0.1)
				(type default)
			)
			(layer "F.SilkS")
		)
		(fp_line
			(start 17.651222 -5.043424)
			(end 16.71066 -4.140962)
			(stroke
				(width 0.1)
				(type default)
			)
			(layer "F.SilkS")
		)
		(fp_line
			(start 17.66189 -0.882904)
			(end 17.664938 -0.901192)
			(stroke
				(width 0.1)
				(type default)
			)
			(layer "F.SilkS")
		)
		(fp_line
			(start 17.66189 -0.882904)
			(end 17.664938 -0.901192)
			(stroke
				(width 0.1)
				(type default)
			)
			(layer "F.SilkS")
		)
		(fp_line
			(start 17.677384 -0.970788)
			(end 17.664938 -0.901192)
			(stroke
				(width 0.1)
				(type default)
			)
			(layer "F.SilkS")
		)
		(fp_line
			(start 17.677384 -0.970788)
			(end 17.664938 -0.901192)
			(stroke
				(width 0.1)
				(type default)
			)
			(layer "F.SilkS")
		)
		(fp_line
			(start 17.686274 -5.019294)
			(end 16.747998 -4.119118)
			(stroke
				(width 0.1)
				(type default)
			)
			(layer "F.SilkS")
		)
		(fp_line
			(start 17.686274 -5.019294)
			(end 16.747998 -4.119118)
			(stroke
				(width 0.1)
				(type default)
			)
			(layer "F.SilkS")
		)
		(fp_line
			(start 17.689576 -1.04013)
			(end 17.677384 -0.970788)
			(stroke
				(width 0.1)
				(type default)
			)
			(layer "F.SilkS")
		)
		(fp_line
			(start 17.689576 -1.04013)
			(end 17.677384 -0.970788)
			(stroke
				(width 0.1)
				(type default)
			)
			(layer "F.SilkS")
		)
		(fp_line
			(start 17.701514 -1.109472)
			(end 17.689576 -1.04013)
			(stroke
				(width 0.1)
				(type default)
			)
			(layer "F.SilkS")
		)
		(fp_line
			(start 17.701514 -1.109472)
			(end 17.689576 -1.04013)
			(stroke
				(width 0.1)
				(type default)
			)
			(layer "F.SilkS")
		)
		(fp_line
			(start 17.71396 -1.178814)
			(end 17.701514 -1.109472)
			(stroke
				(width 0.1)
				(type default)
			)
			(layer "F.SilkS")
		)
		(fp_line
			(start 17.71396 -1.178814)
			(end 17.701514 -1.109472)
			(stroke
				(width 0.1)
				(type default)
			)
			(layer "F.SilkS")
		)
		(fp_line
			(start 17.721834 -4.995672)
			(end 16.785844 -4.097782)
			(stroke
				(width 0.1)
				(type default)
			)
			(layer "F.SilkS")
		)
		(fp_line
			(start 17.721834 -4.995672)
			(end 16.785844 -4.097782)
			(stroke
				(width 0.1)
				(type default)
			)
			(layer "F.SilkS")
		)
		(fp_line
			(start 17.725898 -1.248156)
			(end 17.71396 -1.178814)
			(stroke
				(width 0.1)
				(type default)
			)
			(layer "F.SilkS")
		)
		(fp_line
			(start 17.725898 -1.248156)
			(end 17.71396 -1.178814)
			(stroke
				(width 0.1)
				(type default)
			)
			(layer "F.SilkS")
		)
		(fp_line
			(start 17.73809 -1.317752)
			(end 17.725898 -1.248156)
			(stroke
				(width 0.1)
				(type default)
			)
			(layer "F.SilkS")
		)
		(fp_line
			(start 17.73809 -1.317752)
			(end 17.725898 -1.248156)
			(stroke
				(width 0.1)
				(type default)
			)
			(layer "F.SilkS")
		)
		(fp_line
			(start 17.750536 -1.387348)
			(end 17.73809 -1.317752)
			(stroke
				(width 0.1)
				(type default)
			)
			(layer "F.SilkS")
		)
		(fp_line
			(start 17.750536 -1.387348)
			(end 17.73809 -1.317752)
			(stroke
				(width 0.1)
				(type default)
			)
			(layer "F.SilkS")
		)
		(fp_line
			(start 17.757394 -4.971796)
			(end 16.818102 -4.071112)
			(stroke
				(width 0.1)
				(type default)
			)
			(layer "F.SilkS")
		)
		(fp_line
			(start 17.757394 -4.971796)
			(end 16.818102 -4.071112)
			(stroke
				(width 0.1)
				(type default)
			)
			(layer "F.SilkS")
		)
		(fp_line
			(start 17.762474 -1.456436)
			(end 17.750536 -1.387348)
			(stroke
				(width 0.1)
				(type default)
			)
			(layer "F.SilkS")
		)
		(fp_line
			(start 17.762474 -1.456436)
			(end 17.750536 -1.387348)
			(stroke
				(width 0.1)
				(type default)
			)
			(layer "F.SilkS")
		)
		(fp_line
			(start 17.774666 -1.525778)
			(end 17.762474 -1.456436)
			(stroke
				(width 0.1)
				(type default)
			)
			(layer "F.SilkS")
		)
		(fp_line
			(start 17.774666 -1.525778)
			(end 17.762474 -1.456436)
			(stroke
				(width 0.1)
				(type default)
			)
			(layer "F.SilkS")
		)
		(fp_line
			(start 17.786858 -1.595374)
			(end 17.774666 -1.525778)
			(stroke
				(width 0.1)
				(type default)
			)
			(layer "F.SilkS")
		)
		(fp_line
			(start 17.786858 -1.595374)
			(end 17.774666 -1.525778)
			(stroke
				(width 0.1)
				(type default)
			)
			(layer "F.SilkS")
		)
		(fp_line
			(start 17.78762 -4.943348)
			(end 16.845788 -4.03987)
			(stroke
				(width 0.1)
				(type default)
			)
			(layer "F.SilkS")
		)
		(fp_line
			(start 17.78762 -4.943348)
			(end 16.845788 -4.03987)
			(stroke
				(width 0.1)
				(type default)
			)
			(layer "F.SilkS")
		)
		(fp_line
			(start 17.79905 -1.664716)
			(end 17.786858 -1.595374)
			(stroke
				(width 0.1)
				(type default)
			)
			(layer "F.SilkS")
		)
		(fp_line
			(start 17.79905 -1.664716)
			(end 17.786858 -1.595374)
			(stroke
				(width 0.1)
				(type default)
			)
			(layer "F.SilkS")
		)
		(fp_line
			(start 17.810988 -1.734058)
			(end 17.79905 -1.664716)
			(stroke
				(width 0.1)
				(type default)
			)
			(layer "F.SilkS")
		)
		(fp_line
			(start 17.810988 -1.734058)
			(end 17.79905 -1.664716)
			(stroke
				(width 0.1)
				(type default)
			)
			(layer "F.SilkS")
		)
		(fp_line
			(start 17.813782 -4.910836)
			(end 16.87322 -4.008882)
			(stroke
				(width 0.1)
				(type default)
			)
			(layer "F.SilkS")
		)
		(fp_line
			(start 17.813782 -4.910836)
			(end 16.87322 -4.008882)
			(stroke
				(width 0.1)
				(type default)
			)
			(layer "F.SilkS")
		)
		(fp_line
			(start 17.823434 -1.8034)
			(end 17.810988 -1.734058)
			(stroke
				(width 0.1)
				(type default)
			)
			(layer "F.SilkS")
		)
		(fp_line
			(start 17.823434 -1.8034)
			(end 17.810988 -1.734058)
			(stroke
				(width 0.1)
				(type default)
			)
			(layer "F.SilkS")
		)
		(fp_line
			(start 17.835626 -1.872742)
			(end 17.823434 -1.8034)
			(stroke
				(width 0.1)
				(type default)
			)
			(layer "F.SilkS")
		)
		(fp_line
			(start 17.835626 -1.872742)
			(end 17.823434 -1.8034)
			(stroke
				(width 0.1)
				(type default)
			)
			(layer "F.SilkS")
		)
		(fp_line
			(start 17.839944 -4.878324)
			(end 16.89735 -3.97383)
			(stroke
				(width 0.1)
				(type default)
			)
			(layer "F.SilkS")
		)
		(fp_line
			(start 17.839944 -4.878324)
			(end 16.89735 -3.97383)
			(stroke
				(width 0.1)
				(type default)
			)
			(layer "F.SilkS")
		)
		(fp_line
			(start 17.847564 -1.942338)
			(end 17.835626 -1.872742)
			(stroke
				(width 0.1)
				(type default)
			)
			(layer "F.SilkS")
		)
		(fp_line
			(start 17.847564 -1.942338)
			(end 17.835626 -1.872742)
			(stroke
				(width 0.1)
				(type default)
			)
			(layer "F.SilkS")
		)
		(fp_line
			(start 17.86001 -2.011426)
			(end 17.847564 -1.942338)
			(stroke
				(width 0.1)
				(type default)
			)
			(layer "F.SilkS")
		)
		(fp_line
			(start 17.86001 -2.011426)
			(end 17.847564 -1.942338)
			(stroke
				(width 0.1)
				(type default)
			)
			(layer "F.SilkS")
		)
		(fp_line
			(start 17.866106 -4.845558)
			(end 16.915384 -3.93319)
			(stroke
				(width 0.1)
				(type default)
			)
			(layer "F.SilkS")
		)
		(fp_line
			(start 17.866106 -4.845558)
			(end 16.915384 -3.93319)
			(stroke
				(width 0.1)
				(type default)
			)
			(layer "F.SilkS")
		)
		(fp_line
			(start 17.871948 -2.081022)
			(end 17.86001 -2.011426)
			(stroke
				(width 0.1)
				(type default)
			)
			(layer "F.SilkS")
		)
		(fp_line
			(start 17.871948 -2.081022)
			(end 17.86001 -2.011426)
			(stroke
				(width 0.1)
				(type default)
			)
			(layer "F.SilkS")
		)
		(fp_line
			(start 17.88414 -2.150364)
			(end 17.871948 -2.081022)
			(stroke
				(width 0.1)
				(type default)
			)
			(layer "F.SilkS")
		)
		(fp_line
			(start 17.88414 -2.150364)
			(end 17.871948 -2.081022)
			(stroke
				(width 0.1)
				(type default)
			)
			(layer "F.SilkS")
		)
		(fp_line
			(start 17.892268 -4.813046)
			(end 16.93291 -3.89255)
			(stroke
				(width 0.1)
				(type default)
			)
			(layer "F.SilkS")
		)
		(fp_line
			(start 17.892268 -4.813046)
			(end 16.93291 -3.89255)
			(stroke
				(width 0.1)
				(type default)
			)
			(layer "F.SilkS")
		)
		(fp_line
			(start 17.896586 -2.21996)
			(end 17.88414 -2.150364)
			(stroke
				(width 0.1)
				(type default)
			)
			(layer "F.SilkS")
		)
		(fp_line
			(start 17.896586 -2.21996)
			(end 17.88414 -2.150364)
			(stroke
				(width 0.1)
				(type default)
			)
			(layer "F.SilkS")
		)
		(fp_line
			(start 17.908524 -2.289048)
			(end 17.896586 -2.21996)
			(stroke
				(width 0.1)
				(type default)
			)
			(layer "F.SilkS")
		)
		(fp_line
			(start 17.908524 -2.289048)
			(end 17.896586 -2.21996)
			(stroke
				(width 0.1)
				(type default)
			)
			(layer "F.SilkS")
		)
		(fp_line
			(start 17.91843 -4.780534)
			(end 16.949674 -3.850894)
			(stroke
				(width 0.1)
				(type default)
			)
			(layer "F.SilkS")
		)
		(fp_line
			(start 17.91843 -4.780534)
			(end 16.949674 -3.850894)
			(stroke
				(width 0.1)
				(type default)
			)
			(layer "F.SilkS")
		)
		(fp_line
			(start 17.920716 -2.35839)
			(end 17.908524 -2.289048)
			(stroke
				(width 0.1)
				(type default)
			)
			(layer "F.SilkS")
		)
		(fp_line
			(start 17.920716 -2.35839)
			(end 17.908524 -2.289048)
			(stroke
				(width 0.1)
				(type default)
			)
			(layer "F.SilkS")
		)
		(fp_line
			(start 17.932908 -2.427732)
			(end 17.920716 -2.35839)
			(stroke
				(width 0.1)
				(type default)
			)
			(layer "F.SilkS")
		)
		(fp_line
			(start 17.932908 -2.427732)
			(end 17.920716 -2.35839)
			(stroke
				(width 0.1)
				(type default)
			)
			(layer "F.SilkS")
		)
		(fp_line
			(start 17.944846 -4.748022)
			(end 16.958056 -3.80111)
			(stroke
				(width 0.1)
				(type default)
			)
			(layer "F.SilkS")
		)
		(fp_line
			(start 17.944846 -4.748022)
			(end 16.958056 -3.80111)
			(stroke
				(width 0.1)
				(type default)
			)
			(layer "F.SilkS")
		)
		(fp_line
			(start 17.9451 -2.497328)
			(end 17.932908 -2.427732)
			(stroke
				(width 0.1)
				(type default)
			)
			(layer "F.SilkS")
		)
		(fp_line
			(start 17.9451 -2.497328)
			(end 17.932908 -2.427732)
			(stroke
				(width 0.1)
				(type default)
			)
			(layer "F.SilkS")
		)
		(fp_line
			(start 17.957038 -2.56667)
			(end 17.9451 -2.497328)
			(stroke
				(width 0.1)
				(type default)
			)
			(layer "F.SilkS")
		)
		(fp_line
			(start 17.957038 -2.56667)
			(end 17.9451 -2.497328)
			(stroke
				(width 0.1)
				(type default)
			)
			(layer "F.SilkS")
		)
		(fp_line
			(start 17.966182 -4.710176)
			(end 16.966438 -3.751326)
			(stroke
				(width 0.1)
				(type default)
			)
			(layer "F.SilkS")
		)
		(fp_line
			(start 17.966182 -4.710176)
			(end 16.966438 -3.751326)
			(stroke
				(width 0.1)
				(type default)
			)
			(layer "F.SilkS")
		)
		(fp_line
			(start 17.969484 -2.636012)
			(end 17.957038 -2.56667)
			(stroke
				(width 0.1)
				(type default)
			)
			(layer "F.SilkS")
		)
		(fp_line
			(start 17.969484 -2.636012)
			(end 17.957038 -2.56667)
			(stroke
				(width 0.1)
				(type default)
			)
			(layer "F.SilkS")
		)
		(fp_line
			(start 17.981676 -2.705608)
			(end 17.969484 -2.636012)
			(stroke
				(width 0.1)
				(type default)
			)
			(layer "F.SilkS")
		)
		(fp_line
			(start 17.981676 -2.705608)
			(end 17.969484 -2.636012)
			(stroke
				(width 0.1)
				(type default)
			)
			(layer "F.SilkS")
		)
		(fp_line
			(start 17.9832 -4.669282)
			(end 16.974566 -3.701542)
			(stroke
				(width 0.1)
				(type default)
			)
			(layer "F.SilkS")
		)
		(fp_line
			(start 17.9832 -4.669282)
			(end 16.974566 -3.701542)
			(stroke
				(width 0.1)
				(type default)
			)
			(layer "F.SilkS")
		)
		(fp_line
			(start 17.993614 -2.77495)
			(end 17.981676 -2.705608)
			(stroke
				(width 0.1)
				(type default)
			)
			(layer "F.SilkS")
		)
		(fp_line
			(start 17.993614 -2.77495)
			(end 17.981676 -2.705608)
			(stroke
				(width 0.1)
				(type default)
			)
			(layer "F.SilkS")
		)
		(fp_line
			(start 18.000472 -4.628388)
			(end 16.97736 -3.646424)
			(stroke
				(width 0.1)
				(type default)
			)
			(layer "F.SilkS")
		)
		(fp_line
			(start 18.000472 -4.628388)
			(end 16.97736 -3.646424)
			(stroke
				(width 0.1)
				(type default)
			)
			(layer "F.SilkS")
		)
		(fp_line
			(start 18.00606 -2.844292)
			(end 17.993614 -2.77495)
			(stroke
				(width 0.1)
				(type default)
			)
			(layer "F.SilkS")
		)
		(fp_line
			(start 18.00606 -2.844292)
			(end 17.993614 -2.77495)
			(stroke
				(width 0.1)
				(type default)
			)
			(layer "F.SilkS")
		)
		(fp_line
			(start 18.017998 -4.58724)
			(end 16.976598 -3.588258)
			(stroke
				(width 0.1)
				(type default)
			)
			(layer "F.SilkS")
		)
		(fp_line
			(start 18.017998 -4.58724)
			(end 16.976598 -3.588258)
			(stroke
				(width 0.1)
				(type default)
			)
			(layer "F.SilkS")
		)
		(fp_line
			(start 18.017998 -2.913634)
			(end 18.00606 -2.844292)
			(stroke
				(width 0.1)
				(type default)
			)
			(layer "F.SilkS")
		)
		(fp_line
			(start 18.017998 -2.913634)
			(end 18.00606 -2.844292)
			(stroke
				(width 0.1)
				(type default)
			)
			(layer "F.SilkS")
		)
		(fp_line
			(start 18.03019 -2.982976)
			(end 18.017998 -2.913634)
			(stroke
				(width 0.1)
				(type default)
			)
			(layer "F.SilkS")
		)
		(fp_line
			(start 18.03019 -2.982976)
			(end 18.017998 -2.913634)
			(stroke
				(width 0.1)
				(type default)
			)
			(layer "F.SilkS")
		)
		(fp_line
			(start 18.035778 -4.546346)
			(end 16.97609 -3.529838)
			(stroke
				(width 0.1)
				(type default)
			)
			(layer "F.SilkS")
		)
		(fp_line
			(start 18.035778 -4.546346)
			(end 16.97609 -3.529838)
			(stroke
				(width 0.1)
				(type default)
			)
			(layer "F.SilkS")
		)
		(fp_line
			(start 18.042636 -3.052572)
			(end 18.03019 -2.982976)
			(stroke
				(width 0.1)
				(type default)
			)
			(layer "F.SilkS")
		)
		(fp_line
			(start 18.042636 -3.052572)
			(end 18.03019 -2.982976)
			(stroke
				(width 0.1)
				(type default)
			)
			(layer "F.SilkS")
		)
		(fp_line
			(start 18.052796 -4.505198)
			(end 16.975582 -3.471672)
			(stroke
				(width 0.1)
				(type default)
			)
			(layer "F.SilkS")
		)
		(fp_line
			(start 18.052796 -4.505198)
			(end 16.975582 -3.471672)
			(stroke
				(width 0.1)
				(type default)
			)
			(layer "F.SilkS")
		)
		(fp_line
			(start 18.054574 -3.121914)
			(end 18.042636 -3.052572)
			(stroke
				(width 0.1)
				(type default)
			)
			(layer "F.SilkS")
		)
		(fp_line
			(start 18.054574 -3.121914)
			(end 18.042636 -3.052572)
			(stroke
				(width 0.1)
				(type default)
			)
			(layer "F.SilkS")
		)
		(fp_line
			(start 18.066766 -3.191002)
			(end 18.054574 -3.121914)
			(stroke
				(width 0.1)
				(type default)
			)
			(layer "F.SilkS")
		)
		(fp_line
			(start 18.066766 -3.191002)
			(end 18.054574 -3.121914)
			(stroke
				(width 0.1)
				(type default)
			)
			(layer "F.SilkS")
		)
		(fp_line
			(start 18.070068 -4.464304)
			(end 16.967708 -3.406648)
			(stroke
				(width 0.1)
				(type default)
			)
			(layer "F.SilkS")
		)
		(fp_line
			(start 18.070068 -4.464304)
			(end 16.967708 -3.406648)
			(stroke
				(width 0.1)
				(type default)
			)
			(layer "F.SilkS")
		)
		(fp_line
			(start 18.079212 -3.260598)
			(end 18.066766 -3.191002)
			(stroke
				(width 0.1)
				(type default)
			)
			(layer "F.SilkS")
		)
		(fp_line
			(start 18.079212 -3.260598)
			(end 18.066766 -3.191002)
			(stroke
				(width 0.1)
				(type default)
			)
			(layer "F.SilkS")
		)
		(fp_line
			(start 18.081752 -4.417314)
			(end 16.959326 -3.340608)
			(stroke
				(width 0.1)
				(type default)
			)
			(layer "F.SilkS")
		)
		(fp_line
			(start 18.081752 -4.417314)
			(end 16.959326 -3.340608)
			(stroke
				(width 0.1)
				(type default)
			)
			(layer "F.SilkS")
		)
		(fp_line
			(start 18.090388 -4.368038)
			(end 16.950436 -3.274568)
			(stroke
				(width 0.1)
				(type default)
			)
			(layer "F.SilkS")
		)
		(fp_line
			(start 18.090388 -4.368038)
			(end 16.950436 -3.274568)
			(stroke
				(width 0.1)
				(type default)
			)
			(layer "F.SilkS")
		)
		(fp_line
			(start 18.099532 -4.318762)
			(end 16.942308 -3.208782)
			(stroke
				(width 0.1)
				(type default)
			)
			(layer "F.SilkS")
		)
		(fp_line
			(start 18.099532 -4.318762)
			(end 16.942308 -3.208782)
			(stroke
				(width 0.1)
				(type default)
			)
			(layer "F.SilkS")
		)
		(fp_line
			(start 18.107914 -4.26974)
			(end 16.930624 -3.139694)
			(stroke
				(width 0.1)
				(type default)
			)
			(layer "F.SilkS")
		)
		(fp_line
			(start 18.107914 -4.26974)
			(end 16.930624 -3.139694)
			(stroke
				(width 0.1)
				(type default)
			)
			(layer "F.SilkS")
		)
		(fp_line
			(start 18.137632 -3.836416)
			(end 16.83258 -2.58445)
			(stroke
				(width 0.1)
				(type default)
			)
			(layer "F.SilkS")
		)
		(fp_line
			(start 18.137632 -3.836416)
			(end 16.83258 -2.58445)
			(stroke
				(width 0.1)
				(type default)
			)
			(layer "F.SilkS")
		)
		(fp_line
			(start 18.736818 -4.109466)
			(end 18.783554 -4.109466)
			(stroke
				(width 0.1)
				(type default)
			)
			(layer "F.SilkS")
		)
		(fp_line
			(start 18.736818 -4.109466)
			(end 18.783554 -4.109466)
			(stroke
				(width 0.1)
				(type default)
			)
			(layer "F.SilkS")
		)
		(fp_line
			(start 18.739612 -4.12496)
			(end 18.736818 -4.109466)
			(stroke
				(width 0.1)
				(type default)
			)
			(layer "F.SilkS")
		)
		(fp_line
			(start 18.739612 -4.12496)
			(end 18.736818 -4.109466)
			(stroke
				(width 0.1)
				(type default)
			)
			(layer "F.SilkS")
		)
		(fp_line
			(start 18.739612 -4.12496)
			(end 20.959318 -6.254496)
			(stroke
				(width 0.1)
				(type default)
			)
			(layer "F.SilkS")
		)
		(fp_line
			(start 18.739612 -4.12496)
			(end 20.959318 -6.254496)
			(stroke
				(width 0.1)
				(type default)
			)
			(layer "F.SilkS")
		)
		(fp_line
			(start 18.75155 -4.194556)
			(end 18.739612 -4.12496)
			(stroke
				(width 0.1)
				(type default)
			)
			(layer "F.SilkS")
		)
		(fp_line
			(start 18.75155 -4.194556)
			(end 18.739612 -4.12496)
			(stroke
				(width 0.1)
				(type default)
			)
			(layer "F.SilkS")
		)
		(fp_line
			(start 18.763996 -4.263898)
			(end 18.75155 -4.194556)
			(stroke
				(width 0.1)
				(type default)
			)
			(layer "F.SilkS")
		)
		(fp_line
			(start 18.763996 -4.263898)
			(end 18.75155 -4.194556)
			(stroke
				(width 0.1)
				(type default)
			)
			(layer "F.SilkS")
		)
		(fp_line
			(start 18.775934 -4.33324)
			(end 18.763996 -4.263898)
			(stroke
				(width 0.1)
				(type default)
			)
			(layer "F.SilkS")
		)
		(fp_line
			(start 18.775934 -4.33324)
			(end 18.763996 -4.263898)
			(stroke
				(width 0.1)
				(type default)
			)
			(layer "F.SilkS")
		)
		(fp_line
			(start 18.775934 -4.33324)
			(end 18.78838 -4.402836)
			(stroke
				(width 0.1)
				(type default)
			)
			(layer "F.SilkS")
		)
		(fp_line
			(start 18.775934 -4.33324)
			(end 18.78838 -4.402836)
			(stroke
				(width 0.1)
				(type default)
			)
			(layer "F.SilkS")
		)
		(fp_line
			(start 18.783554 -4.109466)
			(end 18.843498 -4.109466)
			(stroke
				(width 0.1)
				(type default)
			)
			(layer "F.SilkS")
		)
		(fp_line
			(start 18.783554 -4.109466)
			(end 18.843498 -4.109466)
			(stroke
				(width 0.1)
				(type default)
			)
			(layer "F.SilkS")
		)
		(fp_line
			(start 18.783554 -4.109466)
			(end 20.947126 -6.1849)
			(stroke
				(width 0.1)
				(type default)
			)
			(layer "F.SilkS")
		)
		(fp_line
			(start 18.783554 -4.109466)
			(end 20.947126 -6.1849)
			(stroke
				(width 0.1)
				(type default)
			)
			(layer "F.SilkS")
		)
		(fp_line
			(start 18.78838 -4.402836)
			(end 18.800572 -4.472178)
			(stroke
				(width 0.1)
				(type default)
			)
			(layer "F.SilkS")
		)
		(fp_line
			(start 18.78838 -4.402836)
			(end 18.800572 -4.472178)
			(stroke
				(width 0.1)
				(type default)
			)
			(layer "F.SilkS")
		)
		(fp_line
			(start 18.78838 -4.402836)
			(end 19.58975 -5.171694)
			(stroke
				(width 0.1)
				(type default)
			)
			(layer "F.SilkS")
		)
		(fp_line
			(start 18.78838 -4.402836)
			(end 19.58975 -5.171694)
			(stroke
				(width 0.1)
				(type default)
			)
			(layer "F.SilkS")
		)
		(fp_line
			(start 18.800572 -4.472178)
			(end 18.81251 -4.54152)
			(stroke
				(width 0.1)
				(type default)
			)
			(layer "F.SilkS")
		)
		(fp_line
			(start 18.800572 -4.472178)
			(end 18.81251 -4.54152)
			(stroke
				(width 0.1)
				(type default)
			)
			(layer "F.SilkS")
		)
		(fp_line
			(start 18.800572 -4.472178)
			(end 19.529806 -5.171694)
			(stroke
				(width 0.1)
				(type default)
			)
			(layer "F.SilkS")
		)
		(fp_line
			(start 18.800572 -4.472178)
			(end 19.529806 -5.171694)
			(stroke
				(width 0.1)
				(type default)
			)
			(layer "F.SilkS")
		)
		(fp_line
			(start 18.81251 -4.54152)
			(end 18.824956 -4.610862)
			(stroke
				(width 0.1)
				(type default)
			)
			(layer "F.SilkS")
		)
		(fp_line
			(start 18.81251 -4.54152)
			(end 18.824956 -4.610862)
			(stroke
				(width 0.1)
				(type default)
			)
			(layer "F.SilkS")
		)
		(fp_line
			(start 18.81251 -4.54152)
			(end 19.469608 -5.171694)
			(stroke
				(width 0.1)
				(type default)
			)
			(layer "F.SilkS")
		)
		(fp_line
			(start 18.81251 -4.54152)
			(end 19.469608 -5.171694)
			(stroke
				(width 0.1)
				(type default)
			)
			(layer "F.SilkS")
		)
		(fp_line
			(start 18.824956 -4.610862)
			(end 18.836894 -4.680458)
			(stroke
				(width 0.1)
				(type default)
			)
			(layer "F.SilkS")
		)
		(fp_line
			(start 18.824956 -4.610862)
			(end 18.836894 -4.680458)
			(stroke
				(width 0.1)
				(type default)
			)
			(layer "F.SilkS")
		)
		(fp_line
			(start 18.824956 -4.610862)
			(end 19.409664 -5.171694)
			(stroke
				(width 0.1)
				(type default)
			)
			(layer "F.SilkS")
		)
		(fp_line
			(start 18.824956 -4.610862)
			(end 19.409664 -5.171694)
			(stroke
				(width 0.1)
				(type default)
			)
			(layer "F.SilkS")
		)
		(fp_line
			(start 18.836894 -4.680458)
			(end 18.84934 -4.7498)
			(stroke
				(width 0.1)
				(type default)
			)
			(layer "F.SilkS")
		)
		(fp_line
			(start 18.836894 -4.680458)
			(end 18.84934 -4.7498)
			(stroke
				(width 0.1)
				(type default)
			)
			(layer "F.SilkS")
		)
		(fp_line
			(start 18.836894 -4.680458)
			(end 19.349212 -5.171694)
			(stroke
				(width 0.1)
				(type default)
			)
			(layer "F.SilkS")
		)
		(fp_line
			(start 18.836894 -4.680458)
			(end 19.349212 -5.171694)
			(stroke
				(width 0.1)
				(type default)
			)
			(layer "F.SilkS")
		)
		(fp_line
			(start 18.843498 -4.109466)
			(end 18.90395 -4.109466)
			(stroke
				(width 0.1)
				(type default)
			)
			(layer "F.SilkS")
		)
		(fp_line
			(start 18.843498 -4.109466)
			(end 18.90395 -4.109466)
			(stroke
				(width 0.1)
				(type default)
			)
			(layer "F.SilkS")
		)
		(fp_line
			(start 18.843498 -4.109466)
			(end 20.93468 -6.115558)
			(stroke
				(width 0.1)
				(type default)
			)
			(layer "F.SilkS")
		)
		(fp_line
			(start 18.843498 -4.109466)
			(end 20.93468 -6.115558)
			(stroke
				(width 0.1)
				(type default)
			)
			(layer "F.SilkS")
		)
		(fp_line
			(start 18.84934 -4.7498)
			(end 18.861532 -4.819142)
			(stroke
				(width 0.1)
				(type default)
			)
			(layer "F.SilkS")
		)
		(fp_line
			(start 18.84934 -4.7498)
			(end 18.861532 -4.819142)
			(stroke
				(width 0.1)
				(type default)
			)
			(layer "F.SilkS")
		)
		(fp_line
			(start 18.84934 -4.7498)
			(end 19.289014 -5.171694)
			(stroke
				(width 0.1)
				(type default)
			)
			(layer "F.SilkS")
		)
		(fp_line
			(start 18.84934 -4.7498)
			(end 19.289014 -5.171694)
			(stroke
				(width 0.1)
				(type default)
			)
			(layer "F.SilkS")
		)
		(fp_line
			(start 18.861532 -4.819142)
			(end 18.873978 -4.888484)
			(stroke
				(width 0.1)
				(type default)
			)
			(layer "F.SilkS")
		)
		(fp_line
			(start 18.861532 -4.819142)
			(end 18.873978 -4.888484)
			(stroke
				(width 0.1)
				(type default)
			)
			(layer "F.SilkS")
		)
		(fp_line
			(start 18.861532 -4.819142)
			(end 19.22907 -5.171694)
			(stroke
				(width 0.1)
				(type default)
			)
			(layer "F.SilkS")
		)
		(fp_line
			(start 18.861532 -4.819142)
			(end 19.22907 -5.171694)
			(stroke
				(width 0.1)
				(type default)
			)
			(layer "F.SilkS")
		)
		(fp_line
			(start 18.873978 -4.888484)
			(end 19.168872 -5.171694)
			(stroke
				(width 0.1)
				(type default)
			)
			(layer "F.SilkS")
		)
		(fp_line
			(start 18.873978 -4.888484)
			(end 19.168872 -5.171694)
			(stroke
				(width 0.1)
				(type default)
			)
			(layer "F.SilkS")
		)
		(fp_line
			(start 18.885916 -4.95808)
			(end 18.873978 -4.888484)
			(stroke
				(width 0.1)
				(type default)
			)
			(layer "F.SilkS")
		)
		(fp_line
			(start 18.885916 -4.95808)
			(end 18.873978 -4.888484)
			(stroke
				(width 0.1)
				(type default)
			)
			(layer "F.SilkS")
		)
		(fp_line
			(start 18.898108 -5.027422)
			(end 18.885916 -4.95808)
			(stroke
				(width 0.1)
				(type default)
			)
			(layer "F.SilkS")
		)
		(fp_line
			(start 18.898108 -5.027422)
			(end 18.885916 -4.95808)
			(stroke
				(width 0.1)
				(type default)
			)
			(layer "F.SilkS")
		)
		(fp_line
			(start 18.898108 -5.027422)
			(end 18.9103 -5.097018)
			(stroke
				(width 0.1)
				(type default)
			)
			(layer "F.SilkS")
		)
		(fp_line
			(start 18.898108 -5.027422)
			(end 18.9103 -5.097018)
			(stroke
				(width 0.1)
				(type default)
			)
			(layer "F.SilkS")
		)
		(fp_line
			(start 18.898108 -5.027422)
			(end 19.048476 -5.171694)
			(stroke
				(width 0.1)
				(type default)
			)
			(layer "F.SilkS")
		)
		(fp_line
			(start 18.898108 -5.027422)
			(end 19.048476 -5.171694)
			(stroke
				(width 0.1)
				(type default)
			)
			(layer "F.SilkS")
		)
		(fp_line
			(start 18.90395 -4.109466)
			(end 18.964148 -4.109466)
			(stroke
				(width 0.1)
				(type default)
			)
			(layer "F.SilkS")
		)
		(fp_line
			(start 18.90395 -4.109466)
			(end 18.964148 -4.109466)
			(stroke
				(width 0.1)
				(type default)
			)
			(layer "F.SilkS")
		)
		(fp_line
			(start 18.90395 -4.109466)
			(end 20.922742 -6.04647)
			(stroke
				(width 0.1)
				(type default)
			)
			(layer "F.SilkS")
		)
		(fp_line
			(start 18.90395 -4.109466)
			(end 20.922742 -6.04647)
			(stroke
				(width 0.1)
				(type default)
			)
			(layer "F.SilkS")
		)
		(fp_line
			(start 18.9103 -5.097018)
			(end 18.922492 -5.166106)
			(stroke
				(width 0.1)
				(type default)
			)
			(layer "F.SilkS")
		)
		(fp_line
			(start 18.9103 -5.097018)
			(end 18.922492 -5.166106)
			(stroke
				(width 0.1)
				(type default)
			)
			(layer "F.SilkS")
		)
		(fp_line
			(start 18.9103 -5.097018)
			(end 18.988278 -5.171694)
			(stroke
				(width 0.1)
				(type default)
			)
			(layer "F.SilkS")
		)
		(fp_line
			(start 18.9103 -5.097018)
			(end 18.988278 -5.171694)
			(stroke
				(width 0.1)
				(type default)
			)
			(layer "F.SilkS")
		)
		(fp_line
			(start 18.922492 -5.166106)
			(end 18.923508 -5.171694)
			(stroke
				(width 0.1)
				(type default)
			)
			(layer "F.SilkS")
		)
		(fp_line
			(start 18.922492 -5.166106)
			(end 18.923508 -5.171694)
			(stroke
				(width 0.1)
				(type default)
			)
			(layer "F.SilkS")
		)
		(fp_line
			(start 18.922492 -5.166106)
			(end 18.928334 -5.171694)
			(stroke
				(width 0.1)
				(type default)
			)
			(layer "F.SilkS")
		)
		(fp_line
			(start 18.922492 -5.166106)
			(end 18.928334 -5.171694)
			(stroke
				(width 0.1)
				(type default)
			)
			(layer "F.SilkS")
		)
		(fp_line
			(start 18.923508 -5.171694)
			(end 18.928334 -5.171694)
			(stroke
				(width 0.1)
				(type default)
			)
			(layer "F.SilkS")
		)
		(fp_line
			(start 18.923508 -5.171694)
			(end 18.928334 -5.171694)
			(stroke
				(width 0.1)
				(type default)
			)
			(layer "F.SilkS")
		)
		(fp_line
			(start 18.964148 -4.109466)
			(end 19.024092 -4.109466)
			(stroke
				(width 0.1)
				(type default)
			)
			(layer "F.SilkS")
		)
		(fp_line
			(start 18.964148 -4.109466)
			(end 19.024092 -4.109466)
			(stroke
				(width 0.1)
				(type default)
			)
			(layer "F.SilkS")
		)
		(fp_line
			(start 18.964148 -4.109466)
			(end 20.91055 -5.976874)
			(stroke
				(width 0.1)
				(type default)
			)
			(layer "F.SilkS")
		)
		(fp_line
			(start 18.964148 -4.109466)
			(end 20.91055 -5.976874)
			(stroke
				(width 0.1)
				(type default)
			)
			(layer "F.SilkS")
		)
		(fp_line
			(start 18.988278 -5.171694)
			(end 18.928334 -5.171694)
			(stroke
				(width 0.1)
				(type default)
			)
			(layer "F.SilkS")
		)
		(fp_line
			(start 18.988278 -5.171694)
			(end 18.928334 -5.171694)
			(stroke
				(width 0.1)
				(type default)
			)
			(layer "F.SilkS")
		)
		(fp_line
			(start 19.024092 -4.109466)
			(end 19.08429 -4.109466)
			(stroke
				(width 0.1)
				(type default)
			)
			(layer "F.SilkS")
		)
		(fp_line
			(start 19.024092 -4.109466)
			(end 19.08429 -4.109466)
			(stroke
				(width 0.1)
				(type default)
			)
			(layer "F.SilkS")
		)
		(fp_line
			(start 19.024092 -4.109466)
			(end 20.898104 -5.907278)
			(stroke
				(width 0.1)
				(type default)
			)
			(layer "F.SilkS")
		)
		(fp_line
			(start 19.024092 -4.109466)
			(end 20.898104 -5.907278)
			(stroke
				(width 0.1)
				(type default)
			)
			(layer "F.SilkS")
		)
		(fp_line
			(start 19.048476 -5.171694)
			(end 18.988278 -5.171694)
			(stroke
				(width 0.1)
				(type default)
			)
			(layer "F.SilkS")
		)
		(fp_line
			(start 19.048476 -5.171694)
			(end 18.988278 -5.171694)
			(stroke
				(width 0.1)
				(type default)
			)
			(layer "F.SilkS")
		)
		(fp_line
			(start 19.048476 -5.171694)
			(end 19.10842 -5.171694)
			(stroke
				(width 0.1)
				(type default)
			)
			(layer "F.SilkS")
		)
		(fp_line
			(start 19.048476 -5.171694)
			(end 19.10842 -5.171694)
			(stroke
				(width 0.1)
				(type default)
			)
			(layer "F.SilkS")
		)
		(fp_line
			(start 19.074638 -1.79197)
			(end 20.399248 -3.062478)
			(stroke
				(width 0.1)
				(type default)
			)
			(layer "F.SilkS")
		)
		(fp_line
			(start 19.074638 -1.79197)
			(end 20.399248 -3.062478)
			(stroke
				(width 0.1)
				(type default)
			)
			(layer "F.SilkS")
		)
		(fp_line
			(start 19.077178 -1.851914)
			(end 20.41144 -3.13182)
			(stroke
				(width 0.1)
				(type default)
			)
			(layer "F.SilkS")
		)
		(fp_line
			(start 19.077178 -1.851914)
			(end 20.41144 -3.13182)
			(stroke
				(width 0.1)
				(type default)
			)
			(layer "F.SilkS")
		)
		(fp_line
			(start 19.078448 -1.737868)
			(end 20.38731 -2.99339)
			(stroke
				(width 0.1)
				(type default)
			)
			(layer "F.SilkS")
		)
		(fp_line
			(start 19.078448 -1.737868)
			(end 20.38731 -2.99339)
			(stroke
				(width 0.1)
				(type default)
			)
			(layer "F.SilkS")
		)
		(fp_line
			(start 19.082258 -1.683512)
			(end 20.374864 -2.923794)
			(stroke
				(width 0.1)
				(type default)
			)
			(layer "F.SilkS")
		)
		(fp_line
			(start 19.082258 -1.683512)
			(end 20.374864 -2.923794)
			(stroke
				(width 0.1)
				(type default)
			)
			(layer "F.SilkS")
		)
		(fp_line
			(start 19.083274 -1.915668)
			(end 20.423886 -3.201416)
			(stroke
				(width 0.1)
				(type default)
			)
			(layer "F.SilkS")
		)
		(fp_line
			(start 19.083274 -1.915668)
			(end 20.423886 -3.201416)
			(stroke
				(width 0.1)
				(type default)
			)
			(layer "F.SilkS")
		)
		(fp_line
			(start 19.08429 -4.109466)
			(end 19.144234 -4.109466)
			(stroke
				(width 0.1)
				(type default)
			)
			(layer "F.SilkS")
		)
		(fp_line
			(start 19.08429 -4.109466)
			(end 19.144234 -4.109466)
			(stroke
				(width 0.1)
				(type default)
			)
			(layer "F.SilkS")
		)
		(fp_line
			(start 19.08429 -4.109466)
			(end 20.886166 -5.837936)
			(stroke
				(width 0.1)
				(type default)
			)
			(layer "F.SilkS")
		)
		(fp_line
			(start 19.08429 -4.109466)
			(end 20.886166 -5.837936)
			(stroke
				(width 0.1)
				(type default)
			)
			(layer "F.SilkS")
		)
		(fp_line
			(start 19.086068 -1.62941)
			(end 20.362926 -2.854198)
			(stroke
				(width 0.1)
				(type default)
			)
			(layer "F.SilkS")
		)
		(fp_line
			(start 19.086068 -1.62941)
			(end 20.362926 -2.854198)
			(stroke
				(width 0.1)
				(type default)
			)
			(layer "F.SilkS")
		)
		(fp_line
			(start 19.089624 -1.575308)
			(end 20.35048 -2.784856)
			(stroke
				(width 0.1)
				(type default)
			)
			(layer "F.SilkS")
		)
		(fp_line
			(start 19.089624 -1.575308)
			(end 20.35048 -2.784856)
			(stroke
				(width 0.1)
				(type default)
			)
			(layer "F.SilkS")
		)
		(fp_line
			(start 19.089878 -1.979676)
			(end 20.435824 -3.270758)
			(stroke
				(width 0.1)
				(type default)
			)
			(layer "F.SilkS")
		)
		(fp_line
			(start 19.089878 -1.979676)
			(end 20.435824 -3.270758)
			(stroke
				(width 0.1)
				(type default)
			)
			(layer "F.SilkS")
		)
		(fp_line
			(start 19.095974 -2.043176)
			(end 20.44827 -3.340354)
			(stroke
				(width 0.1)
				(type default)
			)
			(layer "F.SilkS")
		)
		(fp_line
			(start 19.095974 -2.043176)
			(end 20.44827 -3.340354)
			(stroke
				(width 0.1)
				(type default)
			)
			(layer "F.SilkS")
		)
		(fp_line
			(start 19.100292 -1.528064)
			(end 20.338288 -2.715768)
			(stroke
				(width 0.1)
				(type default)
			)
			(layer "F.SilkS")
		)
		(fp_line
			(start 19.100292 -1.528064)
			(end 20.338288 -2.715768)
			(stroke
				(width 0.1)
				(type default)
			)
			(layer "F.SilkS")
		)
		(fp_line
			(start 19.10461 -2.108962)
			(end 20.460462 -3.409442)
			(stroke
				(width 0.1)
				(type default)
			)
			(layer "F.SilkS")
		)
		(fp_line
			(start 19.10461 -2.108962)
			(end 20.460462 -3.409442)
			(stroke
				(width 0.1)
				(type default)
			)
			(layer "F.SilkS")
		)
		(fp_line
			(start 19.10842 -5.171694)
			(end 18.885916 -4.95808)
			(stroke
				(width 0.1)
				(type default)
			)
			(layer "F.SilkS")
		)
		(fp_line
			(start 19.10842 -5.171694)
			(end 18.885916 -4.95808)
			(stroke
				(width 0.1)
				(type default)
			)
			(layer "F.SilkS")
		)
		(fp_line
			(start 19.10842 -5.171694)
			(end 19.168872 -5.171694)
			(stroke
				(width 0.1)
				(type default)
			)
			(layer "F.SilkS")
		)
		(fp_line
			(start 19.10842 -5.171694)
			(end 19.168872 -5.171694)
			(stroke
				(width 0.1)
				(type default)
			)
			(layer "F.SilkS")
		)
		(fp_line
			(start 19.112738 -1.48209)
			(end 20.32635 -2.646172)
			(stroke
				(width 0.1)
				(type default)
			)
			(layer "F.SilkS")
		)
		(fp_line
			(start 19.112738 -1.48209)
			(end 20.32635 -2.646172)
			(stroke
				(width 0.1)
				(type default)
			)
			(layer "F.SilkS")
		)
		(fp_line
			(start 19.116802 -2.178304)
			(end 19.10461 -2.108962)
			(stroke
				(width 0.1)
				(type default)
			)
			(layer "F.SilkS")
		)
		(fp_line
			(start 19.116802 -2.178304)
			(end 19.10461 -2.108962)
			(stroke
				(width 0.1)
				(type default)
			)
			(layer "F.SilkS")
		)
		(fp_line
			(start 19.116802 -2.178304)
			(end 20.4724 -3.479038)
			(stroke
				(width 0.1)
				(type default)
			)
			(layer "F.SilkS")
		)
		(fp_line
			(start 19.116802 -2.178304)
			(end 20.4724 -3.479038)
			(stroke
				(width 0.1)
				(type default)
			)
			(layer "F.SilkS")
		)
		(fp_line
			(start 19.12493 -1.436116)
			(end 20.313904 -2.576576)
			(stroke
				(width 0.1)
				(type default)
			)
			(layer "F.SilkS")
		)
		(fp_line
			(start 19.12493 -1.436116)
			(end 20.313904 -2.576576)
			(stroke
				(width 0.1)
				(type default)
			)
			(layer "F.SilkS")
		)
		(fp_line
			(start 19.12874 -2.2479)
			(end 19.116802 -2.178304)
			(stroke
				(width 0.1)
				(type default)
			)
			(layer "F.SilkS")
		)
		(fp_line
			(start 19.12874 -2.2479)
			(end 19.116802 -2.178304)
			(stroke
				(width 0.1)
				(type default)
			)
			(layer "F.SilkS")
		)
		(fp_line
			(start 19.12874 -2.2479)
			(end 19.141186 -2.317242)
			(stroke
				(width 0.1)
				(type default)
			)
			(layer "F.SilkS")
		)
		(fp_line
			(start 19.12874 -2.2479)
			(end 19.141186 -2.317242)
			(stroke
				(width 0.1)
				(type default)
			)
			(layer "F.SilkS")
		)
		(fp_line
			(start 19.12874 -2.2479)
			(end 20.484846 -3.548634)
			(stroke
				(width 0.1)
				(type default)
			)
			(layer "F.SilkS")
		)
		(fp_line
			(start 19.12874 -2.2479)
			(end 20.484846 -3.548634)
			(stroke
				(width 0.1)
				(type default)
			)
			(layer "F.SilkS")
		)
		(fp_line
			(start 19.137376 -1.390396)
			(end 20.301966 -2.507234)
			(stroke
				(width 0.1)
				(type default)
			)
			(layer "F.SilkS")
		)
		(fp_line
			(start 19.137376 -1.390396)
			(end 20.301966 -2.507234)
			(stroke
				(width 0.1)
				(type default)
			)
			(layer "F.SilkS")
		)
		(fp_line
			(start 19.144234 -4.109466)
			(end 19.204686 -4.109466)
			(stroke
				(width 0.1)
				(type default)
			)
			(layer "F.SilkS")
		)
		(fp_line
			(start 19.144234 -4.109466)
			(end 19.204686 -4.109466)
			(stroke
				(width 0.1)
				(type default)
			)
			(layer "F.SilkS")
		)
		(fp_line
			(start 19.144234 -4.109466)
			(end 20.874228 -5.768594)
			(stroke
				(width 0.1)
				(type default)
			)
			(layer "F.SilkS")
		)
		(fp_line
			(start 19.144234 -4.109466)
			(end 20.874228 -5.768594)
			(stroke
				(width 0.1)
				(type default)
			)
			(layer "F.SilkS")
		)
		(fp_line
			(start 19.149822 -1.344676)
			(end 20.28952 -2.437892)
			(stroke
				(width 0.1)
				(type default)
			)
			(layer "F.SilkS")
		)
		(fp_line
			(start 19.149822 -1.344676)
			(end 20.28952 -2.437892)
			(stroke
				(width 0.1)
				(type default)
			)
			(layer "F.SilkS")
		)
		(fp_line
			(start 19.153378 -2.386584)
			(end 19.141186 -2.317242)
			(stroke
				(width 0.1)
				(type default)
			)
			(layer "F.SilkS")
		)
		(fp_line
			(start 19.153378 -2.386584)
			(end 19.141186 -2.317242)
			(stroke
				(width 0.1)
				(type default)
			)
			(layer "F.SilkS")
		)
		(fp_line
			(start 19.153378 -2.386584)
			(end 20.50923 -3.687064)
			(stroke
				(width 0.1)
				(type default)
			)
			(layer "F.SilkS")
		)
		(fp_line
			(start 19.153378 -2.386584)
			(end 20.50923 -3.687064)
			(stroke
				(width 0.1)
				(type default)
			)
			(layer "F.SilkS")
		)
		(fp_line
			(start 19.165316 -2.455926)
			(end 19.153378 -2.386584)
			(stroke
				(width 0.1)
				(type default)
			)
			(layer "F.SilkS")
		)
		(fp_line
			(start 19.165316 -2.455926)
			(end 19.153378 -2.386584)
			(stroke
				(width 0.1)
				(type default)
			)
			(layer "F.SilkS")
		)
		(fp_line
			(start 19.165316 -2.455926)
			(end 20.521422 -3.75666)
			(stroke
				(width 0.1)
				(type default)
			)
			(layer "F.SilkS")
		)
		(fp_line
			(start 19.165316 -2.455926)
			(end 20.521422 -3.75666)
			(stroke
				(width 0.1)
				(type default)
			)
			(layer "F.SilkS")
		)
		(fp_line
			(start 19.170142 -1.306322)
			(end 20.278344 -2.369312)
			(stroke
				(width 0.1)
				(type default)
			)
			(layer "F.SilkS")
		)
		(fp_line
			(start 19.170142 -1.306322)
			(end 20.278344 -2.369312)
			(stroke
				(width 0.1)
				(type default)
			)
			(layer "F.SilkS")
		)
		(fp_line
			(start 19.177762 -2.525522)
			(end 19.165316 -2.455926)
			(stroke
				(width 0.1)
				(type default)
			)
			(layer "F.SilkS")
		)
		(fp_line
			(start 19.177762 -2.525522)
			(end 19.165316 -2.455926)
			(stroke
				(width 0.1)
				(type default)
			)
			(layer "F.SilkS")
		)
		(fp_line
			(start 19.177762 -2.525522)
			(end 20.533614 -3.826256)
			(stroke
				(width 0.1)
				(type default)
			)
			(layer "F.SilkS")
		)
		(fp_line
			(start 19.177762 -2.525522)
			(end 20.533614 -3.826256)
			(stroke
				(width 0.1)
				(type default)
			)
			(layer "F.SilkS")
		)
		(fp_line
			(start 19.1897 -2.594864)
			(end 19.177762 -2.525522)
			(stroke
				(width 0.1)
				(type default)
			)
			(layer "F.SilkS")
		)
		(fp_line
			(start 19.1897 -2.594864)
			(end 19.177762 -2.525522)
			(stroke
				(width 0.1)
				(type default)
			)
			(layer "F.SilkS")
		)
		(fp_line
			(start 19.1897 -2.594864)
			(end 20.545806 -3.895344)
			(stroke
				(width 0.1)
				(type default)
			)
			(layer "F.SilkS")
		)
		(fp_line
			(start 19.1897 -2.594864)
			(end 20.545806 -3.895344)
			(stroke
				(width 0.1)
				(type default)
			)
			(layer "F.SilkS")
		)
		(fp_line
			(start 19.190462 -1.267968)
			(end 20.270216 -2.303526)
			(stroke
				(width 0.1)
				(type default)
			)
			(layer "F.SilkS")
		)
		(fp_line
			(start 19.190462 -1.267968)
			(end 20.270216 -2.303526)
			(stroke
				(width 0.1)
				(type default)
			)
			(layer "F.SilkS")
		)
		(fp_line
			(start 19.201892 -2.663952)
			(end 19.1897 -2.594864)
			(stroke
				(width 0.1)
				(type default)
			)
			(layer "F.SilkS")
		)
		(fp_line
			(start 19.201892 -2.663952)
			(end 19.1897 -2.594864)
			(stroke
				(width 0.1)
				(type default)
			)
			(layer "F.SilkS")
		)
		(fp_line
			(start 19.201892 -2.663952)
			(end 20.557744 -3.96494)
			(stroke
				(width 0.1)
				(type default)
			)
			(layer "F.SilkS")
		)
		(fp_line
			(start 19.201892 -2.663952)
			(end 20.557744 -3.96494)
			(stroke
				(width 0.1)
				(type default)
			)
			(layer "F.SilkS")
		)
		(fp_line
			(start 19.204686 -4.109466)
			(end 19.264884 -4.109466)
			(stroke
				(width 0.1)
				(type default)
			)
			(layer "F.SilkS")
		)
		(fp_line
			(start 19.204686 -4.109466)
			(end 19.264884 -4.109466)
			(stroke
				(width 0.1)
				(type default)
			)
			(layer "F.SilkS")
		)
		(fp_line
			(start 19.204686 -4.109466)
			(end 20.861782 -5.699252)
			(stroke
				(width 0.1)
				(type default)
			)
			(layer "F.SilkS")
		)
		(fp_line
			(start 19.204686 -4.109466)
			(end 20.861782 -5.699252)
			(stroke
				(width 0.1)
				(type default)
			)
			(layer "F.SilkS")
		)
		(fp_line
			(start 19.210782 -1.229868)
			(end 20.26285 -2.239264)
			(stroke
				(width 0.1)
				(type default)
			)
			(layer "F.SilkS")
		)
		(fp_line
			(start 19.210782 -1.229868)
			(end 20.26285 -2.239264)
			(stroke
				(width 0.1)
				(type default)
			)
			(layer "F.SilkS")
		)
		(fp_line
			(start 19.21383 -2.733548)
			(end 19.201892 -2.663952)
			(stroke
				(width 0.1)
				(type default)
			)
			(layer "F.SilkS")
		)
		(fp_line
			(start 19.21383 -2.733548)
			(end 19.201892 -2.663952)
			(stroke
				(width 0.1)
				(type default)
			)
			(layer "F.SilkS")
		)
		(fp_line
			(start 19.21383 -2.733548)
			(end 20.57019 -4.034282)
			(stroke
				(width 0.1)
				(type default)
			)
			(layer "F.SilkS")
		)
		(fp_line
			(start 19.21383 -2.733548)
			(end 20.57019 -4.034282)
			(stroke
				(width 0.1)
				(type default)
			)
			(layer "F.SilkS")
		)
		(fp_line
			(start 19.226276 -2.80289)
			(end 19.21383 -2.733548)
			(stroke
				(width 0.1)
				(type default)
			)
			(layer "F.SilkS")
		)
		(fp_line
			(start 19.226276 -2.80289)
			(end 19.21383 -2.733548)
			(stroke
				(width 0.1)
				(type default)
			)
			(layer "F.SilkS")
		)
		(fp_line
			(start 19.226276 -2.80289)
			(end 20.582382 -4.103878)
			(stroke
				(width 0.1)
				(type default)
			)
			(layer "F.SilkS")
		)
		(fp_line
			(start 19.226276 -2.80289)
			(end 20.582382 -4.103878)
			(stroke
				(width 0.1)
				(type default)
			)
			(layer "F.SilkS")
		)
		(fp_line
			(start 19.22907 -5.171694)
			(end 19.168872 -5.171694)
			(stroke
				(width 0.1)
				(type default)
			)
			(layer "F.SilkS")
		)
		(fp_line
			(start 19.22907 -5.171694)
			(end 19.168872 -5.171694)
			(stroke
				(width 0.1)
				(type default)
			)
			(layer "F.SilkS")
		)
		(fp_line
			(start 19.230848 -1.191514)
			(end 20.263358 -2.181606)
			(stroke
				(width 0.1)
				(type default)
			)
			(layer "F.SilkS")
		)
		(fp_line
			(start 19.230848 -1.191514)
			(end 20.263358 -2.181606)
			(stroke
				(width 0.1)
				(type default)
			)
			(layer "F.SilkS")
		)
		(fp_line
			(start 19.238468 -2.872232)
			(end 19.226276 -2.80289)
			(stroke
				(width 0.1)
				(type default)
			)
			(layer "F.SilkS")
		)
		(fp_line
			(start 19.238468 -2.872232)
			(end 19.226276 -2.80289)
			(stroke
				(width 0.1)
				(type default)
			)
			(layer "F.SilkS")
		)
		(fp_line
			(start 19.238468 -2.872232)
			(end 21.635466 -5.171694)
			(stroke
				(width 0.1)
				(type default)
			)
			(layer "F.SilkS")
		)
		(fp_line
			(start 19.238468 -2.872232)
			(end 21.635466 -5.171694)
			(stroke
				(width 0.1)
				(type default)
			)
			(layer "F.SilkS")
		)
		(fp_line
			(start 19.250406 -2.941574)
			(end 19.238468 -2.872232)
			(stroke
				(width 0.1)
				(type default)
			)
			(layer "F.SilkS")
		)
		(fp_line
			(start 19.250406 -2.941574)
			(end 19.238468 -2.872232)
			(stroke
				(width 0.1)
				(type default)
			)
			(layer "F.SilkS")
		)
		(fp_line
			(start 19.25193 -1.153922)
			(end 20.265136 -2.125726)
			(stroke
				(width 0.1)
				(type default)
			)
			(layer "F.SilkS")
		)
		(fp_line
			(start 19.25193 -1.153922)
			(end 20.265136 -2.125726)
			(stroke
				(width 0.1)
				(type default)
			)
			(layer "F.SilkS")
		)
		(fp_line
			(start 19.262852 -3.01117)
			(end 19.250406 -2.941574)
			(stroke
				(width 0.1)
				(type default)
			)
			(layer "F.SilkS")
		)
		(fp_line
			(start 19.262852 -3.01117)
			(end 19.250406 -2.941574)
			(stroke
				(width 0.1)
				(type default)
			)
			(layer "F.SilkS")
		)
		(fp_line
			(start 19.264884 -4.109466)
			(end 19.324828 -4.109466)
			(stroke
				(width 0.1)
				(type default)
			)
			(layer "F.SilkS")
		)
		(fp_line
			(start 19.264884 -4.109466)
			(end 19.324828 -4.109466)
			(stroke
				(width 0.1)
				(type default)
			)
			(layer "F.SilkS")
		)
		(fp_line
			(start 19.264884 -4.109466)
			(end 20.84959 -5.629656)
			(stroke
				(width 0.1)
				(type default)
			)
			(layer "F.SilkS")
		)
		(fp_line
			(start 19.264884 -4.109466)
			(end 20.84959 -5.629656)
			(stroke
				(width 0.1)
				(type default)
			)
			(layer "F.SilkS")
		)
		(fp_line
			(start 19.27479 -3.080512)
			(end 19.262852 -3.01117)
			(stroke
				(width 0.1)
				(type default)
			)
			(layer "F.SilkS")
		)
		(fp_line
			(start 19.27479 -3.080512)
			(end 19.262852 -3.01117)
			(stroke
				(width 0.1)
				(type default)
			)
			(layer "F.SilkS")
		)
		(fp_line
			(start 19.279616 -1.122934)
			(end 20.274534 -2.077212)
			(stroke
				(width 0.1)
				(type default)
			)
			(layer "F.SilkS")
		)
		(fp_line
			(start 19.279616 -1.122934)
			(end 20.274534 -2.077212)
			(stroke
				(width 0.1)
				(type default)
			)
			(layer "F.SilkS")
		)
		(fp_line
			(start 19.286982 -3.149854)
			(end 19.27479 -3.080512)
			(stroke
				(width 0.1)
				(type default)
			)
			(layer "F.SilkS")
		)
		(fp_line
			(start 19.286982 -3.149854)
			(end 19.27479 -3.080512)
			(stroke
				(width 0.1)
				(type default)
			)
			(layer "F.SilkS")
		)
		(fp_line
			(start 19.289014 -5.171694)
			(end 19.22907 -5.171694)
			(stroke
				(width 0.1)
				(type default)
			)
			(layer "F.SilkS")
		)
		(fp_line
			(start 19.289014 -5.171694)
			(end 19.22907 -5.171694)
			(stroke
				(width 0.1)
				(type default)
			)
			(layer "F.SilkS")
		)
		(fp_line
			(start 19.299428 -3.218942)
			(end 19.286982 -3.149854)
			(stroke
				(width 0.1)
				(type default)
			)
			(layer "F.SilkS")
		)
		(fp_line
			(start 19.299428 -3.218942)
			(end 19.286982 -3.149854)
			(stroke
				(width 0.1)
				(type default)
			)
			(layer "F.SilkS")
		)
		(fp_line
			(start 19.307556 -1.091946)
			(end 20.287488 -2.031746)
			(stroke
				(width 0.1)
				(type default)
			)
			(layer "F.SilkS")
		)
		(fp_line
			(start 19.307556 -1.091946)
			(end 20.287488 -2.031746)
			(stroke
				(width 0.1)
				(type default)
			)
			(layer "F.SilkS")
		)
		(fp_line
			(start 19.311366 -3.288538)
			(end 19.299428 -3.218942)
			(stroke
				(width 0.1)
				(type default)
			)
			(layer "F.SilkS")
		)
		(fp_line
			(start 19.311366 -3.288538)
			(end 19.299428 -3.218942)
			(stroke
				(width 0.1)
				(type default)
			)
			(layer "F.SilkS")
		)
		(fp_line
			(start 19.323558 -3.358134)
			(end 19.311366 -3.288538)
			(stroke
				(width 0.1)
				(type default)
			)
			(layer "F.SilkS")
		)
		(fp_line
			(start 19.323558 -3.358134)
			(end 19.311366 -3.288538)
			(stroke
				(width 0.1)
				(type default)
			)
			(layer "F.SilkS")
		)
		(fp_line
			(start 19.324828 -4.109466)
			(end 19.385026 -4.109466)
			(stroke
				(width 0.1)
				(type default)
			)
			(layer "F.SilkS")
		)
		(fp_line
			(start 19.324828 -4.109466)
			(end 19.385026 -4.109466)
			(stroke
				(width 0.1)
				(type default)
			)
			(layer "F.SilkS")
		)
		(fp_line
			(start 19.324828 -4.109466)
			(end 20.837144 -5.560314)
			(stroke
				(width 0.1)
				(type default)
			)
			(layer "F.SilkS")
		)
		(fp_line
			(start 19.324828 -4.109466)
			(end 20.837144 -5.560314)
			(stroke
				(width 0.1)
				(type default)
			)
			(layer "F.SilkS")
		)
		(fp_line
			(start 19.335496 -1.061212)
			(end 20.307046 -1.992884)
			(stroke
				(width 0.1)
				(type default)
			)
			(layer "F.SilkS")
		)
		(fp_line
			(start 19.335496 -1.061212)
			(end 20.307046 -1.992884)
			(stroke
				(width 0.1)
				(type default)
			)
			(layer "F.SilkS")
		)
		(fp_line
			(start 19.33575 -3.427476)
			(end 19.323558 -3.358134)
			(stroke
				(width 0.1)
				(type default)
			)
			(layer "F.SilkS")
		)
		(fp_line
			(start 19.33575 -3.427476)
			(end 19.323558 -3.358134)
			(stroke
				(width 0.1)
				(type default)
			)
			(layer "F.SilkS")
		)
		(fp_line
			(start 19.347942 -3.496564)
			(end 19.33575 -3.427476)
			(stroke
				(width 0.1)
				(type default)
			)
			(layer "F.SilkS")
		)
		(fp_line
			(start 19.347942 -3.496564)
			(end 19.33575 -3.427476)
			(stroke
				(width 0.1)
				(type default)
			)
			(layer "F.SilkS")
		)
		(fp_line
			(start 19.349212 -5.171694)
			(end 19.289014 -5.171694)
			(stroke
				(width 0.1)
				(type default)
			)
			(layer "F.SilkS")
		)
		(fp_line
			(start 19.349212 -5.171694)
			(end 19.289014 -5.171694)
			(stroke
				(width 0.1)
				(type default)
			)
			(layer "F.SilkS")
		)
		(fp_line
			(start 19.35988 -3.56616)
			(end 19.347942 -3.496564)
			(stroke
				(width 0.1)
				(type default)
			)
			(layer "F.SilkS")
		)
		(fp_line
			(start 19.35988 -3.56616)
			(end 19.347942 -3.496564)
			(stroke
				(width 0.1)
				(type default)
			)
			(layer "F.SilkS")
		)
		(fp_line
			(start 19.363436 -1.030224)
			(end 20.332446 -1.959356)
			(stroke
				(width 0.1)
				(type default)
			)
			(layer "F.SilkS")
		)
		(fp_line
			(start 19.363436 -1.030224)
			(end 20.332446 -1.959356)
			(stroke
				(width 0.1)
				(type default)
			)
			(layer "F.SilkS")
		)
		(fp_line
			(start 19.372326 -3.635502)
			(end 19.35988 -3.56616)
			(stroke
				(width 0.1)
				(type default)
			)
			(layer "F.SilkS")
		)
		(fp_line
			(start 19.372326 -3.635502)
			(end 19.35988 -3.56616)
			(stroke
				(width 0.1)
				(type default)
			)
			(layer "F.SilkS")
		)
		(fp_line
			(start 19.384518 -3.704844)
			(end 19.372326 -3.635502)
			(stroke
				(width 0.1)
				(type default)
			)
			(layer "F.SilkS")
		)
		(fp_line
			(start 19.384518 -3.704844)
			(end 19.372326 -3.635502)
			(stroke
				(width 0.1)
				(type default)
			)
			(layer "F.SilkS")
		)
		(fp_line
			(start 19.385026 -4.109466)
			(end 19.445478 -4.109466)
			(stroke
				(width 0.1)
				(type default)
			)
			(layer "F.SilkS")
		)
		(fp_line
			(start 19.385026 -4.109466)
			(end 19.445478 -4.109466)
			(stroke
				(width 0.1)
				(type default)
			)
			(layer "F.SilkS")
		)
		(fp_line
			(start 19.385026 -4.109466)
			(end 20.825206 -5.490972)
			(stroke
				(width 0.1)
				(type default)
			)
			(layer "F.SilkS")
		)
		(fp_line
			(start 19.385026 -4.109466)
			(end 20.825206 -5.490972)
			(stroke
				(width 0.1)
				(type default)
			)
			(layer "F.SilkS")
		)
		(fp_line
			(start 19.392646 -1.000252)
			(end 20.362164 -1.9304)
			(stroke
				(width 0.1)
				(type default)
			)
			(layer "F.SilkS")
		)
		(fp_line
			(start 19.392646 -1.000252)
			(end 20.362164 -1.9304)
			(stroke
				(width 0.1)
				(type default)
			)
			(layer "F.SilkS")
		)
		(fp_line
			(start 19.396456 -3.774186)
			(end 19.384518 -3.704844)
			(stroke
				(width 0.1)
				(type default)
			)
			(layer "F.SilkS")
		)
		(fp_line
			(start 19.396456 -3.774186)
			(end 19.384518 -3.704844)
			(stroke
				(width 0.1)
				(type default)
			)
			(layer "F.SilkS")
		)
		(fp_line
			(start 19.408902 -3.843528)
			(end 19.396456 -3.774186)
			(stroke
				(width 0.1)
				(type default)
			)
			(layer "F.SilkS")
		)
		(fp_line
			(start 19.408902 -3.843528)
			(end 19.396456 -3.774186)
			(stroke
				(width 0.1)
				(type default)
			)
			(layer "F.SilkS")
		)
		(fp_line
			(start 19.409664 -5.171694)
			(end 19.349212 -5.171694)
			(stroke
				(width 0.1)
				(type default)
			)
			(layer "F.SilkS")
		)
		(fp_line
			(start 19.409664 -5.171694)
			(end 19.349212 -5.171694)
			(stroke
				(width 0.1)
				(type default)
			)
			(layer "F.SilkS")
		)
		(fp_line
			(start 19.42084 -3.913124)
			(end 19.408902 -3.843528)
			(stroke
				(width 0.1)
				(type default)
			)
			(layer "F.SilkS")
		)
		(fp_line
			(start 19.42084 -3.913124)
			(end 19.408902 -3.843528)
			(stroke
				(width 0.1)
				(type default)
			)
			(layer "F.SilkS")
		)
		(fp_line
			(start 19.42084 -3.913124)
			(end 20.776184 -5.21335)
			(stroke
				(width 0.1)
				(type default)
			)
			(layer "F.SilkS")
		)
		(fp_line
			(start 19.42084 -3.913124)
			(end 20.776184 -5.21335)
			(stroke
				(width 0.1)
				(type default)
			)
			(layer "F.SilkS")
		)
		(fp_line
			(start 19.42846 -0.976884)
			(end 20.400772 -1.909572)
			(stroke
				(width 0.1)
				(type default)
			)
			(layer "F.SilkS")
		)
		(fp_line
			(start 19.42846 -0.976884)
			(end 20.400772 -1.909572)
			(stroke
				(width 0.1)
				(type default)
			)
			(layer "F.SilkS")
		)
		(fp_line
			(start 19.433032 -3.982466)
			(end 19.42084 -3.913124)
			(stroke
				(width 0.1)
				(type default)
			)
			(layer "F.SilkS")
		)
		(fp_line
			(start 19.433032 -3.982466)
			(end 19.42084 -3.913124)
			(stroke
				(width 0.1)
				(type default)
			)
			(layer "F.SilkS")
		)
		(fp_line
			(start 19.445478 -4.109466)
			(end 19.455384 -4.109466)
			(stroke
				(width 0.1)
				(type default)
			)
			(layer "F.SilkS")
		)
		(fp_line
			(start 19.445478 -4.109466)
			(end 19.455384 -4.109466)
			(stroke
				(width 0.1)
				(type default)
			)
			(layer "F.SilkS")
		)
		(fp_line
			(start 19.445478 -4.109466)
			(end 20.81276 -5.421376)
			(stroke
				(width 0.1)
				(type default)
			)
			(layer "F.SilkS")
		)
		(fp_line
			(start 19.445478 -4.109466)
			(end 20.81276 -5.421376)
			(stroke
				(width 0.1)
				(type default)
			)
			(layer "F.SilkS")
		)
		(fp_line
			(start 19.445478 -4.051554)
			(end 19.433032 -3.982466)
			(stroke
				(width 0.1)
				(type default)
			)
			(layer "F.SilkS")
		)
		(fp_line
			(start 19.445478 -4.051554)
			(end 19.433032 -3.982466)
			(stroke
				(width 0.1)
				(type default)
			)
			(layer "F.SilkS")
		)
		(fp_line
			(start 19.455384 -4.109466)
			(end 19.445478 -4.051554)
			(stroke
				(width 0.1)
				(type default)
			)
			(layer "F.SilkS")
		)
		(fp_line
			(start 19.455384 -4.109466)
			(end 19.445478 -4.051554)
			(stroke
				(width 0.1)
				(type default)
			)
			(layer "F.SilkS")
		)
		(fp_line
			(start 19.46402 -0.953516)
			(end 20.442428 -1.892046)
			(stroke
				(width 0.1)
				(type default)
			)
			(layer "F.SilkS")
		)
		(fp_line
			(start 19.46402 -0.953516)
			(end 20.442428 -1.892046)
			(stroke
				(width 0.1)
				(type default)
			)
			(layer "F.SilkS")
		)
		(fp_line
			(start 19.469608 -5.171694)
			(end 19.409664 -5.171694)
			(stroke
				(width 0.1)
				(type default)
			)
			(layer "F.SilkS")
		)
		(fp_line
			(start 19.469608 -5.171694)
			(end 19.409664 -5.171694)
			(stroke
				(width 0.1)
				(type default)
			)
			(layer "F.SilkS")
		)
		(fp_line
			(start 19.500088 -0.930148)
			(end 20.491704 -1.881378)
			(stroke
				(width 0.1)
				(type default)
			)
			(layer "F.SilkS")
		)
		(fp_line
			(start 19.500088 -0.930148)
			(end 20.491704 -1.881378)
			(stroke
				(width 0.1)
				(type default)
			)
			(layer "F.SilkS")
		)
		(fp_line
			(start 19.529806 -5.171694)
			(end 19.469608 -5.171694)
			(stroke
				(width 0.1)
				(type default)
			)
			(layer "F.SilkS")
		)
		(fp_line
			(start 19.529806 -5.171694)
			(end 19.469608 -5.171694)
			(stroke
				(width 0.1)
				(type default)
			)
			(layer "F.SilkS")
		)
		(fp_line
			(start 19.536156 -0.906526)
			(end 20.545044 -1.874774)
			(stroke
				(width 0.1)
				(type default)
			)
			(layer "F.SilkS")
		)
		(fp_line
			(start 19.536156 -0.906526)
			(end 20.545044 -1.874774)
			(stroke
				(width 0.1)
				(type default)
			)
			(layer "F.SilkS")
		)
		(fp_line
			(start 19.574002 -0.88519)
			(end 20.60194 -1.871726)
			(stroke
				(width 0.1)
				(type default)
			)
			(layer "F.SilkS")
		)
		(fp_line
			(start 19.574002 -0.88519)
			(end 20.60194 -1.871726)
			(stroke
				(width 0.1)
				(type default)
			)
			(layer "F.SilkS")
		)
		(fp_line
			(start 19.58975 -5.171694)
			(end 19.529806 -5.171694)
			(stroke
				(width 0.1)
				(type default)
			)
			(layer "F.SilkS")
		)
		(fp_line
			(start 19.58975 -5.171694)
			(end 19.529806 -5.171694)
			(stroke
				(width 0.1)
				(type default)
			)
			(layer "F.SilkS")
		)
		(fp_line
			(start 19.58975 -5.171694)
			(end 19.641566 -5.171694)
			(stroke
				(width 0.1)
				(type default)
			)
			(layer "F.SilkS")
		)
		(fp_line
			(start 19.58975 -5.171694)
			(end 19.641566 -5.171694)
			(stroke
				(width 0.1)
				(type default)
			)
			(layer "F.SilkS")
		)
		(fp_line
			(start 19.617944 -0.870458)
			(end 20.669504 -1.878838)
			(stroke
				(width 0.1)
				(type default)
			)
			(layer "F.SilkS")
		)
		(fp_line
			(start 19.617944 -0.870458)
			(end 20.669504 -1.878838)
			(stroke
				(width 0.1)
				(type default)
			)
			(layer "F.SilkS")
		)
		(fp_line
			(start 19.641566 -5.171694)
			(end 19.651726 -5.23113)
			(stroke
				(width 0.1)
				(type default)
			)
			(layer "F.SilkS")
		)
		(fp_line
			(start 19.641566 -5.171694)
			(end 19.651726 -5.23113)
			(stroke
				(width 0.1)
				(type default)
			)
			(layer "F.SilkS")
		)
		(fp_line
			(start 19.662902 -0.855218)
			(end 20.738084 -1.886966)
			(stroke
				(width 0.1)
				(type default)
			)
			(layer "F.SilkS")
		)
		(fp_line
			(start 19.662902 -0.855218)
			(end 20.738084 -1.886966)
			(stroke
				(width 0.1)
				(type default)
			)
			(layer "F.SilkS")
		)
		(fp_line
			(start 19.664172 -5.300472)
			(end 19.651726 -5.23113)
			(stroke
				(width 0.1)
				(type default)
			)
			(layer "F.SilkS")
		)
		(fp_line
			(start 19.664172 -5.300472)
			(end 19.651726 -5.23113)
			(stroke
				(width 0.1)
				(type default)
			)
			(layer "F.SilkS")
		)
		(fp_line
			(start 19.676364 -5.370068)
			(end 19.664172 -5.300472)
			(stroke
				(width 0.1)
				(type default)
			)
			(layer "F.SilkS")
		)
		(fp_line
			(start 19.676364 -5.370068)
			(end 19.664172 -5.300472)
			(stroke
				(width 0.1)
				(type default)
			)
			(layer "F.SilkS")
		)
		(fp_line
			(start 19.688302 -5.439156)
			(end 19.676364 -5.370068)
			(stroke
				(width 0.1)
				(type default)
			)
			(layer "F.SilkS")
		)
		(fp_line
			(start 19.688302 -5.439156)
			(end 19.676364 -5.370068)
			(stroke
				(width 0.1)
				(type default)
			)
			(layer "F.SilkS")
		)
		(fp_line
			(start 19.700748 -5.508752)
			(end 19.688302 -5.439156)
			(stroke
				(width 0.1)
				(type default)
			)
			(layer "F.SilkS")
		)
		(fp_line
			(start 19.700748 -5.508752)
			(end 19.688302 -5.439156)
			(stroke
				(width 0.1)
				(type default)
			)
			(layer "F.SilkS")
		)
		(fp_line
			(start 19.707352 -0.840486)
			(end 20.828 -1.915414)
			(stroke
				(width 0.1)
				(type default)
			)
			(layer "F.SilkS")
		)
		(fp_line
			(start 19.707352 -0.840486)
			(end 20.828 -1.915414)
			(stroke
				(width 0.1)
				(type default)
			)
			(layer "F.SilkS")
		)
		(fp_line
			(start 19.712686 -5.578094)
			(end 19.700748 -5.508752)
			(stroke
				(width 0.1)
				(type default)
			)
			(layer "F.SilkS")
		)
		(fp_line
			(start 19.712686 -5.578094)
			(end 19.700748 -5.508752)
			(stroke
				(width 0.1)
				(type default)
			)
			(layer "F.SilkS")
		)
		(fp_line
			(start 19.725132 -5.647436)
			(end 19.712686 -5.578094)
			(stroke
				(width 0.1)
				(type default)
			)
			(layer "F.SilkS")
		)
		(fp_line
			(start 19.725132 -5.647436)
			(end 19.712686 -5.578094)
			(stroke
				(width 0.1)
				(type default)
			)
			(layer "F.SilkS")
		)
		(fp_line
			(start 19.737324 -5.716778)
			(end 19.725132 -5.647436)
			(stroke
				(width 0.1)
				(type default)
			)
			(layer "F.SilkS")
		)
		(fp_line
			(start 19.737324 -5.716778)
			(end 19.725132 -5.647436)
			(stroke
				(width 0.1)
				(type default)
			)
			(layer "F.SilkS")
		)
		(fp_line
			(start 19.749262 -5.786374)
			(end 19.737324 -5.716778)
			(stroke
				(width 0.1)
				(type default)
			)
			(layer "F.SilkS")
		)
		(fp_line
			(start 19.749262 -5.786374)
			(end 19.737324 -5.716778)
			(stroke
				(width 0.1)
				(type default)
			)
			(layer "F.SilkS")
		)
		(fp_line
			(start 19.751802 -0.825246)
			(end 20.932902 -1.95834)
			(stroke
				(width 0.1)
				(type default)
			)
			(layer "F.SilkS")
		)
		(fp_line
			(start 19.751802 -0.825246)
			(end 20.932902 -1.95834)
			(stroke
				(width 0.1)
				(type default)
			)
			(layer "F.SilkS")
		)
		(fp_line
			(start 19.761708 -5.85597)
			(end 19.749262 -5.786374)
			(stroke
				(width 0.1)
				(type default)
			)
			(layer "F.SilkS")
		)
		(fp_line
			(start 19.761708 -5.85597)
			(end 19.749262 -5.786374)
			(stroke
				(width 0.1)
				(type default)
			)
			(layer "F.SilkS")
		)
		(fp_line
			(start 19.773646 -5.925058)
			(end 19.761708 -5.85597)
			(stroke
				(width 0.1)
				(type default)
			)
			(layer "F.SilkS")
		)
		(fp_line
			(start 19.773646 -5.925058)
			(end 19.761708 -5.85597)
			(stroke
				(width 0.1)
				(type default)
			)
			(layer "F.SilkS")
		)
		(fp_line
			(start 19.785838 -5.9944)
			(end 19.773646 -5.925058)
			(stroke
				(width 0.1)
				(type default)
			)
			(layer "F.SilkS")
		)
		(fp_line
			(start 19.785838 -5.9944)
			(end 19.773646 -5.925058)
			(stroke
				(width 0.1)
				(type default)
			)
			(layer "F.SilkS")
		)
		(fp_line
			(start 19.798284 -6.063996)
			(end 19.785838 -5.9944)
			(stroke
				(width 0.1)
				(type default)
			)
			(layer "F.SilkS")
		)
		(fp_line
			(start 19.798284 -6.063996)
			(end 19.785838 -5.9944)
			(stroke
				(width 0.1)
				(type default)
			)
			(layer "F.SilkS")
		)
		(fp_line
			(start 19.798284 -6.063996)
			(end 19.810222 -6.133338)
			(stroke
				(width 0.1)
				(type default)
			)
			(layer "F.SilkS")
		)
		(fp_line
			(start 19.798284 -6.063996)
			(end 19.810222 -6.133338)
			(stroke
				(width 0.1)
				(type default)
			)
			(layer "F.SilkS")
		)
		(fp_line
			(start 19.801078 -0.815086)
			(end 21.08327 -2.044954)
			(stroke
				(width 0.1)
				(type default)
			)
			(layer "F.SilkS")
		)
		(fp_line
			(start 19.801078 -0.815086)
			(end 21.08327 -2.044954)
			(stroke
				(width 0.1)
				(type default)
			)
			(layer "F.SilkS")
		)
		(fp_line
			(start 19.810222 -6.133338)
			(end 19.822668 -6.20268)
			(stroke
				(width 0.1)
				(type default)
			)
			(layer "F.SilkS")
		)
		(fp_line
			(start 19.810222 -6.133338)
			(end 19.822668 -6.20268)
			(stroke
				(width 0.1)
				(type default)
			)
			(layer "F.SilkS")
		)
		(fp_line
			(start 19.822668 -6.20268)
			(end 19.834606 -6.272022)
			(stroke
				(width 0.1)
				(type default)
			)
			(layer "F.SilkS")
		)
		(fp_line
			(start 19.822668 -6.20268)
			(end 19.834606 -6.272022)
			(stroke
				(width 0.1)
				(type default)
			)
			(layer "F.SilkS")
		)
		(fp_line
			(start 19.835114 -6.274308)
			(end 19.834606 -6.272022)
			(stroke
				(width 0.1)
				(type default)
			)
			(layer "F.SilkS")
		)
		(fp_line
			(start 19.835114 -6.274308)
			(end 19.834606 -6.272022)
			(stroke
				(width 0.1)
				(type default)
			)
			(layer "F.SilkS")
		)
		(fp_line
			(start 19.838924 -6.276086)
			(end 19.834606 -6.272022)
			(stroke
				(width 0.1)
				(type default)
			)
			(layer "F.SilkS")
		)
		(fp_line
			(start 19.838924 -6.276086)
			(end 19.834606 -6.272022)
			(stroke
				(width 0.1)
				(type default)
			)
			(layer "F.SilkS")
		)
		(fp_line
			(start 19.838924 -6.276086)
			(end 19.835114 -6.274308)
			(stroke
				(width 0.1)
				(type default)
			)
			(layer "F.SilkS")
		)
		(fp_line
			(start 19.838924 -6.276086)
			(end 19.835114 -6.274308)
			(stroke
				(width 0.1)
				(type default)
			)
			(layer "F.SilkS")
		)
		(fp_line
			(start 19.855434 -0.809498)
			(end 21.299932 -2.195068)
			(stroke
				(width 0.1)
				(type default)
			)
			(layer "F.SilkS")
		)
		(fp_line
			(start 19.855434 -0.809498)
			(end 21.299932 -2.195068)
			(stroke
				(width 0.1)
				(type default)
			)
			(layer "F.SilkS")
		)
		(fp_line
			(start 19.910044 -0.80391)
			(end 21.273516 -2.11201)
			(stroke
				(width 0.1)
				(type default)
			)
			(layer "F.SilkS")
		)
		(fp_line
			(start 19.910044 -0.80391)
			(end 21.273516 -2.11201)
			(stroke
				(width 0.1)
				(type default)
			)
			(layer "F.SilkS")
		)
		(fp_line
			(start 19.95424 -6.329172)
			(end 19.822668 -6.20268)
			(stroke
				(width 0.1)
				(type default)
			)
			(layer "F.SilkS")
		)
		(fp_line
			(start 19.95424 -6.329172)
			(end 19.822668 -6.20268)
			(stroke
				(width 0.1)
				(type default)
			)
			(layer "F.SilkS")
		)
		(fp_line
			(start 19.95424 -6.329172)
			(end 19.838924 -6.276086)
			(stroke
				(width 0.1)
				(type default)
			)
			(layer "F.SilkS")
		)
		(fp_line
			(start 19.95424 -6.329172)
			(end 19.838924 -6.276086)
			(stroke
				(width 0.1)
				(type default)
			)
			(layer "F.SilkS")
		)
		(fp_line
			(start 19.964654 -0.798576)
			(end 21.2471 -2.028952)
			(stroke
				(width 0.1)
				(type default)
			)
			(layer "F.SilkS")
		)
		(fp_line
			(start 19.964654 -0.798576)
			(end 21.2471 -2.028952)
			(stroke
				(width 0.1)
				(type default)
			)
			(layer "F.SilkS")
		)
		(fp_line
			(start 20.01901 -0.792988)
			(end 21.220684 -1.946148)
			(stroke
				(width 0.1)
				(type default)
			)
			(layer "F.SilkS")
		)
		(fp_line
			(start 20.01901 -0.792988)
			(end 21.220684 -1.946148)
			(stroke
				(width 0.1)
				(type default)
			)
			(layer "F.SilkS")
		)
		(fp_line
			(start 20.069302 -6.382004)
			(end 19.810222 -6.133338)
			(stroke
				(width 0.1)
				(type default)
			)
			(layer "F.SilkS")
		)
		(fp_line
			(start 20.069302 -6.382004)
			(end 19.810222 -6.133338)
			(stroke
				(width 0.1)
				(type default)
			)
			(layer "F.SilkS")
		)
		(fp_line
			(start 20.069302 -6.382004)
			(end 19.95424 -6.329172)
			(stroke
				(width 0.1)
				(type default)
			)
			(layer "F.SilkS")
		)
		(fp_line
			(start 20.069302 -6.382004)
			(end 19.95424 -6.329172)
			(stroke
				(width 0.1)
				(type default)
			)
			(layer "F.SilkS")
		)
		(fp_line
			(start 20.084542 -0.798576)
			(end 21.194268 -1.862836)
			(stroke
				(width 0.1)
				(type default)
			)
			(layer "F.SilkS")
		)
		(fp_line
			(start 20.084542 -0.798576)
			(end 21.194268 -1.862836)
			(stroke
				(width 0.1)
				(type default)
			)
			(layer "F.SilkS")
		)
		(fp_line
			(start 20.14982 -0.803402)
			(end 21.167852 -1.779778)
			(stroke
				(width 0.1)
				(type default)
			)
			(layer "F.SilkS")
		)
		(fp_line
			(start 20.14982 -0.803402)
			(end 21.167852 -1.779778)
			(stroke
				(width 0.1)
				(type default)
			)
			(layer "F.SilkS")
		)
		(fp_line
			(start 20.185126 -6.43509)
			(end 19.798284 -6.063996)
			(stroke
				(width 0.1)
				(type default)
			)
			(layer "F.SilkS")
		)
		(fp_line
			(start 20.185126 -6.43509)
			(end 19.798284 -6.063996)
			(stroke
				(width 0.1)
				(type default)
			)
			(layer "F.SilkS")
		)
		(fp_line
			(start 20.185126 -6.43509)
			(end 20.069302 -6.382004)
			(stroke
				(width 0.1)
				(type default)
			)
			(layer "F.SilkS")
		)
		(fp_line
			(start 20.185126 -6.43509)
			(end 20.069302 -6.382004)
			(stroke
				(width 0.1)
				(type default)
			)
			(layer "F.SilkS")
		)
		(fp_line
			(start 20.215352 -0.808228)
			(end 21.141436 -1.69672)
			(stroke
				(width 0.1)
				(type default)
			)
			(layer "F.SilkS")
		)
		(fp_line
			(start 20.215352 -0.808228)
			(end 21.141436 -1.69672)
			(stroke
				(width 0.1)
				(type default)
			)
			(layer "F.SilkS")
		)
		(fp_line
			(start 20.280884 -0.813562)
			(end 21.115274 -1.613916)
			(stroke
				(width 0.1)
				(type default)
			)
			(layer "F.SilkS")
		)
		(fp_line
			(start 20.280884 -0.813562)
			(end 21.115274 -1.613916)
			(stroke
				(width 0.1)
				(type default)
			)
			(layer "F.SilkS")
		)
		(fp_line
			(start 20.30095 -6.488176)
			(end 19.785838 -5.9944)
			(stroke
				(width 0.1)
				(type default)
			)
			(layer "F.SilkS")
		)
		(fp_line
			(start 20.30095 -6.488176)
			(end 19.785838 -5.9944)
			(stroke
				(width 0.1)
				(type default)
			)
			(layer "F.SilkS")
		)
		(fp_line
			(start 20.30095 -6.488176)
			(end 20.185126 -6.43509)
			(stroke
				(width 0.1)
				(type default)
			)
			(layer "F.SilkS")
		)
		(fp_line
			(start 20.30095 -6.488176)
			(end 20.185126 -6.43509)
			(stroke
				(width 0.1)
				(type default)
			)
			(layer "F.SilkS")
		)
		(fp_line
			(start 20.301966 -2.507234)
			(end 20.28952 -2.437892)
			(stroke
				(width 0.1)
				(type default)
			)
			(layer "F.SilkS")
		)
		(fp_line
			(start 20.301966 -2.507234)
			(end 20.28952 -2.437892)
			(stroke
				(width 0.1)
				(type default)
			)
			(layer "F.SilkS")
		)
		(fp_line
			(start 20.313904 -2.576576)
			(end 20.301966 -2.507234)
			(stroke
				(width 0.1)
				(type default)
			)
			(layer "F.SilkS")
		)
		(fp_line
			(start 20.313904 -2.576576)
			(end 20.301966 -2.507234)
			(stroke
				(width 0.1)
				(type default)
			)
			(layer "F.SilkS")
		)
		(fp_line
			(start 20.32635 -2.646172)
			(end 20.313904 -2.576576)
			(stroke
				(width 0.1)
				(type default)
			)
			(layer "F.SilkS")
		)
		(fp_line
			(start 20.32635 -2.646172)
			(end 20.313904 -2.576576)
			(stroke
				(width 0.1)
				(type default)
			)
			(layer "F.SilkS")
		)
		(fp_line
			(start 20.32635 -2.646172)
			(end 20.338288 -2.715768)
			(stroke
				(width 0.1)
				(type default)
			)
			(layer "F.SilkS")
		)
		(fp_line
			(start 20.32635 -2.646172)
			(end 20.338288 -2.715768)
			(stroke
				(width 0.1)
				(type default)
			)
			(layer "F.SilkS")
		)
		(fp_line
			(start 20.338288 -2.715768)
			(end 20.35048 -2.784856)
			(stroke
				(width 0.1)
				(type default)
			)
			(layer "F.SilkS")
		)
		(fp_line
			(start 20.338288 -2.715768)
			(end 20.35048 -2.784856)
			(stroke
				(width 0.1)
				(type default)
			)
			(layer "F.SilkS")
		)
		(fp_line
			(start 20.35048 -2.784856)
			(end 20.362926 -2.854198)
			(stroke
				(width 0.1)
				(type default)
			)
			(layer "F.SilkS")
		)
		(fp_line
			(start 20.35048 -2.784856)
			(end 20.362926 -2.854198)
			(stroke
				(width 0.1)
				(type default)
			)
			(layer "F.SilkS")
		)
		(fp_line
			(start 20.359116 -0.830834)
			(end 21.088858 -1.530604)
			(stroke
				(width 0.1)
				(type default)
			)
			(layer "F.SilkS")
		)
		(fp_line
			(start 20.359116 -0.830834)
			(end 21.088858 -1.530604)
			(stroke
				(width 0.1)
				(type default)
			)
			(layer "F.SilkS")
		)
		(fp_line
			(start 20.362926 -2.854198)
			(end 20.374864 -2.923794)
			(stroke
				(width 0.1)
				(type default)
			)
			(layer "F.SilkS")
		)
		(fp_line
			(start 20.362926 -2.854198)
			(end 20.374864 -2.923794)
			(stroke
				(width 0.1)
				(type default)
			)
			(layer "F.SilkS")
		)
		(fp_line
			(start 20.374864 -2.923794)
			(end 20.38731 -2.99339)
			(stroke
				(width 0.1)
				(type default)
			)
			(layer "F.SilkS")
		)
		(fp_line
			(start 20.374864 -2.923794)
			(end 20.38731 -2.99339)
			(stroke
				(width 0.1)
				(type default)
			)
			(layer "F.SilkS")
		)
		(fp_line
			(start 20.38731 -2.99339)
			(end 20.399248 -3.062478)
			(stroke
				(width 0.1)
				(type default)
			)
			(layer "F.SilkS")
		)
		(fp_line
			(start 20.38731 -2.99339)
			(end 20.399248 -3.062478)
			(stroke
				(width 0.1)
				(type default)
			)
			(layer "F.SilkS")
		)
		(fp_line
			(start 20.399248 -3.062478)
			(end 20.41144 -3.13182)
			(stroke
				(width 0.1)
				(type default)
			)
			(layer "F.SilkS")
		)
		(fp_line
			(start 20.399248 -3.062478)
			(end 20.41144 -3.13182)
			(stroke
				(width 0.1)
				(type default)
			)
			(layer "F.SilkS")
		)
		(fp_line
			(start 20.41144 -3.13182)
			(end 20.423886 -3.201416)
			(stroke
				(width 0.1)
				(type default)
			)
			(layer "F.SilkS")
		)
		(fp_line
			(start 20.41144 -3.13182)
			(end 20.423886 -3.201416)
			(stroke
				(width 0.1)
				(type default)
			)
			(layer "F.SilkS")
		)
		(fp_line
			(start 20.416012 -6.541262)
			(end 19.773646 -5.925058)
			(stroke
				(width 0.1)
				(type default)
			)
			(layer "F.SilkS")
		)
		(fp_line
			(start 20.416012 -6.541262)
			(end 19.773646 -5.925058)
			(stroke
				(width 0.1)
				(type default)
			)
			(layer "F.SilkS")
		)
		(fp_line
			(start 20.416012 -6.541262)
			(end 20.30095 -6.488176)
			(stroke
				(width 0.1)
				(type default)
			)
			(layer "F.SilkS")
		)
		(fp_line
			(start 20.416012 -6.541262)
			(end 20.30095 -6.488176)
			(stroke
				(width 0.1)
				(type default)
			)
			(layer "F.SilkS")
		)
		(fp_line
			(start 20.423886 -3.201416)
			(end 20.435824 -3.270758)
			(stroke
				(width 0.1)
				(type default)
			)
			(layer "F.SilkS")
		)
		(fp_line
			(start 20.423886 -3.201416)
			(end 20.435824 -3.270758)
			(stroke
				(width 0.1)
				(type default)
			)
			(layer "F.SilkS")
		)
		(fp_line
			(start 20.435824 -3.270758)
			(end 20.44827 -3.340354)
			(stroke
				(width 0.1)
				(type default)
			)
			(layer "F.SilkS")
		)
		(fp_line
			(start 20.435824 -3.270758)
			(end 20.44827 -3.340354)
			(stroke
				(width 0.1)
				(type default)
			)
			(layer "F.SilkS")
		)
		(fp_line
			(start 20.437602 -0.848106)
			(end 21.062188 -1.447546)
			(stroke
				(width 0.1)
				(type default)
			)
			(layer "F.SilkS")
		)
		(fp_line
			(start 20.437602 -0.848106)
			(end 21.062188 -1.447546)
			(stroke
				(width 0.1)
				(type default)
			)
			(layer "F.SilkS")
		)
		(fp_line
			(start 20.44827 -3.340354)
			(end 20.460462 -3.409442)
			(stroke
				(width 0.1)
				(type default)
			)
			(layer "F.SilkS")
		)
		(fp_line
			(start 20.44827 -3.340354)
			(end 20.460462 -3.409442)
			(stroke
				(width 0.1)
				(type default)
			)
			(layer "F.SilkS")
		)
		(fp_line
			(start 20.460462 -3.409442)
			(end 20.4724 -3.479038)
			(stroke
				(width 0.1)
				(type default)
			)
			(layer "F.SilkS")
		)
		(fp_line
			(start 20.460462 -3.409442)
			(end 20.4724 -3.479038)
			(stroke
				(width 0.1)
				(type default)
			)
			(layer "F.SilkS")
		)
		(fp_line
			(start 20.484846 -3.548634)
			(end 20.4724 -3.479038)
			(stroke
				(width 0.1)
				(type default)
			)
			(layer "F.SilkS")
		)
		(fp_line
			(start 20.484846 -3.548634)
			(end 20.4724 -3.479038)
			(stroke
				(width 0.1)
				(type default)
			)
			(layer "F.SilkS")
		)
		(fp_line
			(start 20.496784 -3.617976)
			(end 19.141186 -2.317242)
			(stroke
				(width 0.1)
				(type default)
			)
			(layer "F.SilkS")
		)
		(fp_line
			(start 20.496784 -3.617976)
			(end 19.141186 -2.317242)
			(stroke
				(width 0.1)
				(type default)
			)
			(layer "F.SilkS")
		)
		(fp_line
			(start 20.496784 -3.617976)
			(end 20.484846 -3.548634)
			(stroke
				(width 0.1)
				(type default)
			)
			(layer "F.SilkS")
		)
		(fp_line
			(start 20.496784 -3.617976)
			(end 20.484846 -3.548634)
			(stroke
				(width 0.1)
				(type default)
			)
			(layer "F.SilkS")
		)
		(fp_line
			(start 20.496784 -3.617976)
			(end 20.50923 -3.687064)
			(stroke
				(width 0.1)
				(type default)
			)
			(layer "F.SilkS")
		)
		(fp_line
			(start 20.496784 -3.617976)
			(end 20.50923 -3.687064)
			(stroke
				(width 0.1)
				(type default)
			)
			(layer "F.SilkS")
		)
		(fp_line
			(start 20.50923 -3.687064)
			(end 20.521422 -3.75666)
			(stroke
				(width 0.1)
				(type default)
			)
			(layer "F.SilkS")
		)
		(fp_line
			(start 20.50923 -3.687064)
			(end 20.521422 -3.75666)
			(stroke
				(width 0.1)
				(type default)
			)
			(layer "F.SilkS")
		)
		(fp_line
			(start 20.515834 -0.865632)
			(end 21.035772 -1.364742)
			(stroke
				(width 0.1)
				(type default)
			)
			(layer "F.SilkS")
		)
		(fp_line
			(start 20.515834 -0.865632)
			(end 21.035772 -1.364742)
			(stroke
				(width 0.1)
				(type default)
			)
			(layer "F.SilkS")
		)
		(fp_line
			(start 20.521422 -3.75666)
			(end 20.533614 -3.826256)
			(stroke
				(width 0.1)
				(type default)
			)
			(layer "F.SilkS")
		)
		(fp_line
			(start 20.521422 -3.75666)
			(end 20.533614 -3.826256)
			(stroke
				(width 0.1)
				(type default)
			)
			(layer "F.SilkS")
		)
		(fp_line
			(start 20.531328 -6.594348)
			(end 19.761708 -5.85597)
			(stroke
				(width 0.1)
				(type default)
			)
			(layer "F.SilkS")
		)
		(fp_line
			(start 20.531328 -6.594348)
			(end 19.761708 -5.85597)
			(stroke
				(width 0.1)
				(type default)
			)
			(layer "F.SilkS")
		)
		(fp_line
			(start 20.531328 -6.594348)
			(end 20.416012 -6.541262)
			(stroke
				(width 0.1)
				(type default)
			)
			(layer "F.SilkS")
		)
		(fp_line
			(start 20.531328 -6.594348)
			(end 20.416012 -6.541262)
			(stroke
				(width 0.1)
				(type default)
			)
			(layer "F.SilkS")
		)
		(fp_line
			(start 20.533614 -3.826256)
			(end 20.545806 -3.895344)
			(stroke
				(width 0.1)
				(type default)
			)
			(layer "F.SilkS")
		)
		(fp_line
			(start 20.533614 -3.826256)
			(end 20.545806 -3.895344)
			(stroke
				(width 0.1)
				(type default)
			)
			(layer "F.SilkS")
		)
		(fp_line
			(start 20.545806 -3.895344)
			(end 20.557744 -3.96494)
			(stroke
				(width 0.1)
				(type default)
			)
			(layer "F.SilkS")
		)
		(fp_line
			(start 20.545806 -3.895344)
			(end 20.557744 -3.96494)
			(stroke
				(width 0.1)
				(type default)
			)
			(layer "F.SilkS")
		)
		(fp_line
			(start 20.557744 -3.96494)
			(end 20.57019 -4.034282)
			(stroke
				(width 0.1)
				(type default)
			)
			(layer "F.SilkS")
		)
		(fp_line
			(start 20.557744 -3.96494)
			(end 20.57019 -4.034282)
			(stroke
				(width 0.1)
				(type default)
			)
			(layer "F.SilkS")
		)
		(fp_line
			(start 20.57019 -4.034282)
			(end 20.582382 -4.103878)
			(stroke
				(width 0.1)
				(type default)
			)
			(layer "F.SilkS")
		)
		(fp_line
			(start 20.57019 -4.034282)
			(end 20.582382 -4.103878)
			(stroke
				(width 0.1)
				(type default)
			)
			(layer "F.SilkS")
		)
		(fp_line
			(start 20.582382 -4.103878)
			(end 20.583398 -4.109466)
			(stroke
				(width 0.1)
				(type default)
			)
			(layer "F.SilkS")
		)
		(fp_line
			(start 20.582382 -4.103878)
			(end 20.583398 -4.109466)
			(stroke
				(width 0.1)
				(type default)
			)
			(layer "F.SilkS")
		)
		(fp_line
			(start 20.582382 -4.103878)
			(end 20.588224 -4.109466)
			(stroke
				(width 0.1)
				(type default)
			)
			(layer "F.SilkS")
		)
		(fp_line
			(start 20.582382 -4.103878)
			(end 20.588224 -4.109466)
			(stroke
				(width 0.1)
				(type default)
			)
			(layer "F.SilkS")
		)
		(fp_line
			(start 20.583398 -4.109466)
			(end 20.588224 -4.109466)
			(stroke
				(width 0.1)
				(type default)
			)
			(layer "F.SilkS")
		)
		(fp_line
			(start 20.583398 -4.109466)
			(end 20.588224 -4.109466)
			(stroke
				(width 0.1)
				(type default)
			)
			(layer "F.SilkS")
		)
		(fp_line
			(start 20.610322 -0.898652)
			(end 21.00961 -1.281684)
			(stroke
				(width 0.1)
				(type default)
			)
			(layer "F.SilkS")
		)
		(fp_line
			(start 20.610322 -0.898652)
			(end 21.00961 -1.281684)
			(stroke
				(width 0.1)
				(type default)
			)
			(layer "F.SilkS")
		)
		(fp_line
			(start 20.647152 -6.647434)
			(end 19.749262 -5.786374)
			(stroke
				(width 0.1)
				(type default)
			)
			(layer "F.SilkS")
		)
		(fp_line
			(start 20.647152 -6.647434)
			(end 19.749262 -5.786374)
			(stroke
				(width 0.1)
				(type default)
			)
			(layer "F.SilkS")
		)
		(fp_line
			(start 20.647152 -6.647434)
			(end 20.531328 -6.594348)
			(stroke
				(width 0.1)
				(type default)
			)
			(layer "F.SilkS")
		)
		(fp_line
			(start 20.647152 -6.647434)
			(end 20.531328 -6.594348)
			(stroke
				(width 0.1)
				(type default)
			)
			(layer "F.SilkS")
		)
		(fp_line
			(start 20.648422 -4.109466)
			(end 20.588224 -4.109466)
			(stroke
				(width 0.1)
				(type default)
			)
			(layer "F.SilkS")
		)
		(fp_line
			(start 20.648422 -4.109466)
			(end 20.588224 -4.109466)
			(stroke
				(width 0.1)
				(type default)
			)
			(layer "F.SilkS")
		)
		(fp_line
			(start 20.708366 -0.934974)
			(end 20.98294 -1.198626)
			(stroke
				(width 0.1)
				(type default)
			)
			(layer "F.SilkS")
		)
		(fp_line
			(start 20.708366 -0.934974)
			(end 20.98294 -1.198626)
			(stroke
				(width 0.1)
				(type default)
			)
			(layer "F.SilkS")
		)
		(fp_line
			(start 20.70862 -4.109466)
			(end 20.648422 -4.109466)
			(stroke
				(width 0.1)
				(type default)
			)
			(layer "F.SilkS")
		)
		(fp_line
			(start 20.70862 -4.109466)
			(end 20.648422 -4.109466)
			(stroke
				(width 0.1)
				(type default)
			)
			(layer "F.SilkS")
		)
		(fp_line
			(start 20.762722 -6.70052)
			(end 19.737324 -5.716778)
			(stroke
				(width 0.1)
				(type default)
			)
			(layer "F.SilkS")
		)
		(fp_line
			(start 20.762722 -6.70052)
			(end 19.737324 -5.716778)
			(stroke
				(width 0.1)
				(type default)
			)
			(layer "F.SilkS")
		)
		(fp_line
			(start 20.762722 -6.70052)
			(end 20.647152 -6.647434)
			(stroke
				(width 0.1)
				(type default)
			)
			(layer "F.SilkS")
		)
		(fp_line
			(start 20.762722 -6.70052)
			(end 20.647152 -6.647434)
			(stroke
				(width 0.1)
				(type default)
			)
			(layer "F.SilkS")
		)
		(fp_line
			(start 20.768564 -4.109466)
			(end 20.70862 -4.109466)
			(stroke
				(width 0.1)
				(type default)
			)
			(layer "F.SilkS")
		)
		(fp_line
			(start 20.768564 -4.109466)
			(end 20.70862 -4.109466)
			(stroke
				(width 0.1)
				(type default)
			)
			(layer "F.SilkS")
		)
		(fp_line
			(start 20.769072 -5.171694)
			(end 20.793202 -5.171694)
			(stroke
				(width 0.1)
				(type default)
			)
			(layer "F.SilkS")
		)
		(fp_line
			(start 20.769072 -5.171694)
			(end 20.793202 -5.171694)
			(stroke
				(width 0.1)
				(type default)
			)
			(layer "F.SilkS")
		)
		(fp_line
			(start 20.776184 -5.21335)
			(end 20.769072 -5.171694)
			(stroke
				(width 0.1)
				(type default)
			)
			(layer "F.SilkS")
		)
		(fp_line
			(start 20.776184 -5.21335)
			(end 20.769072 -5.171694)
			(stroke
				(width 0.1)
				(type default)
			)
			(layer "F.SilkS")
		)
		(fp_line
			(start 20.776184 -5.21335)
			(end 20.78863 -5.282692)
			(stroke
				(width 0.1)
				(type default)
			)
			(layer "F.SilkS")
		)
		(fp_line
			(start 20.776184 -5.21335)
			(end 20.78863 -5.282692)
			(stroke
				(width 0.1)
				(type default)
			)
			(layer "F.SilkS")
		)
		(fp_line
			(start 20.78863 -5.282692)
			(end 19.433032 -3.982466)
			(stroke
				(width 0.1)
				(type default)
			)
			(layer "F.SilkS")
		)
		(fp_line
			(start 20.78863 -5.282692)
			(end 19.433032 -3.982466)
			(stroke
				(width 0.1)
				(type default)
			)
			(layer "F.SilkS")
		)
		(fp_line
			(start 20.78863 -5.282692)
			(end 20.800822 -5.352034)
			(stroke
				(width 0.1)
				(type default)
			)
			(layer "F.SilkS")
		)
		(fp_line
			(start 20.78863 -5.282692)
			(end 20.800822 -5.352034)
			(stroke
				(width 0.1)
				(type default)
			)
			(layer "F.SilkS")
		)
		(fp_line
			(start 20.793202 -5.171694)
			(end 19.408902 -3.843528)
			(stroke
				(width 0.1)
				(type default)
			)
			(layer "F.SilkS")
		)
		(fp_line
			(start 20.793202 -5.171694)
			(end 19.408902 -3.843528)
			(stroke
				(width 0.1)
				(type default)
			)
			(layer "F.SilkS")
		)
		(fp_line
			(start 20.800822 -5.352034)
			(end 19.445478 -4.051554)
			(stroke
				(width 0.1)
				(type default)
			)
			(layer "F.SilkS")
		)
		(fp_line
			(start 20.800822 -5.352034)
			(end 19.445478 -4.051554)
			(stroke
				(width 0.1)
				(type default)
			)
			(layer "F.SilkS")
		)
		(fp_line
			(start 20.800822 -5.352034)
			(end 20.81276 -5.421376)
			(stroke
				(width 0.1)
				(type default)
			)
			(layer "F.SilkS")
		)
		(fp_line
			(start 20.800822 -5.352034)
			(end 20.81276 -5.421376)
			(stroke
				(width 0.1)
				(type default)
			)
			(layer "F.SilkS")
		)
		(fp_line
			(start 20.81276 -5.421376)
			(end 20.825206 -5.490972)
			(stroke
				(width 0.1)
				(type default)
			)
			(layer "F.SilkS")
		)
		(fp_line
			(start 20.81276 -5.421376)
			(end 20.825206 -5.490972)
			(stroke
				(width 0.1)
				(type default)
			)
			(layer "F.SilkS")
		)
		(fp_line
			(start 20.825206 -5.490972)
			(end 20.837144 -5.560314)
			(stroke
				(width 0.1)
				(type default)
			)
			(layer "F.SilkS")
		)
		(fp_line
			(start 20.825206 -5.490972)
			(end 20.837144 -5.560314)
			(stroke
				(width 0.1)
				(type default)
			)
			(layer "F.SilkS")
		)
		(fp_line
			(start 20.829016 -4.109466)
			(end 20.768564 -4.109466)
			(stroke
				(width 0.1)
				(type default)
			)
			(layer "F.SilkS")
		)
		(fp_line
			(start 20.829016 -4.109466)
			(end 20.768564 -4.109466)
			(stroke
				(width 0.1)
				(type default)
			)
			(layer "F.SilkS")
		)
		(fp_line
			(start 20.831302 -0.995426)
			(end 20.956524 -1.115314)
			(stroke
				(width 0.1)
				(type default)
			)
			(layer "F.SilkS")
		)
		(fp_line
			(start 20.831302 -0.995426)
			(end 20.956524 -1.115314)
			(stroke
				(width 0.1)
				(type default)
			)
			(layer "F.SilkS")
		)
		(fp_line
			(start 20.837144 -5.560314)
			(end 20.84959 -5.629656)
			(stroke
				(width 0.1)
				(type default)
			)
			(layer "F.SilkS")
		)
		(fp_line
			(start 20.837144 -5.560314)
			(end 20.84959 -5.629656)
			(stroke
				(width 0.1)
				(type default)
			)
			(layer "F.SilkS")
		)
		(fp_line
			(start 20.84959 -5.629656)
			(end 20.861782 -5.699252)
			(stroke
				(width 0.1)
				(type default)
			)
			(layer "F.SilkS")
		)
		(fp_line
			(start 20.84959 -5.629656)
			(end 20.861782 -5.699252)
			(stroke
				(width 0.1)
				(type default)
			)
			(layer "F.SilkS")
		)
		(fp_line
			(start 20.8534 -5.171694)
			(end 19.396456 -3.774186)
			(stroke
				(width 0.1)
				(type default)
			)
			(layer "F.SilkS")
		)
		(fp_line
			(start 20.8534 -5.171694)
			(end 19.396456 -3.774186)
			(stroke
				(width 0.1)
				(type default)
			)
			(layer "F.SilkS")
		)
		(fp_line
			(start 20.8534 -5.171694)
			(end 20.793202 -5.171694)
			(stroke
				(width 0.1)
				(type default)
			)
			(layer "F.SilkS")
		)
		(fp_line
			(start 20.8534 -5.171694)
			(end 20.793202 -5.171694)
			(stroke
				(width 0.1)
				(type default)
			)
			(layer "F.SilkS")
		)
		(fp_line
			(start 20.861782 -5.699252)
			(end 20.874228 -5.768594)
			(stroke
				(width 0.1)
				(type default)
			)
			(layer "F.SilkS")
		)
		(fp_line
			(start 20.861782 -5.699252)
			(end 20.874228 -5.768594)
			(stroke
				(width 0.1)
				(type default)
			)
			(layer "F.SilkS")
		)
		(fp_line
			(start 20.874228 -5.768594)
			(end 20.886166 -5.837936)
			(stroke
				(width 0.1)
				(type default)
			)
			(layer "F.SilkS")
		)
		(fp_line
			(start 20.874228 -5.768594)
			(end 20.886166 -5.837936)
			(stroke
				(width 0.1)
				(type default)
			)
			(layer "F.SilkS")
		)
		(fp_line
			(start 20.877784 -6.753606)
			(end 19.725132 -5.647436)
			(stroke
				(width 0.1)
				(type default)
			)
			(layer "F.SilkS")
		)
		(fp_line
			(start 20.877784 -6.753606)
			(end 19.725132 -5.647436)
			(stroke
				(width 0.1)
				(type default)
			)
			(layer "F.SilkS")
		)
		(fp_line
			(start 20.877784 -6.753606)
			(end 20.762722 -6.70052)
			(stroke
				(width 0.1)
				(type default)
			)
			(layer "F.SilkS")
		)
		(fp_line
			(start 20.877784 -6.753606)
			(end 20.762722 -6.70052)
			(stroke
				(width 0.1)
				(type default)
			)
			(layer "F.SilkS")
		)
		(fp_line
			(start 20.886166 -5.837936)
			(end 20.898104 -5.907278)
			(stroke
				(width 0.1)
				(type default)
			)
			(layer "F.SilkS")
		)
		(fp_line
			(start 20.886166 -5.837936)
			(end 20.898104 -5.907278)
			(stroke
				(width 0.1)
				(type default)
			)
			(layer "F.SilkS")
		)
		(fp_line
			(start 20.889214 -4.109466)
			(end 20.829016 -4.109466)
			(stroke
				(width 0.1)
				(type default)
			)
			(layer "F.SilkS")
		)
		(fp_line
			(start 20.889214 -4.109466)
			(end 20.829016 -4.109466)
			(stroke
				(width 0.1)
				(type default)
			)
			(layer "F.SilkS")
		)
		(fp_line
			(start 20.898104 -5.907278)
			(end 20.91055 -5.976874)
			(stroke
				(width 0.1)
				(type default)
			)
			(layer "F.SilkS")
		)
		(fp_line
			(start 20.898104 -5.907278)
			(end 20.91055 -5.976874)
			(stroke
				(width 0.1)
				(type default)
			)
			(layer "F.SilkS")
		)
		(fp_line
			(start 20.91055 -5.976874)
			(end 20.922742 -6.04647)
			(stroke
				(width 0.1)
				(type default)
			)
			(layer "F.SilkS")
		)
		(fp_line
			(start 20.91055 -5.976874)
			(end 20.922742 -6.04647)
			(stroke
				(width 0.1)
				(type default)
			)
			(layer "F.SilkS")
		)
		(fp_line
			(start 20.913344 -5.171694)
			(end 19.384518 -3.704844)
			(stroke
				(width 0.1)
				(type default)
			)
			(layer "F.SilkS")
		)
		(fp_line
			(start 20.913344 -5.171694)
			(end 19.384518 -3.704844)
			(stroke
				(width 0.1)
				(type default)
			)
			(layer "F.SilkS")
		)
		(fp_line
			(start 20.913344 -5.171694)
			(end 20.8534 -5.171694)
			(stroke
				(width 0.1)
				(type default)
			)
			(layer "F.SilkS")
		)
		(fp_line
			(start 20.913344 -5.171694)
			(end 20.8534 -5.171694)
			(stroke
				(width 0.1)
				(type default)
			)
			(layer "F.SilkS")
		)
		(fp_line
			(start 20.922742 -6.04647)
			(end 20.93468 -6.115558)
			(stroke
				(width 0.1)
				(type default)
			)
			(layer "F.SilkS")
		)
		(fp_line
			(start 20.922742 -6.04647)
			(end 20.93468 -6.115558)
			(stroke
				(width 0.1)
				(type default)
			)
			(layer "F.SilkS")
		)
		(fp_line
			(start 20.93468 -6.115558)
			(end 20.947126 -6.1849)
			(stroke
				(width 0.1)
				(type default)
			)
			(layer "F.SilkS")
		)
		(fp_line
			(start 20.93468 -6.115558)
			(end 20.947126 -6.1849)
			(stroke
				(width 0.1)
				(type default)
			)
			(layer "F.SilkS")
		)
		(fp_line
			(start 20.947126 -6.1849)
			(end 20.959318 -6.254496)
			(stroke
				(width 0.1)
				(type default)
			)
			(layer "F.SilkS")
		)
		(fp_line
			(start 20.947126 -6.1849)
			(end 20.959318 -6.254496)
			(stroke
				(width 0.1)
				(type default)
			)
			(layer "F.SilkS")
		)
		(fp_line
			(start 20.949666 -4.109466)
			(end 20.889214 -4.109466)
			(stroke
				(width 0.1)
				(type default)
			)
			(layer "F.SilkS")
		)
		(fp_line
			(start 20.949666 -4.109466)
			(end 20.889214 -4.109466)
			(stroke
				(width 0.1)
				(type default)
			)
			(layer "F.SilkS")
		)
		(fp_line
			(start 20.959318 -6.254496)
			(end 20.97151 -6.324092)
			(stroke
				(width 0.1)
				(type default)
			)
			(layer "F.SilkS")
		)
		(fp_line
			(start 20.959318 -6.254496)
			(end 20.97151 -6.324092)
			(stroke
				(width 0.1)
				(type default)
			)
			(layer "F.SilkS")
		)
		(fp_line
			(start 20.97151 -6.324092)
			(end 18.75155 -4.194556)
			(stroke
				(width 0.1)
				(type default)
			)
			(layer "F.SilkS")
		)
		(fp_line
			(start 20.97151 -6.324092)
			(end 18.75155 -4.194556)
			(stroke
				(width 0.1)
				(type default)
			)
			(layer "F.SilkS")
		)
		(fp_line
			(start 20.97151 -6.324092)
			(end 20.983702 -6.393434)
			(stroke
				(width 0.1)
				(type default)
			)
			(layer "F.SilkS")
		)
		(fp_line
			(start 20.97151 -6.324092)
			(end 20.983702 -6.393434)
			(stroke
				(width 0.1)
				(type default)
			)
			(layer "F.SilkS")
		)
		(fp_line
			(start 20.973542 -5.171694)
			(end 19.372326 -3.635502)
			(stroke
				(width 0.1)
				(type default)
			)
			(layer "F.SilkS")
		)
		(fp_line
			(start 20.973542 -5.171694)
			(end 19.372326 -3.635502)
			(stroke
				(width 0.1)
				(type default)
			)
			(layer "F.SilkS")
		)
		(fp_line
			(start 20.973542 -5.171694)
			(end 20.913344 -5.171694)
			(stroke
				(width 0.1)
				(type default)
			)
			(layer "F.SilkS")
		)
		(fp_line
			(start 20.973542 -5.171694)
			(end 20.913344 -5.171694)
			(stroke
				(width 0.1)
				(type default)
			)
			(layer "F.SilkS")
		)
		(fp_line
			(start 20.98294 -1.198626)
			(end 20.956524 -1.115314)
			(stroke
				(width 0.1)
				(type default)
			)
			(layer "F.SilkS")
		)
		(fp_line
			(start 20.98294 -1.198626)
			(end 20.956524 -1.115314)
			(stroke
				(width 0.1)
				(type default)
			)
			(layer "F.SilkS")
		)
		(fp_line
			(start 20.983702 -6.393434)
			(end 18.763996 -4.263898)
			(stroke
				(width 0.1)
				(type default)
			)
			(layer "F.SilkS")
		)
		(fp_line
			(start 20.983702 -6.393434)
			(end 18.763996 -4.263898)
			(stroke
				(width 0.1)
				(type default)
			)
			(layer "F.SilkS")
		)
		(fp_line
			(start 20.983702 -6.393434)
			(end 20.996148 -6.462522)
			(stroke
				(width 0.1)
				(type default)
			)
			(layer "F.SilkS")
		)
		(fp_line
			(start 20.983702 -6.393434)
			(end 20.996148 -6.462522)
			(stroke
				(width 0.1)
				(type default)
			)
			(layer "F.SilkS")
		)
		(fp_line
			(start 20.993354 -6.806438)
			(end 19.712686 -5.578094)
			(stroke
				(width 0.1)
				(type default)
			)
			(layer "F.SilkS")
		)
		(fp_line
			(start 20.993354 -6.806438)
			(end 19.712686 -5.578094)
			(stroke
				(width 0.1)
				(type default)
			)
			(layer "F.SilkS")
		)
		(fp_line
			(start 20.993354 -6.806438)
			(end 20.877784 -6.753606)
			(stroke
				(width 0.1)
				(type default)
			)
			(layer "F.SilkS")
		)
		(fp_line
			(start 20.993354 -6.806438)
			(end 20.877784 -6.753606)
			(stroke
				(width 0.1)
				(type default)
			)
			(layer "F.SilkS")
		)
		(fp_line
			(start 20.996148 -6.462522)
			(end 18.775934 -4.33324)
			(stroke
				(width 0.1)
				(type default)
			)
			(layer "F.SilkS")
		)
		(fp_line
			(start 20.996148 -6.462522)
			(end 18.775934 -4.33324)
			(stroke
				(width 0.1)
				(type default)
			)
			(layer "F.SilkS")
		)
		(fp_line
			(start 20.996148 -6.462522)
			(end 21.008086 -6.532118)
			(stroke
				(width 0.1)
				(type default)
			)
			(layer "F.SilkS")
		)
		(fp_line
			(start 20.996148 -6.462522)
			(end 21.008086 -6.532118)
			(stroke
				(width 0.1)
				(type default)
			)
			(layer "F.SilkS")
		)
		(fp_line
			(start 21.008086 -6.532118)
			(end 19.651726 -5.23113)
			(stroke
				(width 0.1)
				(type default)
			)
			(layer "F.SilkS")
		)
		(fp_line
			(start 21.008086 -6.532118)
			(end 19.651726 -5.23113)
			(stroke
				(width 0.1)
				(type default)
			)
			(layer "F.SilkS")
		)
		(fp_line
			(start 21.008086 -6.532118)
			(end 21.020278 -6.60146)
			(stroke
				(width 0.1)
				(type default)
			)
			(layer "F.SilkS")
		)
		(fp_line
			(start 21.008086 -6.532118)
			(end 21.020278 -6.60146)
			(stroke
				(width 0.1)
				(type default)
			)
			(layer "F.SilkS")
		)
		(fp_line
			(start 21.00961 -4.109466)
			(end 20.949666 -4.109466)
			(stroke
				(width 0.1)
				(type default)
			)
			(layer "F.SilkS")
		)
		(fp_line
			(start 21.00961 -4.109466)
			(end 20.949666 -4.109466)
			(stroke
				(width 0.1)
				(type default)
			)
			(layer "F.SilkS")
		)
		(fp_line
			(start 21.00961 -4.109466)
			(end 21.069554 -4.109466)
			(stroke
				(width 0.1)
				(type default)
			)
			(layer "F.SilkS")
		)
		(fp_line
			(start 21.00961 -4.109466)
			(end 21.069554 -4.109466)
			(stroke
				(width 0.1)
				(type default)
			)
			(layer "F.SilkS")
		)
		(fp_line
			(start 21.00961 -1.281684)
			(end 20.98294 -1.198626)
			(stroke
				(width 0.1)
				(type default)
			)
			(layer "F.SilkS")
		)
		(fp_line
			(start 21.00961 -1.281684)
			(end 20.98294 -1.198626)
			(stroke
				(width 0.1)
				(type default)
			)
			(layer "F.SilkS")
		)
		(fp_line
			(start 21.020278 -6.60146)
			(end 19.664172 -5.300472)
			(stroke
				(width 0.1)
				(type default)
			)
			(layer "F.SilkS")
		)
		(fp_line
			(start 21.020278 -6.60146)
			(end 19.664172 -5.300472)
			(stroke
				(width 0.1)
				(type default)
			)
			(layer "F.SilkS")
		)
		(fp_line
			(start 21.020278 -6.60146)
			(end 21.03247 -6.671056)
			(stroke
				(width 0.1)
				(type default)
			)
			(layer "F.SilkS")
		)
		(fp_line
			(start 21.020278 -6.60146)
			(end 21.03247 -6.671056)
			(stroke
				(width 0.1)
				(type default)
			)
			(layer "F.SilkS")
		)
		(fp_line
			(start 21.03247 -6.671056)
			(end 19.676364 -5.370068)
			(stroke
				(width 0.1)
				(type default)
			)
			(layer "F.SilkS")
		)
		(fp_line
			(start 21.03247 -6.671056)
			(end 19.676364 -5.370068)
			(stroke
				(width 0.1)
				(type default)
			)
			(layer "F.SilkS")
		)
		(fp_line
			(start 21.03247 -6.671056)
			(end 21.044662 -6.740144)
			(stroke
				(width 0.1)
				(type default)
			)
			(layer "F.SilkS")
		)
		(fp_line
			(start 21.03247 -6.671056)
			(end 21.044662 -6.740144)
			(stroke
				(width 0.1)
				(type default)
			)
			(layer "F.SilkS")
		)
		(fp_line
			(start 21.033994 -5.171694)
			(end 19.35988 -3.56616)
			(stroke
				(width 0.1)
				(type default)
			)
			(layer "F.SilkS")
		)
		(fp_line
			(start 21.033994 -5.171694)
			(end 19.35988 -3.56616)
			(stroke
				(width 0.1)
				(type default)
			)
			(layer "F.SilkS")
		)
		(fp_line
			(start 21.033994 -5.171694)
			(end 20.973542 -5.171694)
			(stroke
				(width 0.1)
				(type default)
			)
			(layer "F.SilkS")
		)
		(fp_line
			(start 21.033994 -5.171694)
			(end 20.973542 -5.171694)
			(stroke
				(width 0.1)
				(type default)
			)
			(layer "F.SilkS")
		)
		(fp_line
			(start 21.035772 -1.364742)
			(end 21.00961 -1.281684)
			(stroke
				(width 0.1)
				(type default)
			)
			(layer "F.SilkS")
		)
		(fp_line
			(start 21.035772 -1.364742)
			(end 21.00961 -1.281684)
			(stroke
				(width 0.1)
				(type default)
			)
			(layer "F.SilkS")
		)
		(fp_line
			(start 21.044662 -6.740144)
			(end 19.688302 -5.439156)
			(stroke
				(width 0.1)
				(type default)
			)
			(layer "F.SilkS")
		)
		(fp_line
			(start 21.044662 -6.740144)
			(end 19.688302 -5.439156)
			(stroke
				(width 0.1)
				(type default)
			)
			(layer "F.SilkS")
		)
		(fp_line
			(start 21.044662 -6.740144)
			(end 21.057108 -6.80974)
			(stroke
				(width 0.1)
				(type default)
			)
			(layer "F.SilkS")
		)
		(fp_line
			(start 21.044662 -6.740144)
			(end 21.057108 -6.80974)
			(stroke
				(width 0.1)
				(type default)
			)
			(layer "F.SilkS")
		)
		(fp_line
			(start 21.057108 -6.80974)
			(end 19.700748 -5.508752)
			(stroke
				(width 0.1)
				(type default)
			)
			(layer "F.SilkS")
		)
		(fp_line
			(start 21.057108 -6.80974)
			(end 19.700748 -5.508752)
			(stroke
				(width 0.1)
				(type default)
			)
			(layer "F.SilkS")
		)
		(fp_line
			(start 21.057108 -6.80974)
			(end 21.061934 -6.838188)
			(stroke
				(width 0.1)
				(type default)
			)
			(layer "F.SilkS")
		)
		(fp_line
			(start 21.057108 -6.80974)
			(end 21.061934 -6.838188)
			(stroke
				(width 0.1)
				(type default)
			)
			(layer "F.SilkS")
		)
		(fp_line
			(start 21.061934 -6.838188)
			(end 20.993354 -6.806438)
			(stroke
				(width 0.1)
				(type default)
			)
			(layer "F.SilkS")
		)
		(fp_line
			(start 21.061934 -6.838188)
			(end 20.993354 -6.806438)
			(stroke
				(width 0.1)
				(type default)
			)
			(layer "F.SilkS")
		)
		(fp_line
			(start 21.062188 -1.447546)
			(end 21.035772 -1.364742)
			(stroke
				(width 0.1)
				(type default)
			)
			(layer "F.SilkS")
		)
		(fp_line
			(start 21.062188 -1.447546)
			(end 21.035772 -1.364742)
			(stroke
				(width 0.1)
				(type default)
			)
			(layer "F.SilkS")
		)
		(fp_line
			(start 21.069554 -4.109466)
			(end 21.129752 -4.109466)
			(stroke
				(width 0.1)
				(type default)
			)
			(layer "F.SilkS")
		)
		(fp_line
			(start 21.069554 -4.109466)
			(end 21.129752 -4.109466)
			(stroke
				(width 0.1)
				(type default)
			)
			(layer "F.SilkS")
		)
		(fp_line
			(start 21.088858 -1.530604)
			(end 21.062188 -1.447546)
			(stroke
				(width 0.1)
				(type default)
			)
			(layer "F.SilkS")
		)
		(fp_line
			(start 21.088858 -1.530604)
			(end 21.062188 -1.447546)
			(stroke
				(width 0.1)
				(type default)
			)
			(layer "F.SilkS")
		)
		(fp_line
			(start 21.093938 -5.171694)
			(end 19.347942 -3.496564)
			(stroke
				(width 0.1)
				(type default)
			)
			(layer "F.SilkS")
		)
		(fp_line
			(start 21.093938 -5.171694)
			(end 19.347942 -3.496564)
			(stroke
				(width 0.1)
				(type default)
			)
			(layer "F.SilkS")
		)
		(fp_line
			(start 21.093938 -5.171694)
			(end 21.033994 -5.171694)
			(stroke
				(width 0.1)
				(type default)
			)
			(layer "F.SilkS")
		)
		(fp_line
			(start 21.093938 -5.171694)
			(end 21.033994 -5.171694)
			(stroke
				(width 0.1)
				(type default)
			)
			(layer "F.SilkS")
		)
		(fp_line
			(start 21.115274 -1.613916)
			(end 21.088858 -1.530604)
			(stroke
				(width 0.1)
				(type default)
			)
			(layer "F.SilkS")
		)
		(fp_line
			(start 21.115274 -1.613916)
			(end 21.088858 -1.530604)
			(stroke
				(width 0.1)
				(type default)
			)
			(layer "F.SilkS")
		)
		(fp_line
			(start 21.129752 -4.109466)
			(end 21.18995 -4.109466)
			(stroke
				(width 0.1)
				(type default)
			)
			(layer "F.SilkS")
		)
		(fp_line
			(start 21.129752 -4.109466)
			(end 21.18995 -4.109466)
			(stroke
				(width 0.1)
				(type default)
			)
			(layer "F.SilkS")
		)
		(fp_line
			(start 21.141436 -1.69672)
			(end 21.115274 -1.613916)
			(stroke
				(width 0.1)
				(type default)
			)
			(layer "F.SilkS")
		)
		(fp_line
			(start 21.141436 -1.69672)
			(end 21.115274 -1.613916)
			(stroke
				(width 0.1)
				(type default)
			)
			(layer "F.SilkS")
		)
		(fp_line
			(start 21.154136 -5.171694)
			(end 19.33575 -3.427476)
			(stroke
				(width 0.1)
				(type default)
			)
			(layer "F.SilkS")
		)
		(fp_line
			(start 21.154136 -5.171694)
			(end 19.33575 -3.427476)
			(stroke
				(width 0.1)
				(type default)
			)
			(layer "F.SilkS")
		)
		(fp_line
			(start 21.154136 -5.171694)
			(end 21.093938 -5.171694)
			(stroke
				(width 0.1)
				(type default)
			)
			(layer "F.SilkS")
		)
		(fp_line
			(start 21.154136 -5.171694)
			(end 21.093938 -5.171694)
			(stroke
				(width 0.1)
				(type default)
			)
			(layer "F.SilkS")
		)
		(fp_line
			(start 21.167852 -1.779778)
			(end 21.141436 -1.69672)
			(stroke
				(width 0.1)
				(type default)
			)
			(layer "F.SilkS")
		)
		(fp_line
			(start 21.167852 -1.779778)
			(end 21.141436 -1.69672)
			(stroke
				(width 0.1)
				(type default)
			)
			(layer "F.SilkS")
		)
		(fp_line
			(start 21.18995 -4.109466)
			(end 21.250402 -4.109466)
			(stroke
				(width 0.1)
				(type default)
			)
			(layer "F.SilkS")
		)
		(fp_line
			(start 21.18995 -4.109466)
			(end 21.250402 -4.109466)
			(stroke
				(width 0.1)
				(type default)
			)
			(layer "F.SilkS")
		)
		(fp_line
			(start 21.194268 -1.862836)
			(end 21.167852 -1.779778)
			(stroke
				(width 0.1)
				(type default)
			)
			(layer "F.SilkS")
		)
		(fp_line
			(start 21.194268 -1.862836)
			(end 21.167852 -1.779778)
			(stroke
				(width 0.1)
				(type default)
			)
			(layer "F.SilkS")
		)
		(fp_line
			(start 21.21408 -5.171694)
			(end 19.323558 -3.358134)
			(stroke
				(width 0.1)
				(type default)
			)
			(layer "F.SilkS")
		)
		(fp_line
			(start 21.21408 -5.171694)
			(end 19.323558 -3.358134)
			(stroke
				(width 0.1)
				(type default)
			)
			(layer "F.SilkS")
		)
		(fp_line
			(start 21.21408 -5.171694)
			(end 21.154136 -5.171694)
			(stroke
				(width 0.1)
				(type default)
			)
			(layer "F.SilkS")
		)
		(fp_line
			(start 21.21408 -5.171694)
			(end 21.154136 -5.171694)
			(stroke
				(width 0.1)
				(type default)
			)
			(layer "F.SilkS")
		)
		(fp_line
			(start 21.220684 -1.946148)
			(end 21.194268 -1.862836)
			(stroke
				(width 0.1)
				(type default)
			)
			(layer "F.SilkS")
		)
		(fp_line
			(start 21.220684 -1.946148)
			(end 21.194268 -1.862836)
			(stroke
				(width 0.1)
				(type default)
			)
			(layer "F.SilkS")
		)
		(fp_line
			(start 21.2471 -2.028952)
			(end 21.220684 -1.946148)
			(stroke
				(width 0.1)
				(type default)
			)
			(layer "F.SilkS")
		)
		(fp_line
			(start 21.2471 -2.028952)
			(end 21.220684 -1.946148)
			(stroke
				(width 0.1)
				(type default)
			)
			(layer "F.SilkS")
		)
		(fp_line
			(start 21.250402 -4.109466)
			(end 21.310346 -4.109466)
			(stroke
				(width 0.1)
				(type default)
			)
			(layer "F.SilkS")
		)
		(fp_line
			(start 21.250402 -4.109466)
			(end 21.310346 -4.109466)
			(stroke
				(width 0.1)
				(type default)
			)
			(layer "F.SilkS")
		)
		(fp_line
			(start 21.273516 -2.11201)
			(end 21.2471 -2.028952)
			(stroke
				(width 0.1)
				(type default)
			)
			(layer "F.SilkS")
		)
		(fp_line
			(start 21.273516 -2.11201)
			(end 21.2471 -2.028952)
			(stroke
				(width 0.1)
				(type default)
			)
			(layer "F.SilkS")
		)
		(fp_line
			(start 21.274532 -5.171694)
			(end 19.311366 -3.288538)
			(stroke
				(width 0.1)
				(type default)
			)
			(layer "F.SilkS")
		)
		(fp_line
			(start 21.274532 -5.171694)
			(end 19.311366 -3.288538)
			(stroke
				(width 0.1)
				(type default)
			)
			(layer "F.SilkS")
		)
		(fp_line
			(start 21.274532 -5.171694)
			(end 21.21408 -5.171694)
			(stroke
				(width 0.1)
				(type default)
			)
			(layer "F.SilkS")
		)
		(fp_line
			(start 21.274532 -5.171694)
			(end 21.21408 -5.171694)
			(stroke
				(width 0.1)
				(type default)
			)
			(layer "F.SilkS")
		)
		(fp_line
			(start 21.299932 -2.195068)
			(end 21.273516 -2.11201)
			(stroke
				(width 0.1)
				(type default)
			)
			(layer "F.SilkS")
		)
		(fp_line
			(start 21.299932 -2.195068)
			(end 21.273516 -2.11201)
			(stroke
				(width 0.1)
				(type default)
			)
			(layer "F.SilkS")
		)
		(fp_line
			(start 21.310346 -4.109466)
			(end 21.370544 -4.109466)
			(stroke
				(width 0.1)
				(type default)
			)
			(layer "F.SilkS")
		)
		(fp_line
			(start 21.310346 -4.109466)
			(end 21.370544 -4.109466)
			(stroke
				(width 0.1)
				(type default)
			)
			(layer "F.SilkS")
		)
		(fp_line
			(start 21.33473 -5.171694)
			(end 19.299428 -3.218942)
			(stroke
				(width 0.1)
				(type default)
			)
			(layer "F.SilkS")
		)
		(fp_line
			(start 21.33473 -5.171694)
			(end 19.299428 -3.218942)
			(stroke
				(width 0.1)
				(type default)
			)
			(layer "F.SilkS")
		)
		(fp_line
			(start 21.33473 -5.171694)
			(end 21.274532 -5.171694)
			(stroke
				(width 0.1)
				(type default)
			)
			(layer "F.SilkS")
		)
		(fp_line
			(start 21.33473 -5.171694)
			(end 21.274532 -5.171694)
			(stroke
				(width 0.1)
				(type default)
			)
			(layer "F.SilkS")
		)
		(fp_line
			(start 21.370544 -4.109466)
			(end 21.430742 -4.109466)
			(stroke
				(width 0.1)
				(type default)
			)
			(layer "F.SilkS")
		)
		(fp_line
			(start 21.370544 -4.109466)
			(end 21.430742 -4.109466)
			(stroke
				(width 0.1)
				(type default)
			)
			(layer "F.SilkS")
		)
		(fp_line
			(start 21.394674 -5.171694)
			(end 19.286982 -3.149854)
			(stroke
				(width 0.1)
				(type default)
			)
			(layer "F.SilkS")
		)
		(fp_line
			(start 21.394674 -5.171694)
			(end 19.286982 -3.149854)
			(stroke
				(width 0.1)
				(type default)
			)
			(layer "F.SilkS")
		)
		(fp_line
			(start 21.394674 -5.171694)
			(end 21.33473 -5.171694)
			(stroke
				(width 0.1)
				(type default)
			)
			(layer "F.SilkS")
		)
		(fp_line
			(start 21.394674 -5.171694)
			(end 21.33473 -5.171694)
			(stroke
				(width 0.1)
				(type default)
			)
			(layer "F.SilkS")
		)
		(fp_line
			(start 21.430742 -4.109466)
			(end 21.490686 -4.109466)
			(stroke
				(width 0.1)
				(type default)
			)
			(layer "F.SilkS")
		)
		(fp_line
			(start 21.430742 -4.109466)
			(end 21.490686 -4.109466)
			(stroke
				(width 0.1)
				(type default)
			)
			(layer "F.SilkS")
		)
		(fp_line
			(start 21.454872 -5.171694)
			(end 19.27479 -3.080512)
			(stroke
				(width 0.1)
				(type default)
			)
			(layer "F.SilkS")
		)
		(fp_line
			(start 21.454872 -5.171694)
			(end 19.27479 -3.080512)
			(stroke
				(width 0.1)
				(type default)
			)
			(layer "F.SilkS")
		)
		(fp_line
			(start 21.454872 -5.171694)
			(end 21.394674 -5.171694)
			(stroke
				(width 0.1)
				(type default)
			)
			(layer "F.SilkS")
		)
		(fp_line
			(start 21.454872 -5.171694)
			(end 21.394674 -5.171694)
			(stroke
				(width 0.1)
				(type default)
			)
			(layer "F.SilkS")
		)
		(fp_line
			(start 21.490686 -4.109466)
			(end 21.55063 -4.109466)
			(stroke
				(width 0.1)
				(type default)
			)
			(layer "F.SilkS")
		)
		(fp_line
			(start 21.490686 -4.109466)
			(end 21.55063 -4.109466)
			(stroke
				(width 0.1)
				(type default)
			)
			(layer "F.SilkS")
		)
		(fp_line
			(start 21.515324 -5.171694)
			(end 19.262852 -3.01117)
			(stroke
				(width 0.1)
				(type default)
			)
			(layer "F.SilkS")
		)
		(fp_line
			(start 21.515324 -5.171694)
			(end 19.262852 -3.01117)
			(stroke
				(width 0.1)
				(type default)
			)
			(layer "F.SilkS")
		)
		(fp_line
			(start 21.515324 -5.171694)
			(end 21.454872 -5.171694)
			(stroke
				(width 0.1)
				(type default)
			)
			(layer "F.SilkS")
		)
		(fp_line
			(start 21.515324 -5.171694)
			(end 21.454872 -5.171694)
			(stroke
				(width 0.1)
				(type default)
			)
			(layer "F.SilkS")
		)
		(fp_line
			(start 21.55063 -4.109466)
			(end 21.611082 -4.109466)
			(stroke
				(width 0.1)
				(type default)
			)
			(layer "F.SilkS")
		)
		(fp_line
			(start 21.55063 -4.109466)
			(end 21.611082 -4.109466)
			(stroke
				(width 0.1)
				(type default)
			)
			(layer "F.SilkS")
		)
		(fp_line
			(start 21.575522 -5.171694)
			(end 19.250406 -2.941574)
			(stroke
				(width 0.1)
				(type default)
			)
			(layer "F.SilkS")
		)
		(fp_line
			(start 21.575522 -5.171694)
			(end 19.250406 -2.941574)
			(stroke
				(width 0.1)
				(type default)
			)
			(layer "F.SilkS")
		)
		(fp_line
			(start 21.575522 -5.171694)
			(end 21.515324 -5.171694)
			(stroke
				(width 0.1)
				(type default)
			)
			(layer "F.SilkS")
		)
		(fp_line
			(start 21.575522 -5.171694)
			(end 21.515324 -5.171694)
			(stroke
				(width 0.1)
				(type default)
			)
			(layer "F.SilkS")
		)
		(fp_line
			(start 21.612352 -4.109466)
			(end 21.611082 -4.109466)
			(stroke
				(width 0.1)
				(type default)
			)
			(layer "F.SilkS")
		)
		(fp_line
			(start 21.612352 -4.109466)
			(end 21.611082 -4.109466)
			(stroke
				(width 0.1)
				(type default)
			)
			(layer "F.SilkS")
		)
		(fp_line
			(start 21.61286 -4.11099)
			(end 21.611082 -4.109466)
			(stroke
				(width 0.1)
				(type default)
			)
			(layer "F.SilkS")
		)
		(fp_line
			(start 21.61286 -4.11099)
			(end 21.611082 -4.109466)
			(stroke
				(width 0.1)
				(type default)
			)
			(layer "F.SilkS")
		)
		(fp_line
			(start 21.61286 -4.11099)
			(end 21.612352 -4.109466)
			(stroke
				(width 0.1)
				(type default)
			)
			(layer "F.SilkS")
		)
		(fp_line
			(start 21.61286 -4.11099)
			(end 21.612352 -4.109466)
			(stroke
				(width 0.1)
				(type default)
			)
			(layer "F.SilkS")
		)
		(fp_line
			(start 21.61286 -4.11099)
			(end 21.624798 -4.180586)
			(stroke
				(width 0.1)
				(type default)
			)
			(layer "F.SilkS")
		)
		(fp_line
			(start 21.61286 -4.11099)
			(end 21.624798 -4.180586)
			(stroke
				(width 0.1)
				(type default)
			)
			(layer "F.SilkS")
		)
		(fp_line
			(start 21.624798 -4.180586)
			(end 21.55063 -4.109466)
			(stroke
				(width 0.1)
				(type default)
			)
			(layer "F.SilkS")
		)
		(fp_line
			(start 21.624798 -4.180586)
			(end 21.55063 -4.109466)
			(stroke
				(width 0.1)
				(type default)
			)
			(layer "F.SilkS")
		)
		(fp_line
			(start 21.624798 -4.180586)
			(end 21.636736 -4.249674)
			(stroke
				(width 0.1)
				(type default)
			)
			(layer "F.SilkS")
		)
		(fp_line
			(start 21.624798 -4.180586)
			(end 21.636736 -4.249674)
			(stroke
				(width 0.1)
				(type default)
			)
			(layer "F.SilkS")
		)
		(fp_line
			(start 21.635466 -5.171694)
			(end 21.575522 -5.171694)
			(stroke
				(width 0.1)
				(type default)
			)
			(layer "F.SilkS")
		)
		(fp_line
			(start 21.635466 -5.171694)
			(end 21.575522 -5.171694)
			(stroke
				(width 0.1)
				(type default)
			)
			(layer "F.SilkS")
		)
		(fp_line
			(start 21.636736 -4.249674)
			(end 21.490686 -4.109466)
			(stroke
				(width 0.1)
				(type default)
			)
			(layer "F.SilkS")
		)
		(fp_line
			(start 21.636736 -4.249674)
			(end 21.490686 -4.109466)
			(stroke
				(width 0.1)
				(type default)
			)
			(layer "F.SilkS")
		)
		(fp_line
			(start 21.636736 -4.249674)
			(end 21.649182 -4.319016)
			(stroke
				(width 0.1)
				(type default)
			)
			(layer "F.SilkS")
		)
		(fp_line
			(start 21.636736 -4.249674)
			(end 21.649182 -4.319016)
			(stroke
				(width 0.1)
				(type default)
			)
			(layer "F.SilkS")
		)
		(fp_line
			(start 21.649182 -4.319016)
			(end 21.430742 -4.109466)
			(stroke
				(width 0.1)
				(type default)
			)
			(layer "F.SilkS")
		)
		(fp_line
			(start 21.649182 -4.319016)
			(end 21.430742 -4.109466)
			(stroke
				(width 0.1)
				(type default)
			)
			(layer "F.SilkS")
		)
		(fp_line
			(start 21.649182 -4.319016)
			(end 21.661374 -4.388358)
			(stroke
				(width 0.1)
				(type default)
			)
			(layer "F.SilkS")
		)
		(fp_line
			(start 21.649182 -4.319016)
			(end 21.661374 -4.388358)
			(stroke
				(width 0.1)
				(type default)
			)
			(layer "F.SilkS")
		)
		(fp_line
			(start 21.661374 -4.388358)
			(end 21.370544 -4.109466)
			(stroke
				(width 0.1)
				(type default)
			)
			(layer "F.SilkS")
		)
		(fp_line
			(start 21.661374 -4.388358)
			(end 21.370544 -4.109466)
			(stroke
				(width 0.1)
				(type default)
			)
			(layer "F.SilkS")
		)
		(fp_line
			(start 21.661374 -4.388358)
			(end 21.673312 -4.457954)
			(stroke
				(width 0.1)
				(type default)
			)
			(layer "F.SilkS")
		)
		(fp_line
			(start 21.661374 -4.388358)
			(end 21.673312 -4.457954)
			(stroke
				(width 0.1)
				(type default)
			)
			(layer "F.SilkS")
		)
		(fp_line
			(start 21.673312 -4.457954)
			(end 21.310346 -4.109466)
			(stroke
				(width 0.1)
				(type default)
			)
			(layer "F.SilkS")
		)
		(fp_line
			(start 21.673312 -4.457954)
			(end 21.310346 -4.109466)
			(stroke
				(width 0.1)
				(type default)
			)
			(layer "F.SilkS")
		)
		(fp_line
			(start 21.673312 -4.457954)
			(end 21.685504 -4.527296)
			(stroke
				(width 0.1)
				(type default)
			)
			(layer "F.SilkS")
		)
		(fp_line
			(start 21.673312 -4.457954)
			(end 21.685504 -4.527296)
			(stroke
				(width 0.1)
				(type default)
			)
			(layer "F.SilkS")
		)
		(fp_line
			(start 21.685504 -4.527296)
			(end 21.250402 -4.109466)
			(stroke
				(width 0.1)
				(type default)
			)
			(layer "F.SilkS")
		)
		(fp_line
			(start 21.685504 -4.527296)
			(end 21.250402 -4.109466)
			(stroke
				(width 0.1)
				(type default)
			)
			(layer "F.SilkS")
		)
		(fp_line
			(start 21.685504 -4.527296)
			(end 21.69795 -4.596638)
			(stroke
				(width 0.1)
				(type default)
			)
			(layer "F.SilkS")
		)
		(fp_line
			(start 21.685504 -4.527296)
			(end 21.69795 -4.596638)
			(stroke
				(width 0.1)
				(type default)
			)
			(layer "F.SilkS")
		)
		(fp_line
			(start 21.69541 -5.171694)
			(end 20.588224 -4.109466)
			(stroke
				(width 0.1)
				(type default)
			)
			(layer "F.SilkS")
		)
		(fp_line
			(start 21.69541 -5.171694)
			(end 20.588224 -4.109466)
			(stroke
				(width 0.1)
				(type default)
			)
			(layer "F.SilkS")
		)
		(fp_line
			(start 21.69541 -5.171694)
			(end 21.635466 -5.171694)
			(stroke
				(width 0.1)
				(type default)
			)
			(layer "F.SilkS")
		)
		(fp_line
			(start 21.69541 -5.171694)
			(end 21.635466 -5.171694)
			(stroke
				(width 0.1)
				(type default)
			)
			(layer "F.SilkS")
		)
		(fp_line
			(start 21.69795 -4.596638)
			(end 21.18995 -4.109466)
			(stroke
				(width 0.1)
				(type default)
			)
			(layer "F.SilkS")
		)
		(fp_line
			(start 21.69795 -4.596638)
			(end 21.18995 -4.109466)
			(stroke
				(width 0.1)
				(type default)
			)
			(layer "F.SilkS")
		)
		(fp_line
			(start 21.69795 -4.596638)
			(end 21.709888 -4.66598)
			(stroke
				(width 0.1)
				(type default)
			)
			(layer "F.SilkS")
		)
		(fp_line
			(start 21.69795 -4.596638)
			(end 21.709888 -4.66598)
			(stroke
				(width 0.1)
				(type default)
			)
			(layer "F.SilkS")
		)
		(fp_line
			(start 21.709888 -4.66598)
			(end 21.129752 -4.109466)
			(stroke
				(width 0.1)
				(type default)
			)
			(layer "F.SilkS")
		)
		(fp_line
			(start 21.709888 -4.66598)
			(end 21.129752 -4.109466)
			(stroke
				(width 0.1)
				(type default)
			)
			(layer "F.SilkS")
		)
		(fp_line
			(start 21.709888 -4.66598)
			(end 21.721826 -4.735576)
			(stroke
				(width 0.1)
				(type default)
			)
			(layer "F.SilkS")
		)
		(fp_line
			(start 21.709888 -4.66598)
			(end 21.721826 -4.735576)
			(stroke
				(width 0.1)
				(type default)
			)
			(layer "F.SilkS")
		)
		(fp_line
			(start 21.721826 -4.735576)
			(end 21.069554 -4.109466)
			(stroke
				(width 0.1)
				(type default)
			)
			(layer "F.SilkS")
		)
		(fp_line
			(start 21.721826 -4.735576)
			(end 21.069554 -4.109466)
			(stroke
				(width 0.1)
				(type default)
			)
			(layer "F.SilkS")
		)
		(fp_line
			(start 21.721826 -4.735576)
			(end 21.734018 -4.804664)
			(stroke
				(width 0.1)
				(type default)
			)
			(layer "F.SilkS")
		)
		(fp_line
			(start 21.721826 -4.735576)
			(end 21.734018 -4.804664)
			(stroke
				(width 0.1)
				(type default)
			)
			(layer "F.SilkS")
		)
		(fp_line
			(start 21.734018 -4.804664)
			(end 21.00961 -4.109466)
			(stroke
				(width 0.1)
				(type default)
			)
			(layer "F.SilkS")
		)
		(fp_line
			(start 21.734018 -4.804664)
			(end 21.00961 -4.109466)
			(stroke
				(width 0.1)
				(type default)
			)
			(layer "F.SilkS")
		)
		(fp_line
			(start 21.734018 -4.804664)
			(end 21.746464 -4.874006)
			(stroke
				(width 0.1)
				(type default)
			)
			(layer "F.SilkS")
		)
		(fp_line
			(start 21.734018 -4.804664)
			(end 21.746464 -4.874006)
			(stroke
				(width 0.1)
				(type default)
			)
			(layer "F.SilkS")
		)
		(fp_line
			(start 21.746464 -4.874006)
			(end 20.949666 -4.109466)
			(stroke
				(width 0.1)
				(type default)
			)
			(layer "F.SilkS")
		)
		(fp_line
			(start 21.746464 -4.874006)
			(end 20.949666 -4.109466)
			(stroke
				(width 0.1)
				(type default)
			)
			(layer "F.SilkS")
		)
		(fp_line
			(start 21.746464 -4.874006)
			(end 21.758402 -4.943348)
			(stroke
				(width 0.1)
				(type default)
			)
			(layer "F.SilkS")
		)
		(fp_line
			(start 21.746464 -4.874006)
			(end 21.758402 -4.943348)
			(stroke
				(width 0.1)
				(type default)
			)
			(layer "F.SilkS")
		)
		(fp_line
			(start 21.755608 -5.171694)
			(end 20.648422 -4.109466)
			(stroke
				(width 0.1)
				(type default)
			)
			(layer "F.SilkS")
		)
		(fp_line
			(start 21.755608 -5.171694)
			(end 20.648422 -4.109466)
			(stroke
				(width 0.1)
				(type default)
			)
			(layer "F.SilkS")
		)
		(fp_line
			(start 21.755608 -5.171694)
			(end 21.69541 -5.171694)
			(stroke
				(width 0.1)
				(type default)
			)
			(layer "F.SilkS")
		)
		(fp_line
			(start 21.755608 -5.171694)
			(end 21.69541 -5.171694)
			(stroke
				(width 0.1)
				(type default)
			)
			(layer "F.SilkS")
		)
		(fp_line
			(start 21.758402 -4.943348)
			(end 20.889214 -4.109466)
			(stroke
				(width 0.1)
				(type default)
			)
			(layer "F.SilkS")
		)
		(fp_line
			(start 21.758402 -4.943348)
			(end 20.889214 -4.109466)
			(stroke
				(width 0.1)
				(type default)
			)
			(layer "F.SilkS")
		)
		(fp_line
			(start 21.758402 -4.943348)
			(end 21.770594 -5.012944)
			(stroke
				(width 0.1)
				(type default)
			)
			(layer "F.SilkS")
		)
		(fp_line
			(start 21.758402 -4.943348)
			(end 21.770594 -5.012944)
			(stroke
				(width 0.1)
				(type default)
			)
			(layer "F.SilkS")
		)
		(fp_line
			(start 21.770594 -5.012944)
			(end 20.829016 -4.109466)
			(stroke
				(width 0.1)
				(type default)
			)
			(layer "F.SilkS")
		)
		(fp_line
			(start 21.770594 -5.012944)
			(end 20.829016 -4.109466)
			(stroke
				(width 0.1)
				(type default)
			)
			(layer "F.SilkS")
		)
		(fp_line
			(start 21.770594 -5.012944)
			(end 21.78304 -5.082032)
			(stroke
				(width 0.1)
				(type default)
			)
			(layer "F.SilkS")
		)
		(fp_line
			(start 21.770594 -5.012944)
			(end 21.78304 -5.082032)
			(stroke
				(width 0.1)
				(type default)
			)
			(layer "F.SilkS")
		)
		(fp_line
			(start 21.78304 -5.082032)
			(end 20.768564 -4.109466)
			(stroke
				(width 0.1)
				(type default)
			)
			(layer "F.SilkS")
		)
		(fp_line
			(start 21.78304 -5.082032)
			(end 20.768564 -4.109466)
			(stroke
				(width 0.1)
				(type default)
			)
			(layer "F.SilkS")
		)
		(fp_line
			(start 21.78304 -5.082032)
			(end 21.794978 -5.151374)
			(stroke
				(width 0.1)
				(type default)
			)
			(layer "F.SilkS")
		)
		(fp_line
			(start 21.78304 -5.082032)
			(end 21.794978 -5.151374)
			(stroke
				(width 0.1)
				(type default)
			)
			(layer "F.SilkS")
		)
		(fp_line
			(start 21.794978 -5.151374)
			(end 20.70862 -4.109466)
			(stroke
				(width 0.1)
				(type default)
			)
			(layer "F.SilkS")
		)
		(fp_line
			(start 21.794978 -5.151374)
			(end 20.70862 -4.109466)
			(stroke
				(width 0.1)
				(type default)
			)
			(layer "F.SilkS")
		)
		(fp_line
			(start 21.794978 -5.151374)
			(end 21.798534 -5.171694)
			(stroke
				(width 0.1)
				(type default)
			)
			(layer "F.SilkS")
		)
		(fp_line
			(start 21.794978 -5.151374)
			(end 21.798534 -5.171694)
			(stroke
				(width 0.1)
				(type default)
			)
			(layer "F.SilkS")
		)
		(fp_line
			(start 21.798534 -5.171694)
			(end 21.755608 -5.171694)
			(stroke
				(width 0.1)
				(type default)
			)
			(layer "F.SilkS")
		)
		(fp_line
			(start 21.798534 -5.171694)
			(end 21.755608 -5.171694)
			(stroke
				(width 0.1)
				(type default)
			)
			(layer "F.SilkS")
		)
		(fp_line
			(start 21.838158 -2.018792)
			(end 23.619206 -3.727196)
			(stroke
				(width 0.1)
				(type default)
			)
			(layer "F.SilkS")
		)
		(fp_line
			(start 21.838158 -2.018792)
			(end 23.619206 -3.727196)
			(stroke
				(width 0.1)
				(type default)
			)
			(layer "F.SilkS")
		)
		(fp_line
			(start 21.839428 -2.07772)
			(end 23.55469 -3.723386)
			(stroke
				(width 0.1)
				(type default)
			)
			(layer "F.SilkS")
		)
		(fp_line
			(start 21.839428 -2.07772)
			(end 23.55469 -3.723386)
			(stroke
				(width 0.1)
				(type default)
			)
			(layer "F.SilkS")
		)
		(fp_line
			(start 21.841206 -2.137156)
			(end 23.489666 -3.71856)
			(stroke
				(width 0.1)
				(type default)
			)
			(layer "F.SilkS")
		)
		(fp_line
			(start 21.841206 -2.137156)
			(end 23.489666 -3.71856)
			(stroke
				(width 0.1)
				(type default)
			)
			(layer "F.SilkS")
		)
		(fp_line
			(start 21.841206 -1.90627)
			(end 23.747984 -3.735324)
			(stroke
				(width 0.1)
				(type default)
			)
			(layer "F.SilkS")
		)
		(fp_line
			(start 21.841206 -1.90627)
			(end 23.747984 -3.735324)
			(stroke
				(width 0.1)
				(type default)
			)
			(layer "F.SilkS")
		)
		(fp_line
			(start 21.846032 -1.853184)
			(end 23.811992 -3.739388)
			(stroke
				(width 0.1)
				(type default)
			)
			(layer "F.SilkS")
		)
		(fp_line
			(start 21.846032 -1.853184)
			(end 23.811992 -3.739388)
			(stroke
				(width 0.1)
				(type default)
			)
			(layer "F.SilkS")
		)
		(fp_line
			(start 21.849334 -2.202942)
			(end 23.414228 -3.703828)
			(stroke
				(width 0.1)
				(type default)
			)
			(layer "F.SilkS")
		)
		(fp_line
			(start 21.849334 -2.202942)
			(end 23.414228 -3.703828)
			(stroke
				(width 0.1)
				(type default)
			)
			(layer "F.SilkS")
		)
		(fp_line
			(start 21.850858 -1.799844)
			(end 23.874222 -3.740912)
			(stroke
				(width 0.1)
				(type default)
			)
			(layer "F.SilkS")
		)
		(fp_line
			(start 21.850858 -1.799844)
			(end 23.874222 -3.740912)
			(stroke
				(width 0.1)
				(type default)
			)
			(layer "F.SilkS")
		)
		(fp_line
			(start 21.85797 -2.268728)
			(end 23.338282 -3.688842)
			(stroke
				(width 0.1)
				(type default)
			)
			(layer "F.SilkS")
		)
		(fp_line
			(start 21.85797 -2.268728)
			(end 23.338282 -3.688842)
			(stroke
				(width 0.1)
				(type default)
			)
			(layer "F.SilkS")
		)
		(fp_line
			(start 21.86051 -1.75133)
			(end 23.930864 -3.737864)
			(stroke
				(width 0.1)
				(type default)
			)
			(layer "F.SilkS")
		)
		(fp_line
			(start 21.86051 -1.75133)
			(end 23.930864 -3.737864)
			(stroke
				(width 0.1)
				(type default)
			)
			(layer "F.SilkS")
		)
		(fp_line
			(start 21.869146 -2.337308)
			(end 23.26259 -3.673856)
			(stroke
				(width 0.1)
				(type default)
			)
			(layer "F.SilkS")
		)
		(fp_line
			(start 21.869146 -2.337308)
			(end 23.26259 -3.673856)
			(stroke
				(width 0.1)
				(type default)
			)
			(layer "F.SilkS")
		)
		(fp_line
			(start 21.870416 -1.703578)
			(end 23.98776 -3.734816)
			(stroke
				(width 0.1)
				(type default)
			)
			(layer "F.SilkS")
		)
		(fp_line
			(start 21.870416 -1.703578)
			(end 23.98776 -3.734816)
			(stroke
				(width 0.1)
				(type default)
			)
			(layer "F.SilkS")
		)
		(fp_line
			(start 21.88083 -1.655826)
			(end 24.04491 -3.731768)
			(stroke
				(width 0.1)
				(type default)
			)
			(layer "F.SilkS")
		)
		(fp_line
			(start 21.88083 -1.655826)
			(end 24.04491 -3.731768)
			(stroke
				(width 0.1)
				(type default)
			)
			(layer "F.SilkS")
		)
		(fp_line
			(start 21.89099 -2.416048)
			(end 23.187152 -3.659124)
			(stroke
				(width 0.1)
				(type default)
			)
			(layer "F.SilkS")
		)
		(fp_line
			(start 21.89099 -2.416048)
			(end 23.187152 -3.659124)
			(stroke
				(width 0.1)
				(type default)
			)
			(layer "F.SilkS")
		)
		(fp_line
			(start 21.894546 -1.611376)
			(end 24.101806 -3.728974)
			(stroke
				(width 0.1)
				(type default)
			)
			(layer "F.SilkS")
		)
		(fp_line
			(start 21.894546 -1.611376)
			(end 24.101806 -3.728974)
			(stroke
				(width 0.1)
				(type default)
			)
			(layer "F.SilkS")
		)
		(fp_line
			(start 21.909786 -1.568196)
			(end 24.154892 -3.721862)
			(stroke
				(width 0.1)
				(type default)
			)
			(layer "F.SilkS")
		)
		(fp_line
			(start 21.909786 -1.568196)
			(end 24.154892 -3.721862)
			(stroke
				(width 0.1)
				(type default)
			)
			(layer "F.SilkS")
		)
		(fp_line
			(start 21.913088 -2.494788)
			(end 23.10003 -3.63347)
			(stroke
				(width 0.1)
				(type default)
			)
			(layer "F.SilkS")
		)
		(fp_line
			(start 21.913088 -2.494788)
			(end 23.10003 -3.63347)
			(stroke
				(width 0.1)
				(type default)
			)
			(layer "F.SilkS")
		)
		(fp_line
			(start 21.924772 -1.525016)
			(end 24.205946 -3.712972)
			(stroke
				(width 0.1)
				(type default)
			)
			(layer "F.SilkS")
		)
		(fp_line
			(start 21.924772 -1.525016)
			(end 24.205946 -3.712972)
			(stroke
				(width 0.1)
				(type default)
			)
			(layer "F.SilkS")
		)
		(fp_line
			(start 21.93544 -2.573782)
			(end 23.00478 -3.599942)
			(stroke
				(width 0.1)
				(type default)
			)
			(layer "F.SilkS")
		)
		(fp_line
			(start 21.93544 -2.573782)
			(end 23.00478 -3.599942)
			(stroke
				(width 0.1)
				(type default)
			)
			(layer "F.SilkS")
		)
		(fp_line
			(start 21.942806 -1.484376)
			(end 23.220934 -2.710688)
			(stroke
				(width 0.1)
				(type default)
			)
			(layer "F.SilkS")
		)
		(fp_line
			(start 21.942806 -1.484376)
			(end 23.220934 -2.710688)
			(stroke
				(width 0.1)
				(type default)
			)
			(layer "F.SilkS")
		)
		(fp_line
			(start 21.957538 -2.652776)
			(end 22.909784 -3.56616)
			(stroke
				(width 0.1)
				(type default)
			)
			(layer "F.SilkS")
		)
		(fp_line
			(start 21.957538 -2.652776)
			(end 22.909784 -3.56616)
			(stroke
				(width 0.1)
				(type default)
			)
			(layer "F.SilkS")
		)
		(fp_line
			(start 21.962364 -1.445514)
			(end 23.052786 -2.491486)
			(stroke
				(width 0.1)
				(type default)
			)
			(layer "F.SilkS")
		)
		(fp_line
			(start 21.962364 -1.445514)
			(end 23.052786 -2.491486)
			(stroke
				(width 0.1)
				(type default)
			)
			(layer "F.SilkS")
		)
		(fp_line
			(start 21.981922 -1.406652)
			(end 23.020782 -2.403094)
			(stroke
				(width 0.1)
				(type default)
			)
			(layer "F.SilkS")
		)
		(fp_line
			(start 21.981922 -1.406652)
			(end 23.020782 -2.403094)
			(stroke
				(width 0.1)
				(type default)
			)
			(layer "F.SilkS")
		)
		(fp_line
			(start 22.003004 -1.36906)
			(end 22.99081 -2.31648)
			(stroke
				(width 0.1)
				(type default)
			)
			(layer "F.SilkS")
		)
		(fp_line
			(start 22.003004 -1.36906)
			(end 22.99081 -2.31648)
			(stroke
				(width 0.1)
				(type default)
			)
			(layer "F.SilkS")
		)
		(fp_line
			(start 22.017228 -2.767838)
			(end 22.802342 -3.521202)
			(stroke
				(width 0.1)
				(type default)
			)
			(layer "F.SilkS")
		)
		(fp_line
			(start 22.017228 -2.767838)
			(end 22.802342 -3.521202)
			(stroke
				(width 0.1)
				(type default)
			)
			(layer "F.SilkS")
		)
		(fp_line
			(start 22.02688 -1.334262)
			(end 22.984206 -2.252726)
			(stroke
				(width 0.1)
				(type default)
			)
			(layer "F.SilkS")
		)
		(fp_line
			(start 22.02688 -1.334262)
			(end 22.984206 -2.252726)
			(stroke
				(width 0.1)
				(type default)
			)
			(layer "F.SilkS")
		)
		(fp_line
			(start 22.05101 -1.299464)
			(end 22.981158 -2.19202)
			(stroke
				(width 0.1)
				(type default)
			)
			(layer "F.SilkS")
		)
		(fp_line
			(start 22.05101 -1.299464)
			(end 22.981158 -2.19202)
			(stroke
				(width 0.1)
				(type default)
			)
			(layer "F.SilkS")
		)
		(fp_line
			(start 22.07514 -1.265174)
			(end 22.985222 -2.137918)
			(stroke
				(width 0.1)
				(type default)
			)
			(layer "F.SilkS")
		)
		(fp_line
			(start 22.07514 -1.265174)
			(end 22.985222 -2.137918)
			(stroke
				(width 0.1)
				(type default)
			)
			(layer "F.SilkS")
		)
		(fp_line
			(start 22.077934 -2.883408)
			(end 22.662896 -3.444748)
			(stroke
				(width 0.1)
				(type default)
			)
			(layer "F.SilkS")
		)
		(fp_line
			(start 22.077934 -2.883408)
			(end 22.662896 -3.444748)
			(stroke
				(width 0.1)
				(type default)
			)
			(layer "F.SilkS")
		)
		(fp_line
			(start 22.10308 -1.233932)
			(end 22.992588 -2.087372)
			(stroke
				(width 0.1)
				(type default)
			)
			(layer "F.SilkS")
		)
		(fp_line
			(start 22.10308 -1.233932)
			(end 22.992588 -2.087372)
			(stroke
				(width 0.1)
				(type default)
			)
			(layer "F.SilkS")
		)
		(fp_line
			(start 22.130512 -1.202944)
			(end 23.005542 -2.042414)
			(stroke
				(width 0.1)
				(type default)
			)
			(layer "F.SilkS")
		)
		(fp_line
			(start 22.130512 -1.202944)
			(end 23.005542 -2.042414)
			(stroke
				(width 0.1)
				(type default)
			)
			(layer "F.SilkS")
		)
		(fp_line
			(start 22.158452 -1.171956)
			(end 23.020782 -1.99898)
			(stroke
				(width 0.1)
				(type default)
			)
			(layer "F.SilkS")
		)
		(fp_line
			(start 22.158452 -1.171956)
			(end 23.020782 -1.99898)
			(stroke
				(width 0.1)
				(type default)
			)
			(layer "F.SilkS")
		)
		(fp_line
			(start 22.18944 -1.143762)
			(end 23.042372 -1.96215)
			(stroke
				(width 0.1)
				(type default)
			)
			(layer "F.SilkS")
		)
		(fp_line
			(start 22.18944 -1.143762)
			(end 23.042372 -1.96215)
			(stroke
				(width 0.1)
				(type default)
			)
			(layer "F.SilkS")
		)
		(fp_line
			(start 22.22119 -1.11633)
			(end 23.06447 -1.925828)
			(stroke
				(width 0.1)
				(type default)
			)
			(layer "F.SilkS")
		)
		(fp_line
			(start 22.22119 -1.11633)
			(end 23.06447 -1.925828)
			(stroke
				(width 0.1)
				(type default)
			)
			(layer "F.SilkS")
		)
		(fp_line
			(start 22.252432 -1.089152)
			(end 23.094188 -1.896364)
			(stroke
				(width 0.1)
				(type default)
			)
			(layer "F.SilkS")
		)
		(fp_line
			(start 22.252432 -1.089152)
			(end 23.094188 -1.896364)
			(stroke
				(width 0.1)
				(type default)
			)
			(layer "F.SilkS")
		)
		(fp_line
			(start 22.286214 -1.063752)
			(end 23.124414 -1.867916)
			(stroke
				(width 0.1)
				(type default)
			)
			(layer "F.SilkS")
		)
		(fp_line
			(start 22.286214 -1.063752)
			(end 23.124414 -1.867916)
			(stroke
				(width 0.1)
				(type default)
			)
			(layer "F.SilkS")
		)
		(fp_line
			(start 22.321774 -1.039622)
			(end 23.158196 -1.842262)
			(stroke
				(width 0.1)
				(type default)
			)
			(layer "F.SilkS")
		)
		(fp_line
			(start 22.321774 -1.039622)
			(end 23.158196 -1.842262)
			(stroke
				(width 0.1)
				(type default)
			)
			(layer "F.SilkS")
		)
		(fp_line
			(start 22.356572 -1.015746)
			(end 23.197058 -1.821942)
			(stroke
				(width 0.1)
				(type default)
			)
			(layer "F.SilkS")
		)
		(fp_line
			(start 22.356572 -1.015746)
			(end 23.197058 -1.821942)
			(stroke
				(width 0.1)
				(type default)
			)
			(layer "F.SilkS")
		)
		(fp_line
			(start 22.393402 -0.993394)
			(end 23.235666 -1.801622)
			(stroke
				(width 0.1)
				(type default)
			)
			(layer "F.SilkS")
		)
		(fp_line
			(start 22.393402 -0.993394)
			(end 23.235666 -1.801622)
			(stroke
				(width 0.1)
				(type default)
			)
			(layer "F.SilkS")
		)
		(fp_line
			(start 22.43201 -0.97282)
			(end 23.280878 -1.786636)
			(stroke
				(width 0.1)
				(type default)
			)
			(layer "F.SilkS")
		)
		(fp_line
			(start 22.43201 -0.97282)
			(end 23.280878 -1.786636)
			(stroke
				(width 0.1)
				(type default)
			)
			(layer "F.SilkS")
		)
		(fp_line
			(start 22.470872 -0.952246)
			(end 23.328122 -1.774444)
			(stroke
				(width 0.1)
				(type default)
			)
			(layer "F.SilkS")
		)
		(fp_line
			(start 22.470872 -0.952246)
			(end 23.328122 -1.774444)
			(stroke
				(width 0.1)
				(type default)
			)
			(layer "F.SilkS")
		)
		(fp_line
			(start 22.510496 -0.932688)
			(end 23.375366 -1.761998)
			(stroke
				(width 0.1)
				(type default)
			)
			(layer "F.SilkS")
		)
		(fp_line
			(start 22.510496 -0.932688)
			(end 23.375366 -1.761998)
			(stroke
				(width 0.1)
				(type default)
			)
			(layer "F.SilkS")
		)
		(fp_line
			(start 22.552914 -0.91567)
			(end 23.430484 -1.757172)
			(stroke
				(width 0.1)
				(type default)
			)
			(layer "F.SilkS")
		)
		(fp_line
			(start 22.552914 -0.91567)
			(end 23.430484 -1.757172)
			(stroke
				(width 0.1)
				(type default)
			)
			(layer "F.SilkS")
		)
		(fp_line
			(start 22.595332 -0.898398)
			(end 23.48611 -1.752854)
			(stroke
				(width 0.1)
				(type default)
			)
			(layer "F.SilkS")
		)
		(fp_line
			(start 22.595332 -0.898398)
			(end 23.48611 -1.752854)
			(stroke
				(width 0.1)
				(type default)
			)
			(layer "F.SilkS")
		)
		(fp_line
			(start 22.638258 -0.881888)
			(end 23.54199 -1.74879)
			(stroke
				(width 0.1)
				(type default)
			)
			(layer "F.SilkS")
		)
		(fp_line
			(start 22.638258 -0.881888)
			(end 23.54199 -1.74879)
			(stroke
				(width 0.1)
				(type default)
			)
			(layer "F.SilkS")
		)
		(fp_line
			(start 22.651212 -4.81838)
			(end 22.66696 -4.776216)
			(stroke
				(width 0.1)
				(type default)
			)
			(layer "F.SilkS")
		)
		(fp_line
			(start 22.651212 -4.81838)
			(end 22.66696 -4.776216)
			(stroke
				(width 0.1)
				(type default)
			)
			(layer "F.SilkS")
		)
		(fp_line
			(start 22.651212 -4.81838)
			(end 22.676358 -4.842764)
			(stroke
				(width 0.1)
				(type default)
			)
			(layer "F.SilkS")
		)
		(fp_line
			(start 22.651212 -4.81838)
			(end 22.676358 -4.842764)
			(stroke
				(width 0.1)
				(type default)
			)
			(layer "F.SilkS")
		)
		(fp_line
			(start 22.66696 -4.776216)
			(end 22.682708 -4.733798)
			(stroke
				(width 0.1)
				(type default)
			)
			(layer "F.SilkS")
		)
		(fp_line
			(start 22.66696 -4.776216)
			(end 22.682708 -4.733798)
			(stroke
				(width 0.1)
				(type default)
			)
			(layer "F.SilkS")
		)
		(fp_line
			(start 22.66696 -4.776216)
			(end 22.802088 -4.905756)
			(stroke
				(width 0.1)
				(type default)
			)
			(layer "F.SilkS")
		)
		(fp_line
			(start 22.66696 -4.776216)
			(end 22.802088 -4.905756)
			(stroke
				(width 0.1)
				(type default)
			)
			(layer "F.SilkS")
		)
		(fp_line
			(start 22.682708 -4.733798)
			(end 22.698964 -4.69138)
			(stroke
				(width 0.1)
				(type default)
			)
			(layer "F.SilkS")
		)
		(fp_line
			(start 22.682708 -4.733798)
			(end 22.698964 -4.69138)
			(stroke
				(width 0.1)
				(type default)
			)
			(layer "F.SilkS")
		)
		(fp_line
			(start 22.682708 -4.733798)
			(end 22.919436 -4.960874)
			(stroke
				(width 0.1)
				(type default)
			)
			(layer "F.SilkS")
		)
		(fp_line
			(start 22.682708 -4.733798)
			(end 22.919436 -4.960874)
			(stroke
				(width 0.1)
				(type default)
			)
			(layer "F.SilkS")
		)
		(fp_line
			(start 22.684232 -0.868172)
			(end 23.610316 -1.756664)
			(stroke
				(width 0.1)
				(type default)
			)
			(layer "F.SilkS")
		)
		(fp_line
			(start 22.684232 -0.868172)
			(end 23.610316 -1.756664)
			(stroke
				(width 0.1)
				(type default)
			)
			(layer "F.SilkS")
		)
		(fp_line
			(start 22.698964 -4.69138)
			(end 22.714712 -4.648962)
			(stroke
				(width 0.1)
				(type default)
			)
			(layer "F.SilkS")
		)
		(fp_line
			(start 22.698964 -4.69138)
			(end 22.714712 -4.648962)
			(stroke
				(width 0.1)
				(type default)
			)
			(layer "F.SilkS")
		)
		(fp_line
			(start 22.698964 -4.69138)
			(end 23.03272 -5.01142)
			(stroke
				(width 0.1)
				(type default)
			)
			(layer "F.SilkS")
		)
		(fp_line
			(start 22.698964 -4.69138)
			(end 23.03272 -5.01142)
			(stroke
				(width 0.1)
				(type default)
			)
			(layer "F.SilkS")
		)
		(fp_line
			(start 22.714712 -4.648962)
			(end 22.730714 -4.606544)
			(stroke
				(width 0.1)
				(type default)
			)
			(layer "F.SilkS")
		)
		(fp_line
			(start 22.714712 -4.648962)
			(end 22.730714 -4.606544)
			(stroke
				(width 0.1)
				(type default)
			)
			(layer "F.SilkS")
		)
		(fp_line
			(start 22.714712 -4.648962)
			(end 23.13432 -5.051298)
			(stroke
				(width 0.1)
				(type default)
			)
			(layer "F.SilkS")
		)
		(fp_line
			(start 22.714712 -4.648962)
			(end 23.13432 -5.051298)
			(stroke
				(width 0.1)
				(type default)
			)
			(layer "F.SilkS")
		)
		(fp_line
			(start 22.729952 -0.85471)
			(end 23.67915 -1.765046)
			(stroke
				(width 0.1)
				(type default)
			)
			(layer "F.SilkS")
		)
		(fp_line
			(start 22.729952 -0.85471)
			(end 23.67915 -1.765046)
			(stroke
				(width 0.1)
				(type default)
			)
			(layer "F.SilkS")
		)
		(fp_line
			(start 22.730714 -4.606544)
			(end 22.74697 -4.564126)
			(stroke
				(width 0.1)
				(type default)
			)
			(layer "F.SilkS")
		)
		(fp_line
			(start 22.730714 -4.606544)
			(end 22.74697 -4.564126)
			(stroke
				(width 0.1)
				(type default)
			)
			(layer "F.SilkS")
		)
		(fp_line
			(start 22.730714 -4.606544)
			(end 23.234396 -5.089652)
			(stroke
				(width 0.1)
				(type default)
			)
			(layer "F.SilkS")
		)
		(fp_line
			(start 22.730714 -4.606544)
			(end 23.234396 -5.089652)
			(stroke
				(width 0.1)
				(type default)
			)
			(layer "F.SilkS")
		)
		(fp_line
			(start 22.74697 -4.564126)
			(end 22.762718 -4.521708)
			(stroke
				(width 0.1)
				(type default)
			)
			(layer "F.SilkS")
		)
		(fp_line
			(start 22.74697 -4.564126)
			(end 22.762718 -4.521708)
			(stroke
				(width 0.1)
				(type default)
			)
			(layer "F.SilkS")
		)
		(fp_line
			(start 22.74697 -4.564126)
			(end 23.32355 -5.117592)
			(stroke
				(width 0.1)
				(type default)
			)
			(layer "F.SilkS")
		)
		(fp_line
			(start 22.74697 -4.564126)
			(end 23.32355 -5.117592)
			(stroke
				(width 0.1)
				(type default)
			)
			(layer "F.SilkS")
		)
		(fp_line
			(start 22.762718 -4.521708)
			(end 22.778466 -4.47929)
			(stroke
				(width 0.1)
				(type default)
			)
			(layer "F.SilkS")
		)
		(fp_line
			(start 22.762718 -4.521708)
			(end 22.778466 -4.47929)
			(stroke
				(width 0.1)
				(type default)
			)
			(layer "F.SilkS")
		)
		(fp_line
			(start 22.762718 -4.521708)
			(end 23.412704 -5.145278)
			(stroke
				(width 0.1)
				(type default)
			)
			(layer "F.SilkS")
		)
		(fp_line
			(start 22.762718 -4.521708)
			(end 23.412704 -5.145278)
			(stroke
				(width 0.1)
				(type default)
			)
			(layer "F.SilkS")
		)
		(fp_line
			(start 22.777196 -0.841756)
			(end 23.748238 -1.773682)
			(stroke
				(width 0.1)
				(type default)
			)
			(layer "F.SilkS")
		)
		(fp_line
			(start 22.777196 -0.841756)
			(end 23.748238 -1.773682)
			(stroke
				(width 0.1)
				(type default)
			)
			(layer "F.SilkS")
		)
		(fp_line
			(start 22.778466 -4.47929)
			(end 22.794722 -4.436872)
			(stroke
				(width 0.1)
				(type default)
			)
			(layer "F.SilkS")
		)
		(fp_line
			(start 22.778466 -4.47929)
			(end 22.794722 -4.436872)
			(stroke
				(width 0.1)
				(type default)
			)
			(layer "F.SilkS")
		)
		(fp_line
			(start 22.778466 -4.47929)
			(end 23.494746 -5.166106)
			(stroke
				(width 0.1)
				(type default)
			)
			(layer "F.SilkS")
		)
		(fp_line
			(start 22.778466 -4.47929)
			(end 23.494746 -5.166106)
			(stroke
				(width 0.1)
				(type default)
			)
			(layer "F.SilkS")
		)
		(fp_line
			(start 22.794722 -4.436872)
			(end 22.81047 -4.394708)
			(stroke
				(width 0.1)
				(type default)
			)
			(layer "F.SilkS")
		)
		(fp_line
			(start 22.794722 -4.436872)
			(end 22.81047 -4.394708)
			(stroke
				(width 0.1)
				(type default)
			)
			(layer "F.SilkS")
		)
		(fp_line
			(start 22.794722 -4.436872)
			(end 23.573994 -5.184648)
			(stroke
				(width 0.1)
				(type default)
			)
			(layer "F.SilkS")
		)
		(fp_line
			(start 22.794722 -4.436872)
			(end 23.573994 -5.184648)
			(stroke
				(width 0.1)
				(type default)
			)
			(layer "F.SilkS")
		)
		(fp_line
			(start 22.81047 -4.394708)
			(end 22.826472 -4.352036)
			(stroke
				(width 0.1)
				(type default)
			)
			(layer "F.SilkS")
		)
		(fp_line
			(start 22.81047 -4.394708)
			(end 22.826472 -4.352036)
			(stroke
				(width 0.1)
				(type default)
			)
			(layer "F.SilkS")
		)
		(fp_line
			(start 22.81047 -4.394708)
			(end 23.652226 -5.20192)
			(stroke
				(width 0.1)
				(type default)
			)
			(layer "F.SilkS")
		)
		(fp_line
			(start 22.81047 -4.394708)
			(end 23.652226 -5.20192)
			(stroke
				(width 0.1)
				(type default)
			)
			(layer "F.SilkS")
		)
		(fp_line
			(start 22.826472 -4.352036)
			(end 22.842728 -4.309618)
			(stroke
				(width 0.1)
				(type default)
			)
			(layer "F.SilkS")
		)
		(fp_line
			(start 22.826472 -4.352036)
			(end 22.842728 -4.309618)
			(stroke
				(width 0.1)
				(type default)
			)
			(layer "F.SilkS")
		)
		(fp_line
			(start 22.826472 -4.352036)
			(end 23.724616 -5.21335)
			(stroke
				(width 0.1)
				(type default)
			)
			(layer "F.SilkS")
		)
		(fp_line
			(start 22.826472 -4.352036)
			(end 23.724616 -5.21335)
			(stroke
				(width 0.1)
				(type default)
			)
			(layer "F.SilkS")
		)
		(fp_line
			(start 22.826726 -0.831596)
			(end 23.82012 -1.78435)
			(stroke
				(width 0.1)
				(type default)
			)
			(layer "F.SilkS")
		)
		(fp_line
			(start 22.826726 -0.831596)
			(end 23.82012 -1.78435)
			(stroke
				(width 0.1)
				(type default)
			)
			(layer "F.SilkS")
		)
		(fp_line
			(start 22.842728 -4.309618)
			(end 22.858476 -4.267454)
			(stroke
				(width 0.1)
				(type default)
			)
			(layer "F.SilkS")
		)
		(fp_line
			(start 22.842728 -4.309618)
			(end 22.858476 -4.267454)
			(stroke
				(width 0.1)
				(type default)
			)
			(layer "F.SilkS")
		)
		(fp_line
			(start 22.842728 -4.309618)
			(end 23.796498 -5.22478)
			(stroke
				(width 0.1)
				(type default)
			)
			(layer "F.SilkS")
		)
		(fp_line
			(start 22.842728 -4.309618)
			(end 23.796498 -5.22478)
			(stroke
				(width 0.1)
				(type default)
			)
			(layer "F.SilkS")
		)
		(fp_line
			(start 22.858476 -4.267454)
			(end 22.874224 -4.225036)
			(stroke
				(width 0.1)
				(type default)
			)
			(layer "F.SilkS")
		)
		(fp_line
			(start 22.858476 -4.267454)
			(end 22.874224 -4.225036)
			(stroke
				(width 0.1)
				(type default)
			)
			(layer "F.SilkS")
		)
		(fp_line
			(start 22.858476 -4.267454)
			(end 23.86711 -5.235194)
			(stroke
				(width 0.1)
				(type default)
			)
			(layer "F.SilkS")
		)
		(fp_line
			(start 22.858476 -4.267454)
			(end 23.86711 -5.235194)
			(stroke
				(width 0.1)
				(type default)
			)
			(layer "F.SilkS")
		)
		(fp_line
			(start 22.874224 -4.225036)
			(end 22.89048 -4.182618)
			(stroke
				(width 0.1)
				(type default)
			)
			(layer "F.SilkS")
		)
		(fp_line
			(start 22.874224 -4.225036)
			(end 22.89048 -4.182618)
			(stroke
				(width 0.1)
				(type default)
			)
			(layer "F.SilkS")
		)
		(fp_line
			(start 22.874224 -4.225036)
			(end 23.933658 -5.241036)
			(stroke
				(width 0.1)
				(type default)
			)
			(layer "F.SilkS")
		)
		(fp_line
			(start 22.874224 -4.225036)
			(end 23.933658 -5.241036)
			(stroke
				(width 0.1)
				(type default)
			)
			(layer "F.SilkS")
		)
		(fp_line
			(start 22.87651 -0.821436)
			(end 23.916894 -1.819656)
			(stroke
				(width 0.1)
				(type default)
			)
			(layer "F.SilkS")
		)
		(fp_line
			(start 22.87651 -0.821436)
			(end 23.916894 -1.819656)
			(stroke
				(width 0.1)
				(type default)
			)
			(layer "F.SilkS")
		)
		(fp_line
			(start 22.89048 -4.182618)
			(end 22.906482 -4.139946)
			(stroke
				(width 0.1)
				(type default)
			)
			(layer "F.SilkS")
		)
		(fp_line
			(start 22.89048 -4.182618)
			(end 22.906482 -4.139946)
			(stroke
				(width 0.1)
				(type default)
			)
			(layer "F.SilkS")
		)
		(fp_line
			(start 22.89048 -4.182618)
			(end 24.000206 -5.246878)
			(stroke
				(width 0.1)
				(type default)
			)
			(layer "F.SilkS")
		)
		(fp_line
			(start 22.89048 -4.182618)
			(end 24.000206 -5.246878)
			(stroke
				(width 0.1)
				(type default)
			)
			(layer "F.SilkS")
		)
		(fp_line
			(start 22.906482 -4.139946)
			(end 22.92223 -4.097782)
			(stroke
				(width 0.1)
				(type default)
			)
			(layer "F.SilkS")
		)
		(fp_line
			(start 22.906482 -4.139946)
			(end 22.92223 -4.097782)
			(stroke
				(width 0.1)
				(type default)
			)
			(layer "F.SilkS")
		)
		(fp_line
			(start 22.906482 -4.139946)
			(end 24.066246 -5.252974)
			(stroke
				(width 0.1)
				(type default)
			)
			(layer "F.SilkS")
		)
		(fp_line
			(start 22.906482 -4.139946)
			(end 24.066246 -5.252974)
			(stroke
				(width 0.1)
				(type default)
			)
			(layer "F.SilkS")
		)
		(fp_line
			(start 22.92223 -4.097782)
			(end 22.938486 -4.055364)
			(stroke
				(width 0.1)
				(type default)
			)
			(layer "F.SilkS")
		)
		(fp_line
			(start 22.92223 -4.097782)
			(end 22.938486 -4.055364)
			(stroke
				(width 0.1)
				(type default)
			)
			(layer "F.SilkS")
		)
		(fp_line
			(start 22.92223 -4.097782)
			(end 24.129492 -5.255768)
			(stroke
				(width 0.1)
				(type default)
			)
			(layer "F.SilkS")
		)
		(fp_line
			(start 22.92223 -4.097782)
			(end 24.129492 -5.255768)
			(stroke
				(width 0.1)
				(type default)
			)
			(layer "F.SilkS")
		)
		(fp_line
			(start 22.927818 -0.813308)
			(end 24.013668 -1.854962)
			(stroke
				(width 0.1)
				(type default)
			)
			(layer "F.SilkS")
		)
		(fp_line
			(start 22.927818 -0.813308)
			(end 24.013668 -1.854962)
			(stroke
				(width 0.1)
				(type default)
			)
			(layer "F.SilkS")
		)
		(fp_line
			(start 22.938486 -4.055364)
			(end 24.191468 -5.257546)
			(stroke
				(width 0.1)
				(type default)
			)
			(layer "F.SilkS")
		)
		(fp_line
			(start 22.938486 -4.055364)
			(end 24.191468 -5.257546)
			(stroke
				(width 0.1)
				(type default)
			)
			(layer "F.SilkS")
		)
		(fp_line
			(start 22.981158 -0.806704)
			(end 24.158956 -1.93675)
			(stroke
				(width 0.1)
				(type default)
			)
			(layer "F.SilkS")
		)
		(fp_line
			(start 22.981158 -0.806704)
			(end 24.158956 -1.93675)
			(stroke
				(width 0.1)
				(type default)
			)
			(layer "F.SilkS")
		)
		(fp_line
			(start 23.029672 -4.085336)
			(end 24.253444 -5.25907)
			(stroke
				(width 0.1)
				(type default)
			)
			(layer "F.SilkS")
		)
		(fp_line
			(start 23.029672 -4.085336)
			(end 24.253444 -5.25907)
			(stroke
				(width 0.1)
				(type default)
			)
			(layer "F.SilkS")
		)
		(fp_line
			(start 23.091394 -0.797052)
			(end 25.733502 -3.331464)
			(stroke
				(width 0.1)
				(type default)
			)
			(layer "F.SilkS")
		)
		(fp_line
			(start 23.091394 -0.797052)
			(end 25.733502 -3.331464)
			(stroke
				(width 0.1)
				(type default)
			)
			(layer "F.SilkS")
		)
		(fp_line
			(start 23.143718 -4.136898)
			(end 24.31542 -5.260848)
			(stroke
				(width 0.1)
				(type default)
			)
			(layer "F.SilkS")
		)
		(fp_line
			(start 23.143718 -4.136898)
			(end 24.31542 -5.260848)
			(stroke
				(width 0.1)
				(type default)
			)
			(layer "F.SilkS")
		)
		(fp_line
			(start 23.149306 -0.79502)
			(end 25.721056 -3.262122)
			(stroke
				(width 0.1)
				(type default)
			)
			(layer "F.SilkS")
		)
		(fp_line
			(start 23.149306 -0.79502)
			(end 25.721056 -3.262122)
			(stroke
				(width 0.1)
				(type default)
			)
			(layer "F.SilkS")
		)
		(fp_line
			(start 23.208488 -0.794258)
			(end 25.708864 -3.19278)
			(stroke
				(width 0.1)
				(type default)
			)
			(layer "F.SilkS")
		)
		(fp_line
			(start 23.208488 -0.794258)
			(end 25.708864 -3.19278)
			(stroke
				(width 0.1)
				(type default)
			)
			(layer "F.SilkS")
		)
		(fp_line
			(start 23.23084 -2.720086)
			(end 24.256492 -3.704082)
			(stroke
				(width 0.1)
				(type default)
			)
			(layer "F.SilkS")
		)
		(fp_line
			(start 23.23084 -2.720086)
			(end 24.256492 -3.704082)
			(stroke
				(width 0.1)
				(type default)
			)
			(layer "F.SilkS")
		)
		(fp_line
			(start 23.249382 -4.180586)
			(end 24.372824 -5.258562)
			(stroke
				(width 0.1)
				(type default)
			)
			(layer "F.SilkS")
		)
		(fp_line
			(start 23.249382 -4.180586)
			(end 24.372824 -5.258562)
			(stroke
				(width 0.1)
				(type default)
			)
			(layer "F.SilkS")
		)
		(fp_line
			(start 23.275798 -0.800608)
			(end 25.696926 -3.123184)
			(stroke
				(width 0.1)
				(type default)
			)
			(layer "F.SilkS")
		)
		(fp_line
			(start 23.275798 -0.800608)
			(end 25.696926 -3.123184)
			(stroke
				(width 0.1)
				(type default)
			)
			(layer "F.SilkS")
		)
		(fp_line
			(start 23.3426 -0.807466)
			(end 25.68448 -3.054096)
			(stroke
				(width 0.1)
				(type default)
			)
			(layer "F.SilkS")
		)
		(fp_line
			(start 23.3426 -0.807466)
			(end 25.68448 -3.054096)
			(stroke
				(width 0.1)
				(type default)
			)
			(layer "F.SilkS")
		)
		(fp_line
			(start 23.344632 -4.214114)
			(end 24.429212 -5.254752)
			(stroke
				(width 0.1)
				(type default)
			)
			(layer "F.SilkS")
		)
		(fp_line
			(start 23.344632 -4.214114)
			(end 24.429212 -5.254752)
			(stroke
				(width 0.1)
				(type default)
			)
			(layer "F.SilkS")
		)
		(fp_line
			(start 23.34895 -2.775712)
			(end 24.307546 -3.695192)
			(stroke
				(width 0.1)
				(type default)
			)
			(layer "F.SilkS")
		)
		(fp_line
			(start 23.34895 -2.775712)
			(end 24.307546 -3.695192)
			(stroke
				(width 0.1)
				(type default)
			)
			(layer "F.SilkS")
		)
		(fp_line
			(start 23.409402 -0.813562)
			(end 25.672542 -2.984754)
			(stroke
				(width 0.1)
				(type default)
			)
			(layer "F.SilkS")
		)
		(fp_line
			(start 23.409402 -0.813562)
			(end 25.672542 -2.984754)
			(stroke
				(width 0.1)
				(type default)
			)
			(layer "F.SilkS")
		)
		(fp_line
			(start 23.46071 -2.825242)
			(end 24.35606 -3.684016)
			(stroke
				(width 0.1)
				(type default)
			)
			(layer "F.SilkS")
		)
		(fp_line
			(start 23.46071 -2.825242)
			(end 24.35606 -3.684016)
			(stroke
				(width 0.1)
				(type default)
			)
			(layer "F.SilkS")
		)
		(fp_line
			(start 23.476458 -0.82042)
			(end 25.66035 -2.915412)
			(stroke
				(width 0.1)
				(type default)
			)
			(layer "F.SilkS")
		)
		(fp_line
			(start 23.476458 -0.82042)
			(end 25.66035 -2.915412)
			(stroke
				(width 0.1)
				(type default)
			)
			(layer "F.SilkS")
		)
		(fp_line
			(start 23.530052 -2.833878)
			(end 24.401272 -3.669538)
			(stroke
				(width 0.1)
				(type default)
			)
			(layer "F.SilkS")
		)
		(fp_line
			(start 23.530052 -2.833878)
			(end 24.401272 -3.669538)
			(stroke
				(width 0.1)
				(type default)
			)
			(layer "F.SilkS")
		)
		(fp_line
			(start 23.557484 -0.840232)
			(end 25.648412 -2.845816)
			(stroke
				(width 0.1)
				(type default)
			)
			(layer "F.SilkS")
		)
		(fp_line
			(start 23.557484 -0.840232)
			(end 25.648412 -2.845816)
			(stroke
				(width 0.1)
				(type default)
			)
			(layer "F.SilkS")
		)
		(fp_line
			(start 23.642828 -0.864616)
			(end 25.635966 -2.776474)
			(stroke
				(width 0.1)
				(type default)
			)
			(layer "F.SilkS")
		)
		(fp_line
			(start 23.642828 -0.864616)
			(end 25.635966 -2.776474)
			(stroke
				(width 0.1)
				(type default)
			)
			(layer "F.SilkS")
		)
		(fp_line
			(start 23.683468 -3.731514)
			(end 21.836634 -1.95961)
			(stroke
				(width 0.1)
				(type default)
			)
			(layer "F.SilkS")
		)
		(fp_line
			(start 23.683468 -3.731514)
			(end 21.836634 -1.95961)
			(stroke
				(width 0.1)
				(type default)
			)
			(layer "F.SilkS")
		)
		(fp_line
			(start 23.728426 -0.888746)
			(end 25.623774 -2.707132)
			(stroke
				(width 0.1)
				(type default)
			)
			(layer "F.SilkS")
		)
		(fp_line
			(start 23.728426 -0.888746)
			(end 25.623774 -2.707132)
			(stroke
				(width 0.1)
				(type default)
			)
			(layer "F.SilkS")
		)
		(fp_line
			(start 23.831296 -0.929894)
			(end 25.611836 -2.63779)
			(stroke
				(width 0.1)
				(type default)
			)
			(layer "F.SilkS")
		)
		(fp_line
			(start 23.831296 -0.929894)
			(end 25.611836 -2.63779)
			(stroke
				(width 0.1)
				(type default)
			)
			(layer "F.SilkS")
		)
		(fp_line
			(start 23.951692 -0.987552)
			(end 25.59939 -2.568194)
			(stroke
				(width 0.1)
				(type default)
			)
			(layer "F.SilkS")
		)
		(fp_line
			(start 23.951692 -0.987552)
			(end 25.59939 -2.568194)
			(stroke
				(width 0.1)
				(type default)
			)
			(layer "F.SilkS")
		)
		(fp_line
			(start 24.122888 -1.094232)
			(end 25.587452 -2.498852)
			(stroke
				(width 0.1)
				(type default)
			)
			(layer "F.SilkS")
		)
		(fp_line
			(start 24.122888 -1.094232)
			(end 25.587452 -2.498852)
			(stroke
				(width 0.1)
				(type default)
			)
			(layer "F.SilkS")
		)
		(fp_line
			(start 24.17699 -0.882904)
			(end 24.203406 -0.882904)
			(stroke
				(width 0.1)
				(type default)
			)
			(layer "F.SilkS")
		)
		(fp_line
			(start 24.17699 -0.882904)
			(end 24.203406 -0.882904)
			(stroke
				(width 0.1)
				(type default)
			)
			(layer "F.SilkS")
		)
		(fp_line
			(start 24.183848 -0.921512)
			(end 24.17699 -0.882904)
			(stroke
				(width 0.1)
				(type default)
			)
			(layer "F.SilkS")
		)
		(fp_line
			(start 24.183848 -0.921512)
			(end 24.17699 -0.882904)
			(stroke
				(width 0.1)
				(type default)
			)
			(layer "F.SilkS")
		)
		(fp_line
			(start 24.183848 -0.921512)
			(end 25.538684 -2.221484)
			(stroke
				(width 0.1)
				(type default)
			)
			(layer "F.SilkS")
		)
		(fp_line
			(start 24.183848 -0.921512)
			(end 25.538684 -2.221484)
			(stroke
				(width 0.1)
				(type default)
			)
			(layer "F.SilkS")
		)
		(fp_line
			(start 24.195786 -0.991108)
			(end 24.183848 -0.921512)
			(stroke
				(width 0.1)
				(type default)
			)
			(layer "F.SilkS")
		)
		(fp_line
			(start 24.195786 -0.991108)
			(end 24.183848 -0.921512)
			(stroke
				(width 0.1)
				(type default)
			)
			(layer "F.SilkS")
		)
		(fp_line
			(start 24.195786 -0.991108)
			(end 25.550876 -2.290826)
			(stroke
				(width 0.1)
				(type default)
			)
			(layer "F.SilkS")
		)
		(fp_line
			(start 24.195786 -0.991108)
			(end 25.550876 -2.290826)
			(stroke
				(width 0.1)
				(type default)
			)
			(layer "F.SilkS")
		)
		(fp_line
			(start 24.203406 -0.882904)
			(end 24.263858 -0.882904)
			(stroke
				(width 0.1)
				(type default)
			)
			(layer "F.SilkS")
		)
		(fp_line
			(start 24.203406 -0.882904)
			(end 24.263858 -0.882904)
			(stroke
				(width 0.1)
				(type default)
			)
			(layer "F.SilkS")
		)
		(fp_line
			(start 24.203406 -0.882904)
			(end 25.526746 -2.152142)
			(stroke
				(width 0.1)
				(type default)
			)
			(layer "F.SilkS")
		)
		(fp_line
			(start 24.203406 -0.882904)
			(end 25.526746 -2.152142)
			(stroke
				(width 0.1)
				(type default)
			)
			(layer "F.SilkS")
		)
		(fp_line
			(start 24.208232 -1.06045)
			(end 24.195786 -0.991108)
			(stroke
				(width 0.1)
				(type default)
			)
			(layer "F.SilkS")
		)
		(fp_line
			(start 24.208232 -1.06045)
			(end 24.195786 -0.991108)
			(stroke
				(width 0.1)
				(type default)
			)
			(layer "F.SilkS")
		)
		(fp_line
			(start 24.208232 -1.06045)
			(end 25.563322 -2.360422)
			(stroke
				(width 0.1)
				(type default)
			)
			(layer "F.SilkS")
		)
		(fp_line
			(start 24.208232 -1.06045)
			(end 25.563322 -2.360422)
			(stroke
				(width 0.1)
				(type default)
			)
			(layer "F.SilkS")
		)
		(fp_line
			(start 24.220424 -1.130046)
			(end 24.208232 -1.06045)
			(stroke
				(width 0.1)
				(type default)
			)
			(layer "F.SilkS")
		)
		(fp_line
			(start 24.220424 -1.130046)
			(end 24.208232 -1.06045)
			(stroke
				(width 0.1)
				(type default)
			)
			(layer "F.SilkS")
		)
		(fp_line
			(start 24.263858 -0.882904)
			(end 24.324056 -0.882904)
			(stroke
				(width 0.1)
				(type default)
			)
			(layer "F.SilkS")
		)
		(fp_line
			(start 24.263858 -0.882904)
			(end 24.324056 -0.882904)
			(stroke
				(width 0.1)
				(type default)
			)
			(layer "F.SilkS")
		)
		(fp_line
			(start 24.263858 -0.882904)
			(end 25.5143 -2.0828)
			(stroke
				(width 0.1)
				(type default)
			)
			(layer "F.SilkS")
		)
		(fp_line
			(start 24.263858 -0.882904)
			(end 25.5143 -2.0828)
			(stroke
				(width 0.1)
				(type default)
			)
			(layer "F.SilkS")
		)
		(fp_line
			(start 24.324056 -0.882904)
			(end 24.384 -0.882904)
			(stroke
				(width 0.1)
				(type default)
			)
			(layer "F.SilkS")
		)
		(fp_line
			(start 24.324056 -0.882904)
			(end 24.384 -0.882904)
			(stroke
				(width 0.1)
				(type default)
			)
			(layer "F.SilkS")
		)
		(fp_line
			(start 24.324056 -0.882904)
			(end 25.502362 -2.013204)
			(stroke
				(width 0.1)
				(type default)
			)
			(layer "F.SilkS")
		)
		(fp_line
			(start 24.324056 -0.882904)
			(end 25.502362 -2.013204)
			(stroke
				(width 0.1)
				(type default)
			)
			(layer "F.SilkS")
		)
		(fp_line
			(start 24.384 -0.882904)
			(end 24.443944 -0.882904)
			(stroke
				(width 0.1)
				(type default)
			)
			(layer "F.SilkS")
		)
		(fp_line
			(start 24.384 -0.882904)
			(end 24.443944 -0.882904)
			(stroke
				(width 0.1)
				(type default)
			)
			(layer "F.SilkS")
		)
		(fp_line
			(start 24.384 -0.882904)
			(end 25.49017 -1.943862)
			(stroke
				(width 0.1)
				(type default)
			)
			(layer "F.SilkS")
		)
		(fp_line
			(start 24.384 -0.882904)
			(end 25.49017 -1.943862)
			(stroke
				(width 0.1)
				(type default)
			)
			(layer "F.SilkS")
		)
		(fp_line
			(start 24.414988 -2.24028)
			(end 24.402796 -2.170938)
			(stroke
				(width 0.1)
				(type default)
			)
			(layer "F.SilkS")
		)
		(fp_line
			(start 24.414988 -2.24028)
			(end 24.402796 -2.170938)
			(stroke
				(width 0.1)
				(type default)
			)
			(layer "F.SilkS")
		)
		(fp_line
			(start 24.427434 -2.309368)
			(end 24.414988 -2.24028)
			(stroke
				(width 0.1)
				(type default)
			)
			(layer "F.SilkS")
		)
		(fp_line
			(start 24.427434 -2.309368)
			(end 24.414988 -2.24028)
			(stroke
				(width 0.1)
				(type default)
			)
			(layer "F.SilkS")
		)
		(fp_line
			(start 24.439372 -2.37871)
			(end 24.427434 -2.309368)
			(stroke
				(width 0.1)
				(type default)
			)
			(layer "F.SilkS")
		)
		(fp_line
			(start 24.439372 -2.37871)
			(end 24.427434 -2.309368)
			(stroke
				(width 0.1)
				(type default)
			)
			(layer "F.SilkS")
		)
		(fp_line
			(start 24.443944 -0.882904)
			(end 24.504142 -0.882904)
			(stroke
				(width 0.1)
				(type default)
			)
			(layer "F.SilkS")
		)
		(fp_line
			(start 24.443944 -0.882904)
			(end 24.504142 -0.882904)
			(stroke
				(width 0.1)
				(type default)
			)
			(layer "F.SilkS")
		)
		(fp_line
			(start 24.443944 -0.882904)
			(end 25.478232 -1.874774)
			(stroke
				(width 0.1)
				(type default)
			)
			(layer "F.SilkS")
		)
		(fp_line
			(start 24.443944 -0.882904)
			(end 25.478232 -1.874774)
			(stroke
				(width 0.1)
				(type default)
			)
			(layer "F.SilkS")
		)
		(fp_line
			(start 24.44623 -3.655568)
			(end 23.598886 -2.842514)
			(stroke
				(width 0.1)
				(type default)
			)
			(layer "F.SilkS")
		)
		(fp_line
			(start 24.44623 -3.655568)
			(end 23.598886 -2.842514)
			(stroke
				(width 0.1)
				(type default)
			)
			(layer "F.SilkS")
		)
		(fp_line
			(start 24.451564 -2.448306)
			(end 24.439372 -2.37871)
			(stroke
				(width 0.1)
				(type default)
			)
			(layer "F.SilkS")
		)
		(fp_line
			(start 24.451564 -2.448306)
			(end 24.439372 -2.37871)
			(stroke
				(width 0.1)
				(type default)
			)
			(layer "F.SilkS")
		)
		(fp_line
			(start 24.46401 -2.517648)
			(end 24.451564 -2.448306)
			(stroke
				(width 0.1)
				(type default)
			)
			(layer "F.SilkS")
		)
		(fp_line
			(start 24.46401 -2.517648)
			(end 24.451564 -2.448306)
			(stroke
				(width 0.1)
				(type default)
			)
			(layer "F.SilkS")
		)
		(fp_line
			(start 24.475948 -2.58699)
			(end 24.46401 -2.517648)
			(stroke
				(width 0.1)
				(type default)
			)
			(layer "F.SilkS")
		)
		(fp_line
			(start 24.475948 -2.58699)
			(end 24.46401 -2.517648)
			(stroke
				(width 0.1)
				(type default)
			)
			(layer "F.SilkS")
		)
		(fp_line
			(start 24.485346 -5.250942)
			(end 23.433532 -4.2418)
			(stroke
				(width 0.1)
				(type default)
			)
			(layer "F.SilkS")
		)
		(fp_line
			(start 24.485346 -5.250942)
			(end 23.433532 -4.2418)
			(stroke
				(width 0.1)
				(type default)
			)
			(layer "F.SilkS")
		)
		(fp_line
			(start 24.487886 -2.656332)
			(end 24.475948 -2.58699)
			(stroke
				(width 0.1)
				(type default)
			)
			(layer "F.SilkS")
		)
		(fp_line
			(start 24.487886 -2.656332)
			(end 24.475948 -2.58699)
			(stroke
				(width 0.1)
				(type default)
			)
			(layer "F.SilkS")
		)
		(fp_line
			(start 24.491696 -3.64109)
			(end 23.668482 -2.85115)
			(stroke
				(width 0.1)
				(type default)
			)
			(layer "F.SilkS")
		)
		(fp_line
			(start 24.491696 -3.64109)
			(end 23.668482 -2.85115)
			(stroke
				(width 0.1)
				(type default)
			)
			(layer "F.SilkS")
		)
		(fp_line
			(start 24.504142 -0.882904)
			(end 24.564594 -0.882904)
			(stroke
				(width 0.1)
				(type default)
			)
			(layer "F.SilkS")
		)
		(fp_line
			(start 24.504142 -0.882904)
			(end 24.564594 -0.882904)
			(stroke
				(width 0.1)
				(type default)
			)
			(layer "F.SilkS")
		)
		(fp_line
			(start 24.504142 -0.882904)
			(end 25.465786 -1.805178)
			(stroke
				(width 0.1)
				(type default)
			)
			(layer "F.SilkS")
		)
		(fp_line
			(start 24.504142 -0.882904)
			(end 25.465786 -1.805178)
			(stroke
				(width 0.1)
				(type default)
			)
			(layer "F.SilkS")
		)
		(fp_line
			(start 24.534114 -3.624072)
			(end 23.73757 -2.859786)
			(stroke
				(width 0.1)
				(type default)
			)
			(layer "F.SilkS")
		)
		(fp_line
			(start 24.534114 -3.624072)
			(end 23.73757 -2.859786)
			(stroke
				(width 0.1)
				(type default)
			)
			(layer "F.SilkS")
		)
		(fp_line
			(start 24.541734 -5.246878)
			(end 23.518114 -4.265168)
			(stroke
				(width 0.1)
				(type default)
			)
			(layer "F.SilkS")
		)
		(fp_line
			(start 24.541734 -5.246878)
			(end 23.518114 -4.265168)
			(stroke
				(width 0.1)
				(type default)
			)
			(layer "F.SilkS")
		)
		(fp_line
			(start 24.564594 -0.882904)
			(end 24.624538 -0.882904)
			(stroke
				(width 0.1)
				(type default)
			)
			(layer "F.SilkS")
		)
		(fp_line
			(start 24.564594 -0.882904)
			(end 24.624538 -0.882904)
			(stroke
				(width 0.1)
				(type default)
			)
			(layer "F.SilkS")
		)
		(fp_line
			(start 24.564594 -0.882904)
			(end 25.453594 -1.735836)
			(stroke
				(width 0.1)
				(type default)
			)
			(layer "F.SilkS")
		)
		(fp_line
			(start 24.564594 -0.882904)
			(end 25.453594 -1.735836)
			(stroke
				(width 0.1)
				(type default)
			)
			(layer "F.SilkS")
		)
		(fp_line
			(start 24.5745 -3.605276)
			(end 23.797006 -2.859024)
			(stroke
				(width 0.1)
				(type default)
			)
			(layer "F.SilkS")
		)
		(fp_line
			(start 24.5745 -3.605276)
			(end 23.797006 -2.859024)
			(stroke
				(width 0.1)
				(type default)
			)
			(layer "F.SilkS")
		)
		(fp_line
			(start 24.597614 -5.243068)
			(end 23.594822 -4.280916)
			(stroke
				(width 0.1)
				(type default)
			)
			(layer "F.SilkS")
		)
		(fp_line
			(start 24.597614 -5.243068)
			(end 23.594822 -4.280916)
			(stroke
				(width 0.1)
				(type default)
			)
			(layer "F.SilkS")
		)
		(fp_line
			(start 24.614886 -3.586226)
			(end 23.855426 -2.857754)
			(stroke
				(width 0.1)
				(type default)
			)
			(layer "F.SilkS")
		)
		(fp_line
			(start 24.614886 -3.586226)
			(end 23.855426 -2.857754)
			(stroke
				(width 0.1)
				(type default)
			)
			(layer "F.SilkS")
		)
		(fp_line
			(start 24.624538 -0.882904)
			(end 24.684736 -0.882904)
			(stroke
				(width 0.1)
				(type default)
			)
			(layer "F.SilkS")
		)
		(fp_line
			(start 24.624538 -0.882904)
			(end 24.684736 -0.882904)
			(stroke
				(width 0.1)
				(type default)
			)
			(layer "F.SilkS")
		)
		(fp_line
			(start 24.624538 -0.882904)
			(end 25.441656 -1.666494)
			(stroke
				(width 0.1)
				(type default)
			)
			(layer "F.SilkS")
		)
		(fp_line
			(start 24.624538 -0.882904)
			(end 25.441656 -1.666494)
			(stroke
				(width 0.1)
				(type default)
			)
			(layer "F.SilkS")
		)
		(fp_line
			(start 24.653748 -5.239258)
			(end 23.67026 -4.295902)
			(stroke
				(width 0.1)
				(type default)
			)
			(layer "F.SilkS")
		)
		(fp_line
			(start 24.653748 -5.239258)
			(end 23.67026 -4.295902)
			(stroke
				(width 0.1)
				(type default)
			)
			(layer "F.SilkS")
		)
		(fp_line
			(start 24.67102 -3.697478)
			(end 24.658574 -3.627882)
			(stroke
				(width 0.1)
				(type default)
			)
			(layer "F.SilkS")
		)
		(fp_line
			(start 24.67102 -3.697478)
			(end 24.658574 -3.627882)
			(stroke
				(width 0.1)
				(type default)
			)
			(layer "F.SilkS")
		)
		(fp_line
			(start 24.682958 -3.76682)
			(end 24.67102 -3.697478)
			(stroke
				(width 0.1)
				(type default)
			)
			(layer "F.SilkS")
		)
		(fp_line
			(start 24.682958 -3.76682)
			(end 24.67102 -3.697478)
			(stroke
				(width 0.1)
				(type default)
			)
			(layer "F.SilkS")
		)
		(fp_line
			(start 24.684736 -0.882904)
			(end 24.744934 -0.882904)
			(stroke
				(width 0.1)
				(type default)
			)
			(layer "F.SilkS")
		)
		(fp_line
			(start 24.684736 -0.882904)
			(end 24.744934 -0.882904)
			(stroke
				(width 0.1)
				(type default)
			)
			(layer "F.SilkS")
		)
		(fp_line
			(start 24.684736 -0.882904)
			(end 25.42921 -1.597406)
			(stroke
				(width 0.1)
				(type default)
			)
			(layer "F.SilkS")
		)
		(fp_line
			(start 24.684736 -0.882904)
			(end 25.42921 -1.597406)
			(stroke
				(width 0.1)
				(type default)
			)
			(layer "F.SilkS")
		)
		(fp_line
			(start 24.708866 -5.234432)
			(end 23.739856 -4.304792)
			(stroke
				(width 0.1)
				(type default)
			)
			(layer "F.SilkS")
		)
		(fp_line
			(start 24.708866 -5.234432)
			(end 23.739856 -4.304792)
			(stroke
				(width 0.1)
				(type default)
			)
			(layer "F.SilkS")
		)
		(fp_line
			(start 24.744934 -0.882904)
			(end 24.805386 -0.882904)
			(stroke
				(width 0.1)
				(type default)
			)
			(layer "F.SilkS")
		)
		(fp_line
			(start 24.744934 -0.882904)
			(end 24.805386 -0.882904)
			(stroke
				(width 0.1)
				(type default)
			)
			(layer "F.SilkS")
		)
		(fp_line
			(start 24.744934 -0.882904)
			(end 25.417272 -1.52781)
			(stroke
				(width 0.1)
				(type default)
			)
			(layer "F.SilkS")
		)
		(fp_line
			(start 24.744934 -0.882904)
			(end 25.417272 -1.52781)
			(stroke
				(width 0.1)
				(type default)
			)
			(layer "F.SilkS")
		)
		(fp_line
			(start 24.75738 -5.223256)
			(end 23.809452 -4.313936)
			(stroke
				(width 0.1)
				(type default)
			)
			(layer "F.SilkS")
		)
		(fp_line
			(start 24.75738 -5.223256)
			(end 23.809452 -4.313936)
			(stroke
				(width 0.1)
				(type default)
			)
			(layer "F.SilkS")
		)
		(fp_line
			(start 24.805386 -0.882904)
			(end 24.86533 -0.882904)
			(stroke
				(width 0.1)
				(type default)
			)
			(layer "F.SilkS")
		)
		(fp_line
			(start 24.805386 -0.882904)
			(end 24.86533 -0.882904)
			(stroke
				(width 0.1)
				(type default)
			)
			(layer "F.SilkS")
		)
		(fp_line
			(start 24.805386 -0.882904)
			(end 25.40508 -1.458214)
			(stroke
				(width 0.1)
				(type default)
			)
			(layer "F.SilkS")
		)
		(fp_line
			(start 24.805386 -0.882904)
			(end 25.40508 -1.458214)
			(stroke
				(width 0.1)
				(type default)
			)
			(layer "F.SilkS")
		)
		(fp_line
			(start 24.805894 -5.21208)
			(end 23.87473 -4.318762)
			(stroke
				(width 0.1)
				(type default)
			)
			(layer "F.SilkS")
		)
		(fp_line
			(start 24.805894 -5.21208)
			(end 23.87473 -4.318762)
			(stroke
				(width 0.1)
				(type default)
			)
			(layer "F.SilkS")
		)
		(fp_line
			(start 24.854154 -5.200904)
			(end 23.9395 -4.323334)
			(stroke
				(width 0.1)
				(type default)
			)
			(layer "F.SilkS")
		)
		(fp_line
			(start 24.854154 -5.200904)
			(end 23.9395 -4.323334)
			(stroke
				(width 0.1)
				(type default)
			)
			(layer "F.SilkS")
		)
		(fp_line
			(start 24.86533 -0.882904)
			(end 24.925274 -0.882904)
			(stroke
				(width 0.1)
				(type default)
			)
			(layer "F.SilkS")
		)
		(fp_line
			(start 24.86533 -0.882904)
			(end 24.925274 -0.882904)
			(stroke
				(width 0.1)
				(type default)
			)
			(layer "F.SilkS")
		)
		(fp_line
			(start 24.86533 -0.882904)
			(end 25.392634 -1.388872)
			(stroke
				(width 0.1)
				(type default)
			)
			(layer "F.SilkS")
		)
		(fp_line
			(start 24.86533 -0.882904)
			(end 25.392634 -1.388872)
			(stroke
				(width 0.1)
				(type default)
			)
			(layer "F.SilkS")
		)
		(fp_line
			(start 24.903176 -5.189728)
			(end 24.003254 -4.32689)
			(stroke
				(width 0.1)
				(type default)
			)
			(layer "F.SilkS")
		)
		(fp_line
			(start 24.903176 -5.189728)
			(end 24.003254 -4.32689)
			(stroke
				(width 0.1)
				(type default)
			)
			(layer "F.SilkS")
		)
		(fp_line
			(start 24.925274 -0.882904)
			(end 24.985472 -0.882904)
			(stroke
				(width 0.1)
				(type default)
			)
			(layer "F.SilkS")
		)
		(fp_line
			(start 24.925274 -0.882904)
			(end 24.985472 -0.882904)
			(stroke
				(width 0.1)
				(type default)
			)
			(layer "F.SilkS")
		)
		(fp_line
			(start 24.925274 -0.882904)
			(end 25.380696 -1.319784)
			(stroke
				(width 0.1)
				(type default)
			)
			(layer "F.SilkS")
		)
		(fp_line
			(start 24.925274 -0.882904)
			(end 25.380696 -1.319784)
			(stroke
				(width 0.1)
				(type default)
			)
			(layer "F.SilkS")
		)
		(fp_line
			(start 24.95169 -5.178552)
			(end 24.064976 -4.327906)
			(stroke
				(width 0.1)
				(type default)
			)
			(layer "F.SilkS")
		)
		(fp_line
			(start 24.95169 -5.178552)
			(end 24.064976 -4.327906)
			(stroke
				(width 0.1)
				(type default)
			)
			(layer "F.SilkS")
		)
		(fp_line
			(start 24.985472 -0.882904)
			(end 25.04567 -0.882904)
			(stroke
				(width 0.1)
				(type default)
			)
			(layer "F.SilkS")
		)
		(fp_line
			(start 24.985472 -0.882904)
			(end 25.04567 -0.882904)
			(stroke
				(width 0.1)
				(type default)
			)
			(layer "F.SilkS")
		)
		(fp_line
			(start 24.985472 -0.882904)
			(end 25.368504 -1.250188)
			(stroke
				(width 0.1)
				(type default)
			)
			(layer "F.SilkS")
		)
		(fp_line
			(start 24.985472 -0.882904)
			(end 25.368504 -1.250188)
			(stroke
				(width 0.1)
				(type default)
			)
			(layer "F.SilkS")
		)
		(fp_line
			(start 24.99995 -5.16763)
			(end 24.12619 -4.329176)
			(stroke
				(width 0.1)
				(type default)
			)
			(layer "F.SilkS")
		)
		(fp_line
			(start 24.99995 -5.16763)
			(end 24.12619 -4.329176)
			(stroke
				(width 0.1)
				(type default)
			)
			(layer "F.SilkS")
		)
		(fp_line
			(start 25.045162 -5.152898)
			(end 24.18588 -4.328922)
			(stroke
				(width 0.1)
				(type default)
			)
			(layer "F.SilkS")
		)
		(fp_line
			(start 25.045162 -5.152898)
			(end 24.18588 -4.328922)
			(stroke
				(width 0.1)
				(type default)
			)
			(layer "F.SilkS")
		)
		(fp_line
			(start 25.04567 -0.882904)
			(end 25.106122 -0.882904)
			(stroke
				(width 0.1)
				(type default)
			)
			(layer "F.SilkS")
		)
		(fp_line
			(start 25.04567 -0.882904)
			(end 25.106122 -0.882904)
			(stroke
				(width 0.1)
				(type default)
			)
			(layer "F.SilkS")
		)
		(fp_line
			(start 25.04567 -0.882904)
			(end 25.356058 -1.180592)
			(stroke
				(width 0.1)
				(type default)
			)
			(layer "F.SilkS")
		)
		(fp_line
			(start 25.04567 -0.882904)
			(end 25.356058 -1.180592)
			(stroke
				(width 0.1)
				(type default)
			)
			(layer "F.SilkS")
		)
		(fp_line
			(start 25.086056 -5.13461)
			(end 24.241252 -4.32435)
			(stroke
				(width 0.1)
				(type default)
			)
			(layer "F.SilkS")
		)
		(fp_line
			(start 25.086056 -5.13461)
			(end 24.241252 -4.32435)
			(stroke
				(width 0.1)
				(type default)
			)
			(layer "F.SilkS")
		)
		(fp_line
			(start 25.106122 -0.882904)
			(end 25.166066 -0.882904)
			(stroke
				(width 0.1)
				(type default)
			)
			(layer "F.SilkS")
		)
		(fp_line
			(start 25.106122 -0.882904)
			(end 25.166066 -0.882904)
			(stroke
				(width 0.1)
				(type default)
			)
			(layer "F.SilkS")
		)
		(fp_line
			(start 25.106122 -0.882904)
			(end 25.34412 -1.111504)
			(stroke
				(width 0.1)
				(type default)
			)
			(layer "F.SilkS")
		)
		(fp_line
			(start 25.106122 -0.882904)
			(end 25.34412 -1.111504)
			(stroke
				(width 0.1)
				(type default)
			)
			(layer "F.SilkS")
		)
		(fp_line
			(start 25.127458 -5.116322)
			(end 24.297132 -4.320032)
			(stroke
				(width 0.1)
				(type default)
			)
			(layer "F.SilkS")
		)
		(fp_line
			(start 25.127458 -5.116322)
			(end 24.297132 -4.320032)
			(stroke
				(width 0.1)
				(type default)
			)
			(layer "F.SilkS")
		)
		(fp_line
			(start 25.166066 -0.882904)
			(end 25.226264 -0.882904)
			(stroke
				(width 0.1)
				(type default)
			)
			(layer "F.SilkS")
		)
		(fp_line
			(start 25.166066 -0.882904)
			(end 25.226264 -0.882904)
			(stroke
				(width 0.1)
				(type default)
			)
			(layer "F.SilkS")
		)
		(fp_line
			(start 25.166066 -0.882904)
			(end 25.332182 -1.042416)
			(stroke
				(width 0.1)
				(type default)
			)
			(layer "F.SilkS")
		)
		(fp_line
			(start 25.166066 -0.882904)
			(end 25.332182 -1.042416)
			(stroke
				(width 0.1)
				(type default)
			)
			(layer "F.SilkS")
		)
		(fp_line
			(start 25.168352 -5.098034)
			(end 24.346408 -4.309618)
			(stroke
				(width 0.1)
				(type default)
			)
			(layer "F.SilkS")
		)
		(fp_line
			(start 25.168352 -5.098034)
			(end 24.346408 -4.309618)
			(stroke
				(width 0.1)
				(type default)
			)
			(layer "F.SilkS")
		)
		(fp_line
			(start 25.2095 -5.08)
			(end 24.393398 -4.296918)
			(stroke
				(width 0.1)
				(type default)
			)
			(layer "F.SilkS")
		)
		(fp_line
			(start 25.2095 -5.08)
			(end 24.393398 -4.296918)
			(stroke
				(width 0.1)
				(type default)
			)
			(layer "F.SilkS")
		)
		(fp_line
			(start 25.226264 -0.882904)
			(end 25.286462 -0.882904)
			(stroke
				(width 0.1)
				(type default)
			)
			(layer "F.SilkS")
		)
		(fp_line
			(start 25.226264 -0.882904)
			(end 25.286462 -0.882904)
			(stroke
				(width 0.1)
				(type default)
			)
			(layer "F.SilkS")
		)
		(fp_line
			(start 25.226264 -0.882904)
			(end 25.31999 -0.97282)
			(stroke
				(width 0.1)
				(type default)
			)
			(layer "F.SilkS")
		)
		(fp_line
			(start 25.226264 -0.882904)
			(end 25.31999 -0.97282)
			(stroke
				(width 0.1)
				(type default)
			)
			(layer "F.SilkS")
		)
		(fp_line
			(start 25.250648 -5.061712)
			(end 24.438356 -4.28244)
			(stroke
				(width 0.1)
				(type default)
			)
			(layer "F.SilkS")
		)
		(fp_line
			(start 25.250648 -5.061712)
			(end 24.438356 -4.28244)
			(stroke
				(width 0.1)
				(type default)
			)
			(layer "F.SilkS")
		)
		(fp_line
			(start 25.286462 -0.882904)
			(end 25.304242 -0.882904)
			(stroke
				(width 0.1)
				(type default)
			)
			(layer "F.SilkS")
		)
		(fp_line
			(start 25.286462 -0.882904)
			(end 25.304242 -0.882904)
			(stroke
				(width 0.1)
				(type default)
			)
			(layer "F.SilkS")
		)
		(fp_line
			(start 25.286462 -0.882904)
			(end 25.307544 -0.903224)
			(stroke
				(width 0.1)
				(type default)
			)
			(layer "F.SilkS")
		)
		(fp_line
			(start 25.286462 -0.882904)
			(end 25.307544 -0.903224)
			(stroke
				(width 0.1)
				(type default)
			)
			(layer "F.SilkS")
		)
		(fp_line
			(start 25.29205 -5.043424)
			(end 24.477726 -4.26212)
			(stroke
				(width 0.1)
				(type default)
			)
			(layer "F.SilkS")
		)
		(fp_line
			(start 25.29205 -5.043424)
			(end 24.477726 -4.26212)
			(stroke
				(width 0.1)
				(type default)
			)
			(layer "F.SilkS")
		)
		(fp_line
			(start 25.304242 -0.882904)
			(end 25.307544 -0.903224)
			(stroke
				(width 0.1)
				(type default)
			)
			(layer "F.SilkS")
		)
		(fp_line
			(start 25.304242 -0.882904)
			(end 25.307544 -0.903224)
			(stroke
				(width 0.1)
				(type default)
			)
			(layer "F.SilkS")
		)
		(fp_line
			(start 25.307544 -0.903224)
			(end 25.31999 -0.97282)
			(stroke
				(width 0.1)
				(type default)
			)
			(layer "F.SilkS")
		)
		(fp_line
			(start 25.307544 -0.903224)
			(end 25.31999 -0.97282)
			(stroke
				(width 0.1)
				(type default)
			)
			(layer "F.SilkS")
		)
		(fp_line
			(start 25.31999 -0.97282)
			(end 25.332182 -1.042416)
			(stroke
				(width 0.1)
				(type default)
			)
			(layer "F.SilkS")
		)
		(fp_line
			(start 25.31999 -0.97282)
			(end 25.332182 -1.042416)
			(stroke
				(width 0.1)
				(type default)
			)
			(layer "F.SilkS")
		)
		(fp_line
			(start 25.327356 -5.019294)
			(end 24.516334 -4.2418)
			(stroke
				(width 0.1)
				(type default)
			)
			(layer "F.SilkS")
		)
		(fp_line
			(start 25.327356 -5.019294)
			(end 24.516334 -4.2418)
			(stroke
				(width 0.1)
				(type default)
			)
			(layer "F.SilkS")
		)
		(fp_line
			(start 25.332182 -1.042416)
			(end 25.34412 -1.111504)
			(stroke
				(width 0.1)
				(type default)
			)
			(layer "F.SilkS")
		)
		(fp_line
			(start 25.332182 -1.042416)
			(end 25.34412 -1.111504)
			(stroke
				(width 0.1)
				(type default)
			)
			(layer "F.SilkS")
		)
		(fp_line
			(start 25.34412 -1.111504)
			(end 25.356058 -1.180592)
			(stroke
				(width 0.1)
				(type default)
			)
			(layer "F.SilkS")
		)
		(fp_line
			(start 25.34412 -1.111504)
			(end 25.356058 -1.180592)
			(stroke
				(width 0.1)
				(type default)
			)
			(layer "F.SilkS")
		)
		(fp_line
			(start 25.356058 -1.180592)
			(end 25.368504 -1.250188)
			(stroke
				(width 0.1)
				(type default)
			)
			(layer "F.SilkS")
		)
		(fp_line
			(start 25.356058 -1.180592)
			(end 25.368504 -1.250188)
			(stroke
				(width 0.1)
				(type default)
			)
			(layer "F.SilkS")
		)
		(fp_line
			(start 25.36063 -4.994148)
			(end 24.549354 -4.215892)
			(stroke
				(width 0.1)
				(type default)
			)
			(layer "F.SilkS")
		)
		(fp_line
			(start 25.36063 -4.994148)
			(end 24.549354 -4.215892)
			(stroke
				(width 0.1)
				(type default)
			)
			(layer "F.SilkS")
		)
		(fp_line
			(start 25.368504 -1.250188)
			(end 25.380696 -1.319784)
			(stroke
				(width 0.1)
				(type default)
			)
			(layer "F.SilkS")
		)
		(fp_line
			(start 25.368504 -1.250188)
			(end 25.380696 -1.319784)
			(stroke
				(width 0.1)
				(type default)
			)
			(layer "F.SilkS")
		)
		(fp_line
			(start 25.380696 -1.319784)
			(end 25.392634 -1.388872)
			(stroke
				(width 0.1)
				(type default)
			)
			(layer "F.SilkS")
		)
		(fp_line
			(start 25.380696 -1.319784)
			(end 25.392634 -1.388872)
			(stroke
				(width 0.1)
				(type default)
			)
			(layer "F.SilkS")
		)
		(fp_line
			(start 25.392634 -1.388872)
			(end 25.40508 -1.458214)
			(stroke
				(width 0.1)
				(type default)
			)
			(layer "F.SilkS")
		)
		(fp_line
			(start 25.392634 -1.388872)
			(end 25.40508 -1.458214)
			(stroke
				(width 0.1)
				(type default)
			)
			(layer "F.SilkS")
		)
		(fp_line
			(start 25.394412 -4.968494)
			(end 24.580596 -4.187952)
			(stroke
				(width 0.1)
				(type default)
			)
			(layer "F.SilkS")
		)
		(fp_line
			(start 25.394412 -4.968494)
			(end 24.580596 -4.187952)
			(stroke
				(width 0.1)
				(type default)
			)
			(layer "F.SilkS")
		)
		(fp_line
			(start 25.40508 -1.458214)
			(end 25.417272 -1.52781)
			(stroke
				(width 0.1)
				(type default)
			)
			(layer "F.SilkS")
		)
		(fp_line
			(start 25.40508 -1.458214)
			(end 25.417272 -1.52781)
			(stroke
				(width 0.1)
				(type default)
			)
			(layer "F.SilkS")
		)
		(fp_line
			(start 25.417272 -1.52781)
			(end 25.42921 -1.597406)
			(stroke
				(width 0.1)
				(type default)
			)
			(layer "F.SilkS")
		)
		(fp_line
			(start 25.417272 -1.52781)
			(end 25.42921 -1.597406)
			(stroke
				(width 0.1)
				(type default)
			)
			(layer "F.SilkS")
		)
		(fp_line
			(start 25.428194 -4.943094)
			(end 24.609044 -4.157218)
			(stroke
				(width 0.1)
				(type default)
			)
			(layer "F.SilkS")
		)
		(fp_line
			(start 25.428194 -4.943094)
			(end 24.609044 -4.157218)
			(stroke
				(width 0.1)
				(type default)
			)
			(layer "F.SilkS")
		)
		(fp_line
			(start 25.42921 -1.597406)
			(end 25.441656 -1.666494)
			(stroke
				(width 0.1)
				(type default)
			)
			(layer "F.SilkS")
		)
		(fp_line
			(start 25.42921 -1.597406)
			(end 25.441656 -1.666494)
			(stroke
				(width 0.1)
				(type default)
			)
			(layer "F.SilkS")
		)
		(fp_line
			(start 25.441656 -1.666494)
			(end 25.453594 -1.735836)
			(stroke
				(width 0.1)
				(type default)
			)
			(layer "F.SilkS")
		)
		(fp_line
			(start 25.441656 -1.666494)
			(end 25.453594 -1.735836)
			(stroke
				(width 0.1)
				(type default)
			)
			(layer "F.SilkS")
		)
		(fp_line
			(start 25.453594 -1.735836)
			(end 25.465786 -1.805178)
			(stroke
				(width 0.1)
				(type default)
			)
			(layer "F.SilkS")
		)
		(fp_line
			(start 25.453594 -1.735836)
			(end 25.465786 -1.805178)
			(stroke
				(width 0.1)
				(type default)
			)
			(layer "F.SilkS")
		)
		(fp_line
			(start 25.461722 -4.917694)
			(end 24.631904 -4.121912)
			(stroke
				(width 0.1)
				(type default)
			)
			(layer "F.SilkS")
		)
		(fp_line
			(start 25.461722 -4.917694)
			(end 24.631904 -4.121912)
			(stroke
				(width 0.1)
				(type default)
			)
			(layer "F.SilkS")
		)
		(fp_line
			(start 25.465786 -1.805178)
			(end 25.478232 -1.874774)
			(stroke
				(width 0.1)
				(type default)
			)
			(layer "F.SilkS")
		)
		(fp_line
			(start 25.465786 -1.805178)
			(end 25.478232 -1.874774)
			(stroke
				(width 0.1)
				(type default)
			)
			(layer "F.SilkS")
		)
		(fp_line
			(start 25.478232 -1.874774)
			(end 25.49017 -1.943862)
			(stroke
				(width 0.1)
				(type default)
			)
			(layer "F.SilkS")
		)
		(fp_line
			(start 25.478232 -1.874774)
			(end 25.49017 -1.943862)
			(stroke
				(width 0.1)
				(type default)
			)
			(layer "F.SilkS")
		)
		(fp_line
			(start 25.49017 -1.943862)
			(end 25.502362 -2.013204)
			(stroke
				(width 0.1)
				(type default)
			)
			(layer "F.SilkS")
		)
		(fp_line
			(start 25.49017 -1.943862)
			(end 25.502362 -2.013204)
			(stroke
				(width 0.1)
				(type default)
			)
			(layer "F.SilkS")
		)
		(fp_line
			(start 25.49525 -4.892294)
			(end 24.65451 -4.085844)
			(stroke
				(width 0.1)
				(type default)
			)
			(layer "F.SilkS")
		)
		(fp_line
			(start 25.49525 -4.892294)
			(end 24.65451 -4.085844)
			(stroke
				(width 0.1)
				(type default)
			)
			(layer "F.SilkS")
		)
		(fp_line
			(start 25.502362 -2.013204)
			(end 25.5143 -2.0828)
			(stroke
				(width 0.1)
				(type default)
			)
			(layer "F.SilkS")
		)
		(fp_line
			(start 25.502362 -2.013204)
			(end 25.5143 -2.0828)
			(stroke
				(width 0.1)
				(type default)
			)
			(layer "F.SilkS")
		)
		(fp_line
			(start 25.5143 -2.0828)
			(end 25.526746 -2.152142)
			(stroke
				(width 0.1)
				(type default)
			)
			(layer "F.SilkS")
		)
		(fp_line
			(start 25.5143 -2.0828)
			(end 25.526746 -2.152142)
			(stroke
				(width 0.1)
				(type default)
			)
			(layer "F.SilkS")
		)
		(fp_line
			(start 25.526746 -2.152142)
			(end 25.538684 -2.221484)
			(stroke
				(width 0.1)
				(type default)
			)
			(layer "F.SilkS")
		)
		(fp_line
			(start 25.526746 -2.152142)
			(end 25.538684 -2.221484)
			(stroke
				(width 0.1)
				(type default)
			)
			(layer "F.SilkS")
		)
		(fp_line
			(start 25.527508 -4.865624)
			(end 24.669242 -4.042156)
			(stroke
				(width 0.1)
				(type default)
			)
			(layer "F.SilkS")
		)
		(fp_line
			(start 25.527508 -4.865624)
			(end 24.669242 -4.042156)
			(stroke
				(width 0.1)
				(type default)
			)
			(layer "F.SilkS")
		)
		(fp_line
			(start 25.538684 -2.221484)
			(end 25.550876 -2.290826)
			(stroke
				(width 0.1)
				(type default)
			)
			(layer "F.SilkS")
		)
		(fp_line
			(start 25.538684 -2.221484)
			(end 25.550876 -2.290826)
			(stroke
				(width 0.1)
				(type default)
			)
			(layer "F.SilkS")
		)
		(fp_line
			(start 25.550876 -2.290826)
			(end 25.563322 -2.360422)
			(stroke
				(width 0.1)
				(type default)
			)
			(layer "F.SilkS")
		)
		(fp_line
			(start 25.550876 -2.290826)
			(end 25.563322 -2.360422)
			(stroke
				(width 0.1)
				(type default)
			)
			(layer "F.SilkS")
		)
		(fp_line
			(start 25.553162 -4.83235)
			(end 24.683974 -3.998722)
			(stroke
				(width 0.1)
				(type default)
			)
			(layer "F.SilkS")
		)
		(fp_line
			(start 25.553162 -4.83235)
			(end 24.683974 -3.998722)
			(stroke
				(width 0.1)
				(type default)
			)
			(layer "F.SilkS")
		)
		(fp_line
			(start 25.563322 -2.360422)
			(end 25.57526 -2.429764)
			(stroke
				(width 0.1)
				(type default)
			)
			(layer "F.SilkS")
		)
		(fp_line
			(start 25.563322 -2.360422)
			(end 25.57526 -2.429764)
			(stroke
				(width 0.1)
				(type default)
			)
			(layer "F.SilkS")
		)
		(fp_line
			(start 25.57526 -2.429764)
			(end 24.220424 -1.130046)
			(stroke
				(width 0.1)
				(type default)
			)
			(layer "F.SilkS")
		)
		(fp_line
			(start 25.57526 -2.429764)
			(end 24.220424 -1.130046)
			(stroke
				(width 0.1)
				(type default)
			)
			(layer "F.SilkS")
		)
		(fp_line
			(start 25.57526 -2.429764)
			(end 25.587452 -2.498852)
			(stroke
				(width 0.1)
				(type default)
			)
			(layer "F.SilkS")
		)
		(fp_line
			(start 25.57526 -2.429764)
			(end 25.587452 -2.498852)
			(stroke
				(width 0.1)
				(type default)
			)
			(layer "F.SilkS")
		)
		(fp_line
			(start 25.57907 -4.79933)
			(end 24.690324 -3.946652)
			(stroke
				(width 0.1)
				(type default)
			)
			(layer "F.SilkS")
		)
		(fp_line
			(start 25.57907 -4.79933)
			(end 24.690324 -3.946652)
			(stroke
				(width 0.1)
				(type default)
			)
			(layer "F.SilkS")
		)
		(fp_line
			(start 25.587452 -2.498852)
			(end 25.59939 -2.568194)
			(stroke
				(width 0.1)
				(type default)
			)
			(layer "F.SilkS")
		)
		(fp_line
			(start 25.587452 -2.498852)
			(end 25.59939 -2.568194)
			(stroke
				(width 0.1)
				(type default)
			)
			(layer "F.SilkS")
		)
		(fp_line
			(start 25.59939 -2.568194)
			(end 25.611836 -2.63779)
			(stroke
				(width 0.1)
				(type default)
			)
			(layer "F.SilkS")
		)
		(fp_line
			(start 25.59939 -2.568194)
			(end 25.611836 -2.63779)
			(stroke
				(width 0.1)
				(type default)
			)
			(layer "F.SilkS")
		)
		(fp_line
			(start 25.60447 -4.766564)
			(end 24.695658 -3.894328)
			(stroke
				(width 0.1)
				(type default)
			)
			(layer "F.SilkS")
		)
		(fp_line
			(start 25.60447 -4.766564)
			(end 24.695658 -3.894328)
			(stroke
				(width 0.1)
				(type default)
			)
			(layer "F.SilkS")
		)
		(fp_line
			(start 25.611836 -2.63779)
			(end 25.623774 -2.707132)
			(stroke
				(width 0.1)
				(type default)
			)
			(layer "F.SilkS")
		)
		(fp_line
			(start 25.611836 -2.63779)
			(end 25.623774 -2.707132)
			(stroke
				(width 0.1)
				(type default)
			)
			(layer "F.SilkS")
		)
		(fp_line
			(start 25.623774 -2.707132)
			(end 25.635966 -2.776474)
			(stroke
				(width 0.1)
				(type default)
			)
			(layer "F.SilkS")
		)
		(fp_line
			(start 25.623774 -2.707132)
			(end 25.635966 -2.776474)
			(stroke
				(width 0.1)
				(type default)
			)
			(layer "F.SilkS")
		)
		(fp_line
			(start 25.630378 -4.73329)
			(end 24.690324 -3.83159)
			(stroke
				(width 0.1)
				(type default)
			)
			(layer "F.SilkS")
		)
		(fp_line
			(start 25.630378 -4.73329)
			(end 24.690324 -3.83159)
			(stroke
				(width 0.1)
				(type default)
			)
			(layer "F.SilkS")
		)
		(fp_line
			(start 25.635966 -2.776474)
			(end 25.648412 -2.845816)
			(stroke
				(width 0.1)
				(type default)
			)
			(layer "F.SilkS")
		)
		(fp_line
			(start 25.635966 -2.776474)
			(end 25.648412 -2.845816)
			(stroke
				(width 0.1)
				(type default)
			)
			(layer "F.SilkS")
		)
		(fp_line
			(start 25.648412 -2.845816)
			(end 25.66035 -2.915412)
			(stroke
				(width 0.1)
				(type default)
			)
			(layer "F.SilkS")
		)
		(fp_line
			(start 25.648412 -2.845816)
			(end 25.66035 -2.915412)
			(stroke
				(width 0.1)
				(type default)
			)
			(layer "F.SilkS")
		)
		(fp_line
			(start 25.656286 -4.70027)
			(end 24.682958 -3.76682)
			(stroke
				(width 0.1)
				(type default)
			)
			(layer "F.SilkS")
		)
		(fp_line
			(start 25.656286 -4.70027)
			(end 24.682958 -3.76682)
			(stroke
				(width 0.1)
				(type default)
			)
			(layer "F.SilkS")
		)
		(fp_line
			(start 25.66035 -2.915412)
			(end 25.672542 -2.984754)
			(stroke
				(width 0.1)
				(type default)
			)
			(layer "F.SilkS")
		)
		(fp_line
			(start 25.66035 -2.915412)
			(end 25.672542 -2.984754)
			(stroke
				(width 0.1)
				(type default)
			)
			(layer "F.SilkS")
		)
		(fp_line
			(start 25.672542 -2.984754)
			(end 25.68448 -3.054096)
			(stroke
				(width 0.1)
				(type default)
			)
			(layer "F.SilkS")
		)
		(fp_line
			(start 25.672542 -2.984754)
			(end 25.68448 -3.054096)
			(stroke
				(width 0.1)
				(type default)
			)
			(layer "F.SilkS")
		)
		(fp_line
			(start 25.681686 -4.66725)
			(end 24.67102 -3.697478)
			(stroke
				(width 0.1)
				(type default)
			)
			(layer "F.SilkS")
		)
		(fp_line
			(start 25.681686 -4.66725)
			(end 24.67102 -3.697478)
			(stroke
				(width 0.1)
				(type default)
			)
			(layer "F.SilkS")
		)
		(fp_line
			(start 25.68448 -3.054096)
			(end 25.696926 -3.123184)
			(stroke
				(width 0.1)
				(type default)
			)
			(layer "F.SilkS")
		)
		(fp_line
			(start 25.68448 -3.054096)
			(end 25.696926 -3.123184)
			(stroke
				(width 0.1)
				(type default)
			)
			(layer "F.SilkS")
		)
		(fp_line
			(start 25.696926 -3.123184)
			(end 25.708864 -3.19278)
			(stroke
				(width 0.1)
				(type default)
			)
			(layer "F.SilkS")
		)
		(fp_line
			(start 25.696926 -3.123184)
			(end 25.708864 -3.19278)
			(stroke
				(width 0.1)
				(type default)
			)
			(layer "F.SilkS")
		)
		(fp_line
			(start 25.701498 -4.628388)
			(end 24.658574 -3.627882)
			(stroke
				(width 0.1)
				(type default)
			)
			(layer "F.SilkS")
		)
		(fp_line
			(start 25.701498 -4.628388)
			(end 24.658574 -3.627882)
			(stroke
				(width 0.1)
				(type default)
			)
			(layer "F.SilkS")
		)
		(fp_line
			(start 25.708864 -3.19278)
			(end 25.721056 -3.262122)
			(stroke
				(width 0.1)
				(type default)
			)
			(layer "F.SilkS")
		)
		(fp_line
			(start 25.708864 -3.19278)
			(end 25.721056 -3.262122)
			(stroke
				(width 0.1)
				(type default)
			)
			(layer "F.SilkS")
		)
		(fp_line
			(start 25.718516 -4.586986)
			(end 23.913084 -2.85496)
			(stroke
				(width 0.1)
				(type default)
			)
			(layer "F.SilkS")
		)
		(fp_line
			(start 25.718516 -4.586986)
			(end 23.913084 -2.85496)
			(stroke
				(width 0.1)
				(type default)
			)
			(layer "F.SilkS")
		)
		(fp_line
			(start 25.721056 -3.262122)
			(end 25.733502 -3.331464)
			(stroke
				(width 0.1)
				(type default)
			)
			(layer "F.SilkS")
		)
		(fp_line
			(start 25.721056 -3.262122)
			(end 25.733502 -3.331464)
			(stroke
				(width 0.1)
				(type default)
			)
			(layer "F.SilkS")
		)
		(fp_line
			(start 25.733502 -3.331464)
			(end 25.74544 -3.400806)
			(stroke
				(width 0.1)
				(type default)
			)
			(layer "F.SilkS")
		)
		(fp_line
			(start 25.733502 -3.331464)
			(end 25.74544 -3.400806)
			(stroke
				(width 0.1)
				(type default)
			)
			(layer "F.SilkS")
		)
		(fp_line
			(start 25.735534 -4.54533)
			(end 23.969472 -2.85115)
			(stroke
				(width 0.1)
				(type default)
			)
			(layer "F.SilkS")
		)
		(fp_line
			(start 25.735534 -4.54533)
			(end 23.969472 -2.85115)
			(stroke
				(width 0.1)
				(type default)
			)
			(layer "F.SilkS")
		)
		(fp_line
			(start 25.74544 -3.400806)
			(end 23.034752 -0.800608)
			(stroke
				(width 0.1)
				(type default)
			)
			(layer "F.SilkS")
		)
		(fp_line
			(start 25.74544 -3.400806)
			(end 23.034752 -0.800608)
			(stroke
				(width 0.1)
				(type default)
			)
			(layer "F.SilkS")
		)
		(fp_line
			(start 25.74544 -3.400806)
			(end 25.757632 -3.470402)
			(stroke
				(width 0.1)
				(type default)
			)
			(layer "F.SilkS")
		)
		(fp_line
			(start 25.74544 -3.400806)
			(end 25.757632 -3.470402)
			(stroke
				(width 0.1)
				(type default)
			)
			(layer "F.SilkS")
		)
		(fp_line
			(start 25.752298 -4.503928)
			(end 24.024336 -2.846324)
			(stroke
				(width 0.1)
				(type default)
			)
			(layer "F.SilkS")
		)
		(fp_line
			(start 25.752298 -4.503928)
			(end 24.024336 -2.846324)
			(stroke
				(width 0.1)
				(type default)
			)
			(layer "F.SilkS")
		)
		(fp_line
			(start 25.757632 -3.470402)
			(end 24.402796 -2.170938)
			(stroke
				(width 0.1)
				(type default)
			)
			(layer "F.SilkS")
		)
		(fp_line
			(start 25.757632 -3.470402)
			(end 24.402796 -2.170938)
			(stroke
				(width 0.1)
				(type default)
			)
			(layer "F.SilkS")
		)
		(fp_line
			(start 25.757632 -3.470402)
			(end 25.769824 -3.539744)
			(stroke
				(width 0.1)
				(type default)
			)
			(layer "F.SilkS")
		)
		(fp_line
			(start 25.757632 -3.470402)
			(end 25.769824 -3.539744)
			(stroke
				(width 0.1)
				(type default)
			)
			(layer "F.SilkS")
		)
		(fp_line
			(start 25.769316 -4.46278)
			(end 24.076914 -2.839466)
			(stroke
				(width 0.1)
				(type default)
			)
			(layer "F.SilkS")
		)
		(fp_line
			(start 25.769316 -4.46278)
			(end 24.076914 -2.839466)
			(stroke
				(width 0.1)
				(type default)
			)
			(layer "F.SilkS")
		)
		(fp_line
			(start 25.769824 -3.539744)
			(end 24.414988 -2.24028)
			(stroke
				(width 0.1)
				(type default)
			)
			(layer "F.SilkS")
		)
		(fp_line
			(start 25.769824 -3.539744)
			(end 24.414988 -2.24028)
			(stroke
				(width 0.1)
				(type default)
			)
			(layer "F.SilkS")
		)
		(fp_line
			(start 25.769824 -3.539744)
			(end 25.782016 -3.609086)
			(stroke
				(width 0.1)
				(type default)
			)
			(layer "F.SilkS")
		)
		(fp_line
			(start 25.769824 -3.539744)
			(end 25.782016 -3.609086)
			(stroke
				(width 0.1)
				(type default)
			)
			(layer "F.SilkS")
		)
		(fp_line
			(start 25.782016 -3.609086)
			(end 24.427434 -2.309368)
			(stroke
				(width 0.1)
				(type default)
			)
			(layer "F.SilkS")
		)
		(fp_line
			(start 25.782016 -3.609086)
			(end 24.427434 -2.309368)
			(stroke
				(width 0.1)
				(type default)
			)
			(layer "F.SilkS")
		)
		(fp_line
			(start 25.782016 -3.609086)
			(end 25.793954 -3.678174)
			(stroke
				(width 0.1)
				(type default)
			)
			(layer "F.SilkS")
		)
		(fp_line
			(start 25.782016 -3.609086)
			(end 25.793954 -3.678174)
			(stroke
				(width 0.1)
				(type default)
			)
			(layer "F.SilkS")
		)
		(fp_line
			(start 25.786588 -4.421378)
			(end 24.12873 -2.831084)
			(stroke
				(width 0.1)
				(type default)
			)
			(layer "F.SilkS")
		)
		(fp_line
			(start 25.786588 -4.421378)
			(end 24.12873 -2.831084)
			(stroke
				(width 0.1)
				(type default)
			)
			(layer "F.SilkS")
		)
		(fp_line
			(start 25.793954 -3.678174)
			(end 24.439372 -2.37871)
			(stroke
				(width 0.1)
				(type default)
			)
			(layer "F.SilkS")
		)
		(fp_line
			(start 25.793954 -3.678174)
			(end 24.439372 -2.37871)
			(stroke
				(width 0.1)
				(type default)
			)
			(layer "F.SilkS")
		)
		(fp_line
			(start 25.793954 -3.678174)
			(end 25.806146 -3.74777)
			(stroke
				(width 0.1)
				(type default)
			)
			(layer "F.SilkS")
		)
		(fp_line
			(start 25.793954 -3.678174)
			(end 25.806146 -3.74777)
			(stroke
				(width 0.1)
				(type default)
			)
			(layer "F.SilkS")
		)
		(fp_line
			(start 25.798526 -4.37515)
			(end 24.17826 -2.82067)
			(stroke
				(width 0.1)
				(type default)
			)
			(layer "F.SilkS")
		)
		(fp_line
			(start 25.798526 -4.37515)
			(end 24.17826 -2.82067)
			(stroke
				(width 0.1)
				(type default)
			)
			(layer "F.SilkS")
		)
		(fp_line
			(start 25.805384 -4.324096)
			(end 24.225504 -2.808478)
			(stroke
				(width 0.1)
				(type default)
			)
			(layer "F.SilkS")
		)
		(fp_line
			(start 25.805384 -4.324096)
			(end 24.225504 -2.808478)
			(stroke
				(width 0.1)
				(type default)
			)
			(layer "F.SilkS")
		)
		(fp_line
			(start 25.806146 -3.74777)
			(end 24.451564 -2.448306)
			(stroke
				(width 0.1)
				(type default)
			)
			(layer "F.SilkS")
		)
		(fp_line
			(start 25.806146 -3.74777)
			(end 24.451564 -2.448306)
			(stroke
				(width 0.1)
				(type default)
			)
			(layer "F.SilkS")
		)
		(fp_line
			(start 25.812242 -4.273296)
			(end 24.27097 -2.794508)
			(stroke
				(width 0.1)
				(type default)
			)
			(layer "F.SilkS")
		)
		(fp_line
			(start 25.812242 -4.273296)
			(end 24.27097 -2.794508)
			(stroke
				(width 0.1)
				(type default)
			)
			(layer "F.SilkS")
		)
		(fp_line
			(start 25.81275 -3.811524)
			(end 24.46401 -2.517648)
			(stroke
				(width 0.1)
				(type default)
			)
			(layer "F.SilkS")
		)
		(fp_line
			(start 25.81275 -3.811524)
			(end 24.46401 -2.517648)
			(stroke
				(width 0.1)
				(type default)
			)
			(layer "F.SilkS")
		)
		(fp_line
			(start 25.817576 -3.874008)
			(end 24.475948 -2.58699)
			(stroke
				(width 0.1)
				(type default)
			)
			(layer "F.SilkS")
		)
		(fp_line
			(start 25.817576 -3.874008)
			(end 24.475948 -2.58699)
			(stroke
				(width 0.1)
				(type default)
			)
			(layer "F.SilkS")
		)
		(fp_line
			(start 25.819608 -4.222242)
			(end 24.31415 -2.777998)
			(stroke
				(width 0.1)
				(type default)
			)
			(layer "F.SilkS")
		)
		(fp_line
			(start 25.819608 -4.222242)
			(end 24.31415 -2.777998)
			(stroke
				(width 0.1)
				(type default)
			)
			(layer "F.SilkS")
		)
		(fp_line
			(start 25.822656 -3.936492)
			(end 24.487886 -2.656332)
			(stroke
				(width 0.1)
				(type default)
			)
			(layer "F.SilkS")
		)
		(fp_line
			(start 25.822656 -3.936492)
			(end 24.487886 -2.656332)
			(stroke
				(width 0.1)
				(type default)
			)
			(layer "F.SilkS")
		)
		(fp_line
			(start 25.826466 -4.170934)
			(end 24.35606 -2.760472)
			(stroke
				(width 0.1)
				(type default)
			)
			(layer "F.SilkS")
		)
		(fp_line
			(start 25.826466 -4.170934)
			(end 24.35606 -2.760472)
			(stroke
				(width 0.1)
				(type default)
			)
			(layer "F.SilkS")
		)
		(fp_line
			(start 25.827736 -3.99923)
			(end 24.468836 -2.695448)
			(stroke
				(width 0.1)
				(type default)
			)
			(layer "F.SilkS")
		)
		(fp_line
			(start 25.827736 -3.99923)
			(end 24.468836 -2.695448)
			(stroke
				(width 0.1)
				(type default)
			)
			(layer "F.SilkS")
		)
		(fp_line
			(start 25.83307 -4.062222)
			(end 24.432514 -2.718816)
			(stroke
				(width 0.1)
				(type default)
			)
			(layer "F.SilkS")
		)
		(fp_line
			(start 25.83307 -4.062222)
			(end 24.432514 -2.718816)
			(stroke
				(width 0.1)
				(type default)
			)
			(layer "F.SilkS")
		)
		(fp_line
			(start 25.833324 -4.120134)
			(end 24.394668 -2.739898)
			(stroke
				(width 0.1)
				(type default)
			)
			(layer "F.SilkS")
		)
		(fp_line
			(start 25.833324 -4.120134)
			(end 24.394668 -2.739898)
			(stroke
				(width 0.1)
				(type default)
			)
			(layer "F.SilkS")
		)
	)
	(footprint ""
		(layer "F.Cu")
		(at 299.631354 -78.217268 180)
		(property "Reference" "PR315"
			(at 2.959354 -4.393438 0)
			(unlocked yes)
			(layer "F.SilkS")
			(effects
				(font
					(size 0.7874 0.5842)
					(thickness 0.1524)
				)
				(justify left)
			)
		)
		(property "Value" ""
			(at 0 0 180)
			(layer "F.Fab")
			(effects
				(font
					(size 1.27 1.27)
				)
			)
		)
		(duplicate_pad_numbers_are_jumpers no)
		(fp_line
			(start 3.9878 3.5814)
			(end -3.9878 3.5814)
			(stroke
				(width 0.1524)
				(type default)
			)
			(layer "F.SilkS")
		)
		(fp_line
			(start 3.9878 -3.5814)
			(end 3.9878 3.5814)
			(stroke
				(width 0.1524)
				(type default)
			)
			(layer "F.SilkS")
		)
		(fp_line
			(start -3.9878 3.5814)
			(end -3.9878 -3.5814)
			(stroke
				(width 0.1524)
				(type default)
			)
			(layer "F.SilkS")
		)
		(fp_line
			(start -3.9878 -3.5814)
			(end 3.9878 -3.5814)
			(stroke
				(width 0.1524)
				(type default)
			)
			(layer "F.SilkS")
		)
		(fp_line
			(start 3.5306 3.353054)
			(end -3.5306 3.353054)
			(stroke
				(width 0.1)
				(type default)
			)
			(layer "F.Fab")
		)
		(fp_line
			(start 3.5306 -3.353054)
			(end 3.5306 3.353054)
			(stroke
				(width 0.1)
				(type default)
			)
			(layer "F.Fab")
		)
		(fp_line
			(start -3.5306 3.353054)
			(end -3.5306 -3.353054)
			(stroke
				(width 0.1)
				(type default)
			)
			(layer "F.Fab")
		)
		(fp_line
			(start -3.5306 -3.353054)
			(end 3.5306 -3.353054)
			(stroke
				(width 0.1)
				(type default)
			)
			(layer "F.Fab")
		)
		(pad "1A" smd rect
			(at -2.249932 0)
			(size 3.2004 6.858)
			(layers "F.Cu" "F.Mask" "F.Paste")
			(net "P52V_1")
		)
		(pad "1B" smd rect
			(at -0.776732 0 180)
			(size 0.254 0.508)
			(layers "F.Cu" "F.Mask" "F.Paste")
			(net "P52V_HS1_SENSE_P_R2")
		)
		(pad "2A" smd rect
			(at 2.249932 0)
			(size 3.2004 6.858)
			(layers "F.Cu" "F.Mask" "F.Paste")
			(net "P52V_HS1_DRAIN_2")
		)
		(pad "2B" smd rect
			(at 0.776732 0 180)
			(size 0.254 0.508)
			(layers "F.Cu" "F.Mask" "F.Paste")
			(net "P52V_HS1_SENSE_N_R2")
		)
	)
	(footprint ""
		(layer "F.Cu")
		(at 95.504 -51.943)
		(property "Reference" "PC86"
			(at 0 0 0)
			(layer "F.SilkS")
			(hide yes)
			(effects
				(font
					(size 1.27 1.27)
				)
			)
		)
		(property "Value" ""
			(at 0 0 0)
			(layer "F.Fab")
			(effects
				(font
					(size 1.27 1.27)
				)
			)
		)
		(duplicate_pad_numbers_are_jumpers no)
		(fp_line
			(start -1.524 -0.762)
			(end 1.524 -0.762)
			(stroke
				(width 0.1524)
				(type default)
			)
			(layer "F.SilkS")
		)
		(fp_line
			(start -1.524 0.762)
			(end -1.524 -0.762)
			(stroke
				(width 0.1524)
				(type default)
			)
			(layer "F.SilkS")
		)
		(fp_line
			(start 1.524 -0.762)
			(end 1.524 0.762)
			(stroke
				(width 0.1524)
				(type default)
			)
			(layer "F.SilkS")
		)
		(fp_line
			(start 1.524 0.762)
			(end -1.524 0.762)
			(stroke
				(width 0.1524)
				(type default)
			)
			(layer "F.SilkS")
		)
		(fp_line
			(start -1.1049 -0.724916)
			(end -1.1049 0.724916)
			(stroke
				(width 0.1)
				(type default)
			)
			(layer "F.Fab")
		)
		(fp_line
			(start -1.1049 0.724916)
			(end 1.1049 0.724916)
			(stroke
				(width 0.1)
				(type default)
			)
			(layer "F.Fab")
		)
		(fp_line
			(start 1.1049 -0.724916)
			(end -1.1049 -0.724916)
			(stroke
				(width 0.1)
				(type default)
			)
			(layer "F.Fab")
		)
		(fp_line
			(start 1.1049 0.724916)
			(end 1.1049 -0.724916)
			(stroke
				(width 0.1)
				(type default)
			)
			(layer "F.Fab")
		)
		(pad "1" smd rect
			(at -0.889 0 180)
			(size 1.016 1.27)
			(layers "F.Cu" "F.Mask" "F.Paste")
			(net "P12V_BRICK")
		)
		(pad "2" smd rect
			(at 0.889 0 180)
			(size 1.016 1.27)
			(layers "F.Cu" "F.Mask" "F.Paste")
			(net "GND")
		)
	)
	(footprint ""
		(layer "F.Cu")
		(at 277.114 -24.257 90)
		(property "Reference" "R5888"
			(at 0 0 90)
			(layer "F.SilkS")
			(hide yes)
			(effects
				(font
					(size 1.27 1.27)
				)
			)
		)
		(property "Value" ""
			(at 0 0 90)
			(layer "F.Fab")
			(effects
				(font
					(size 1.27 1.27)
				)
			)
		)
		(duplicate_pad_numbers_are_jumpers no)
		(fp_line
			(start 0.7874 -0.4064)
			(end 0.7874 0.4064)
			(stroke
				(width 0.1524)
				(type default)
			)
			(layer "F.SilkS")
		)
		(fp_line
			(start -0.7874 -0.4064)
			(end 0.7874 -0.4064)
			(stroke
				(width 0.1524)
				(type default)
			)
			(layer "F.SilkS")
		)
		(fp_line
			(start 0.7874 0.4064)
			(end -0.7874 0.4064)
			(stroke
				(width 0.1524)
				(type default)
			)
			(layer "F.SilkS")
		)
		(fp_line
			(start -0.7874 0.4064)
			(end -0.7874 -0.4064)
			(stroke
				(width 0.1524)
				(type default)
			)
			(layer "F.SilkS")
		)
		(fp_line
			(start -0.12065 -0.305054)
			(end -0.12065 -0.2794)
			(stroke
				(width 0.1)
				(type default)
			)
			(layer "F.Fab")
		)
		(fp_line
			(start -0.67945 -0.305054)
			(end -0.12065 -0.305054)
			(stroke
				(width 0.1)
				(type default)
			)
			(layer "F.Fab")
		)
		(fp_line
			(start 0.67945 -0.3048)
			(end 0.67945 0.3048)
			(stroke
				(width 0.1)
				(type default)
			)
			(layer "F.Fab")
		)
		(fp_line
			(start 0.12065 -0.3048)
			(end 0.67945 -0.3048)
			(stroke
				(width 0.1)
				(type default)
			)
			(layer "F.Fab")
		)
		(fp_line
			(start 0.12065 -0.2794)
			(end 0.12065 -0.3048)
			(stroke
				(width 0.1)
				(type default)
			)
			(layer "F.Fab")
		)
		(fp_line
			(start -0.12065 -0.2794)
			(end 0.12065 -0.2794)
			(stroke
				(width 0.1)
				(type default)
			)
			(layer "F.Fab")
		)
		(fp_line
			(start 0.120396 0.2794)
			(end -0.12065 0.2794)
			(stroke
				(width 0.1)
				(type default)
			)
			(layer "F.Fab")
		)
		(fp_line
			(start -0.12065 0.2794)
			(end -0.12065 0.3048)
			(stroke
				(width 0.1)
				(type default)
			)
			(layer "F.Fab")
		)
		(fp_line
			(start 0.67945 0.3048)
			(end 0.120396 0.3048)
			(stroke
				(width 0.1)
				(type default)
			)
			(layer "F.Fab")
		)
		(fp_line
			(start 0.120396 0.3048)
			(end 0.120396 0.2794)
			(stroke
				(width 0.1)
				(type default)
			)
			(layer "F.Fab")
		)
		(fp_line
			(start -0.12065 0.3048)
			(end -0.67945 0.3048)
			(stroke
				(width 0.1)
				(type default)
			)
			(layer "F.Fab")
		)
		(fp_line
			(start -0.67945 0.3048)
			(end -0.67945 -0.305054)
			(stroke
				(width 0.1)
				(type default)
			)
			(layer "F.Fab")
		)
		(pad "1" smd circle
			(at -0.40005 0 90)
			(size 0 0)
			(layers "F.Cu" "F.Mask" "F.Paste")
			(net "P3V3_AND")
		)
		(pad "2" smd circle
			(at 0.40005 0 90)
			(size 0 0)
			(layers "F.Cu" "F.Mask" "F.Paste")
			(net "GND")
		)
	)
	(footprint ""
		(layer "F.Cu")
		(at 162.687 -49.911)
		(property "Reference" "PC35"
			(at 0 0 0)
			(layer "F.SilkS")
			(hide yes)
			(effects
				(font
					(size 1.27 1.27)
				)
			)
		)
		(property "Value" ""
			(at 0 0 0)
			(layer "F.Fab")
			(effects
				(font
					(size 1.27 1.27)
				)
			)
		)
		(duplicate_pad_numbers_are_jumpers no)
		(fp_line
			(start -1.524 -0.762)
			(end 1.524 -0.762)
			(stroke
				(width 0.1524)
				(type default)
			)
			(layer "F.SilkS")
		)
		(fp_line
			(start -1.524 0.762)
			(end -1.524 -0.762)
			(stroke
				(width 0.1524)
				(type default)
			)
			(layer "F.SilkS")
		)
		(fp_line
			(start 1.524 -0.762)
			(end 1.524 0.762)
			(stroke
				(width 0.1524)
				(type default)
			)
			(layer "F.SilkS")
		)
		(fp_line
			(start 1.524 0.762)
			(end -1.524 0.762)
			(stroke
				(width 0.1524)
				(type default)
			)
			(layer "F.SilkS")
		)
		(fp_line
			(start -1.1049 -0.724916)
			(end -1.1049 0.724916)
			(stroke
				(width 0.1)
				(type default)
			)
			(layer "F.Fab")
		)
		(fp_line
			(start -1.1049 0.724916)
			(end 1.1049 0.724916)
			(stroke
				(width 0.1)
				(type default)
			)
			(layer "F.Fab")
		)
		(fp_line
			(start 1.1049 -0.724916)
			(end -1.1049 -0.724916)
			(stroke
				(width 0.1)
				(type default)
			)
			(layer "F.Fab")
		)
		(fp_line
			(start 1.1049 0.724916)
			(end 1.1049 -0.724916)
			(stroke
				(width 0.1)
				(type default)
			)
			(layer "F.Fab")
		)
		(pad "1" smd rect
			(at -0.889 0 180)
			(size 1.016 1.27)
			(layers "F.Cu" "F.Mask" "F.Paste")
			(net "P12V_BRICK")
		)
		(pad "2" smd rect
			(at 0.889 0 180)
			(size 1.016 1.27)
			(layers "F.Cu" "F.Mask" "F.Paste")
			(net "GND")
		)
	)
	(footprint ""
		(layer "F.Cu")
		(at 286.383222 -48.960024)
		(property "Reference" "PC560"
			(at 0 0 0)
			(layer "F.SilkS")
			(hide yes)
			(effects
				(font
					(size 1.27 1.27)
				)
			)
		)
		(property "Value" ""
			(at 0 0 0)
			(layer "F.Fab")
			(effects
				(font
					(size 1.27 1.27)
				)
			)
		)
		(duplicate_pad_numbers_are_jumpers no)
		(fp_line
			(start -0.7874 -0.4064)
			(end 0.7874 -0.4064)
			(stroke
				(width 0.1524)
				(type default)
			)
			(layer "F.SilkS")
		)
		(fp_line
			(start -0.7874 0.4064)
			(end -0.7874 -0.4064)
			(stroke
				(width 0.1524)
				(type default)
			)
			(layer "F.SilkS")
		)
		(fp_line
			(start 0.7874 -0.4064)
			(end 0.7874 0.4064)
			(stroke
				(width 0.1524)
				(type default)
			)
			(layer "F.SilkS")
		)
		(fp_line
			(start 0.7874 0.4064)
			(end -0.7874 0.4064)
			(stroke
				(width 0.1524)
				(type default)
			)
			(layer "F.SilkS")
		)
		(fp_line
			(start -0.67945 -0.305054)
			(end -0.12065 -0.305054)
			(stroke
				(width 0.1)
				(type default)
			)
			(layer "F.Fab")
		)
		(fp_line
			(start -0.67945 0.3048)
			(end -0.67945 -0.305054)
			(stroke
				(width 0.1)
				(type default)
			)
			(layer "F.Fab")
		)
		(fp_line
			(start -0.12065 -0.305054)
			(end -0.12065 -0.2794)
			(stroke
				(width 0.1)
				(type default)
			)
			(layer "F.Fab")
		)
		(fp_line
			(start -0.12065 -0.2794)
			(end 0.12065 -0.2794)
			(stroke
				(width 0.1)
				(type default)
			)
			(layer "F.Fab")
		)
		(fp_line
			(start -0.12065 0.2794)
			(end -0.12065 0.3048)
			(stroke
				(width 0.1)
				(type default)
			)
			(layer "F.Fab")
		)
		(fp_line
			(start -0.12065 0.3048)
			(end -0.67945 0.3048)
			(stroke
				(width 0.1)
				(type default)
			)
			(layer "F.Fab")
		)
		(fp_line
			(start 0.120396 0.2794)
			(end -0.12065 0.2794)
			(stroke
				(width 0.1)
				(type default)
			)
			(layer "F.Fab")
		)
		(fp_line
			(start 0.120396 0.3048)
			(end 0.120396 0.2794)
			(stroke
				(width 0.1)
				(type default)
			)
			(layer "F.Fab")
		)
		(fp_line
			(start 0.12065 -0.3048)
			(end 0.67945 -0.3048)
			(stroke
				(width 0.1)
				(type default)
			)
			(layer "F.Fab")
		)
		(fp_line
			(start 0.12065 -0.2794)
			(end 0.12065 -0.3048)
			(stroke
				(width 0.1)
				(type default)
			)
			(layer "F.Fab")
		)
		(fp_line
			(start 0.67945 -0.3048)
			(end 0.67945 0.3048)
			(stroke
				(width 0.1)
				(type default)
			)
			(layer "F.Fab")
		)
		(fp_line
			(start 0.67945 0.3048)
			(end 0.120396 0.3048)
			(stroke
				(width 0.1)
				(type default)
			)
			(layer "F.Fab")
		)
		(pad "1" smd circle
			(at -0.40005 0)
			(size 0 0)
			(layers "F.Cu" "F.Mask" "F.Paste")
			(net "P52V_HS1_TEMPP")
		)
		(pad "2" smd circle
			(at 0.40005 0)
			(size 0 0)
			(layers "F.Cu" "F.Mask" "F.Paste")
			(net "P52V_HS1_TEMPN")
		)
	)
	(footprint ""
		(layer "F.Cu")
		(at 84.713826 -127.889)
		(property "Reference" "PC50"
			(at 0 0 0)
			(layer "F.SilkS")
			(hide yes)
			(effects
				(font
					(size 1.27 1.27)
				)
			)
		)
		(property "Value" ""
			(at 0 0 0)
			(layer "F.Fab")
			(effects
				(font
					(size 1.27 1.27)
				)
			)
		)
		(duplicate_pad_numbers_are_jumpers no)
		(fp_line
			(start -2.2098 -0.9398)
			(end 2.2098 -0.9398)
			(stroke
				(width 0.1524)
				(type default)
			)
			(layer "F.SilkS")
		)
		(fp_line
			(start -2.2098 0.9398)
			(end -2.2098 -0.9398)
			(stroke
				(width 0.1524)
				(type default)
			)
			(layer "F.SilkS")
		)
		(fp_line
			(start 2.2098 -0.9398)
			(end 2.2098 0.9398)
			(stroke
				(width 0.1524)
				(type default)
			)
			(layer "F.SilkS")
		)
		(fp_line
			(start 2.2098 0.9398)
			(end -2.2098 0.9398)
			(stroke
				(width 0.1524)
				(type default)
			)
			(layer "F.SilkS")
		)
		(fp_line
			(start -1.700022 -0.899922)
			(end 1.700022 -0.899922)
			(stroke
				(width 0.1)
				(type default)
			)
			(layer "F.Fab")
		)
		(fp_line
			(start -1.700022 0.899922)
			(end -1.700022 -0.899922)
			(stroke
				(width 0.1)
				(type default)
			)
			(layer "F.Fab")
		)
		(fp_line
			(start 1.700022 -0.899922)
			(end 1.700022 0.899922)
			(stroke
				(width 0.1)
				(type default)
			)
			(layer "F.Fab")
		)
		(fp_line
			(start 1.700022 0.899922)
			(end -1.700022 0.899922)
			(stroke
				(width 0.1)
				(type default)
			)
			(layer "F.Fab")
		)
		(pad "1" smd rect
			(at -1.4732 0 180)
			(size 1.1684 1.5748)
			(layers "F.Cu" "F.Mask" "F.Paste")
			(net "P52V_HS_FILTER")
		)
		(pad "2" smd rect
			(at 1.4732 0 180)
			(size 1.1684 1.5748)
			(layers "F.Cu" "F.Mask" "F.Paste")
			(net "GND")
		)
	)
	(footprint ""
		(layer "F.Cu")
		(at 315.000132 -132.40004 -90)
		(property "Reference" "H19"
			(at -6.13029 1.056132 0)
			(unlocked yes)
			(layer "F.SilkS")
			(effects
				(font
					(size 0.7874 0.5842)
					(thickness 0.1524)
				)
				(justify left)
			)
		)
		(property "Value" ""
			(at 0 0 270)
			(layer "F.Fab")
			(effects
				(font
					(size 1.27 1.27)
				)
			)
		)
		(duplicate_pad_numbers_are_jumpers no)
		(pad "1" thru_hole circle
			(at 0 0 270)
			(size 10.16 10.16)
			(drill 6.4008
				(offset 0 0)
			)
			(layers "*.Cu" "*.Mask")
			(remove_unused_layers no)
			(net "GND")
			(clearance -1.6256)
			(padstack
				(mode front_inner_back)
				(layer "Inner"
					(shape circle)
					(size 10.16 10.16)
					(clearance -1.6256)
				)
				(layer "B.Cu"
					(shape oval)
					(size 10.0076 32.004)
					(offset 0 10.9982)
					(clearance -1.5494)
				)
			)
		)
	)
	(footprint ""
		(layer "F.Cu")
		(at 209.291174 -60.96)
		(property "Reference" "PC134"
			(at -1.773174 -3.65633 0)
			(unlocked yes)
			(layer "F.SilkS")
			(effects
				(font
					(size 0.7874 0.5842)
					(thickness 0.1524)
				)
				(justify left)
			)
		)
		(property "Value" ""
			(at 0 0 0)
			(layer "F.Fab")
			(effects
				(font
					(size 1.27 1.27)
				)
			)
		)
		(duplicate_pad_numbers_are_jumpers no)
		(fp_line
			(start 5.2578 2.499868)
			(end -5.2578 2.499868)
			(stroke
				(width 0.1524)
				(type default)
			)
			(layer "F.SilkS")
		)
		(fp_circle
			(center 0 2.499868)
			(end 5.2578 2.499868)
			(stroke
				(width 0.1524)
				(type default)
			)
			(fill no)
			(layer "F.SilkS")
		)
		(fp_poly
			(pts
				(arc
					(start 5.2578 2.499868)
					(mid 0 7.757922)
					(end -5.2578 2.499868)
				)
			)
			(stroke
				(width 0)
				(type default)
			)
			(fill yes)
			(layer "F.SilkS")
		)
		(fp_circle
			(center 0 2.499868)
			(end 5.2578 2.499868)
			(stroke
				(width 0.1)
				(type default)
			)
			(fill no)
			(layer "F.Fab")
		)
		(pad "1" thru_hole rect
			(at 0 0 270)
			(size 1.524 1.524)
			(drill 1.016)
			(layers "*.Cu" "*.Mask")
			(remove_unused_layers no)
			(net "P12V_BRICK")
			(clearance 0)
			(padstack
				(mode front_inner_back)
				(layer "Inner"
					(shape circle)
					(size 1.524 1.524)
					(clearance 0)
				)
				(layer "B.Cu"
					(shape rect)
					(size 1.524 1.524)
					(clearance 0)
				)
			)
		)
		(pad "2" thru_hole circle
			(at 0 4.99999 270)
			(size 1.524 1.524)
			(drill 1.016)
			(layers "*.Cu" "*.Mask")
			(remove_unused_layers no)
			(net "GND")
			(clearance 0)
		)
	)
	(footprint ""
		(layer "F.Cu")
		(at 100.076 -62.738)
		(property "Reference" "PC56"
			(at 0 0 0)
			(layer "F.SilkS")
			(hide yes)
			(effects
				(font
					(size 1.27 1.27)
				)
			)
		)
		(property "Value" ""
			(at 0 0 0)
			(layer "F.Fab")
			(effects
				(font
					(size 1.27 1.27)
				)
			)
		)
		(duplicate_pad_numbers_are_jumpers no)
		(fp_line
			(start -0.7874 -0.4064)
			(end 0.7874 -0.4064)
			(stroke
				(width 0.1524)
				(type default)
			)
			(layer "F.SilkS")
		)
		(fp_line
			(start -0.7874 0.4064)
			(end -0.7874 -0.4064)
			(stroke
				(width 0.1524)
				(type default)
			)
			(layer "F.SilkS")
		)
		(fp_line
			(start 0.7874 -0.4064)
			(end 0.7874 0.4064)
			(stroke
				(width 0.1524)
				(type default)
			)
			(layer "F.SilkS")
		)
		(fp_line
			(start 0.7874 0.4064)
			(end -0.7874 0.4064)
			(stroke
				(width 0.1524)
				(type default)
			)
			(layer "F.SilkS")
		)
		(fp_line
			(start -0.6858 -0.3048)
			(end -0.1016 -0.3048)
			(stroke
				(width 0.1)
				(type default)
			)
			(layer "F.Fab")
		)
		(fp_line
			(start -0.6858 0.3048)
			(end -0.6858 -0.3048)
			(stroke
				(width 0.1)
				(type default)
			)
			(layer "F.Fab")
		)
		(fp_line
			(start -0.1016 -0.3048)
			(end -0.1016 -0.2794)
			(stroke
				(width 0.1)
				(type default)
			)
			(layer "F.Fab")
		)
		(fp_line
			(start -0.1016 -0.2794)
			(end 0.1016 -0.2794)
			(stroke
				(width 0.1)
				(type default)
			)
			(layer "F.Fab")
		)
		(fp_line
			(start -0.1016 0.2794)
			(end -0.1016 0.3048)
			(stroke
				(width 0.1)
				(type default)
			)
			(layer "F.Fab")
		)
		(fp_line
			(start -0.1016 0.3048)
			(end -0.6858 0.3048)
			(stroke
				(width 0.1)
				(type default)
			)
			(layer "F.Fab")
		)
		(fp_line
			(start 0.1016 -0.3048)
			(end 0.6858 -0.3048)
			(stroke
				(width 0.1)
				(type default)
			)
			(layer "F.Fab")
		)
		(fp_line
			(start 0.1016 -0.2794)
			(end 0.1016 -0.3048)
			(stroke
				(width 0.1)
				(type default)
			)
			(layer "F.Fab")
		)
		(fp_line
			(start 0.1016 0.2794)
			(end -0.1016 0.2794)
			(stroke
				(width 0.1)
				(type default)
			)
			(layer "F.Fab")
		)
		(fp_line
			(start 0.1016 0.3048)
			(end 0.1016 0.2794)
			(stroke
				(width 0.1)
				(type default)
			)
			(layer "F.Fab")
		)
		(fp_line
			(start 0.6858 -0.3048)
			(end 0.6858 0.3048)
			(stroke
				(width 0.1)
				(type default)
			)
			(layer "F.Fab")
		)
		(fp_line
			(start 0.6858 0.3048)
			(end 0.1016 0.3048)
			(stroke
				(width 0.1)
				(type default)
			)
			(layer "F.Fab")
		)
		(pad "1" smd rect
			(at -0.40005 0 180)
			(size 0.4572 0.508)
			(layers "F.Cu" "F.Mask" "F.Paste")
			(net "P12V_BRICK")
		)
		(pad "2" smd rect
			(at 0.40005 0 180)
			(size 0.4572 0.508)
			(layers "F.Cu" "F.Mask" "F.Paste")
			(net "GND")
		)
	)
	(footprint ""
		(layer "F.Cu")
		(at 179.324 -14.732 90)
		(property "Reference" "PR88"
			(at 0 0 90)
			(layer "F.SilkS")
			(hide yes)
			(effects
				(font
					(size 1.27 1.27)
				)
			)
		)
		(property "Value" ""
			(at 0 0 90)
			(layer "F.Fab")
			(effects
				(font
					(size 1.27 1.27)
				)
			)
		)
		(duplicate_pad_numbers_are_jumpers no)
		(fp_line
			(start 0.7874 -0.4064)
			(end 0.7874 0.4064)
			(stroke
				(width 0.1524)
				(type default)
			)
			(layer "F.SilkS")
		)
		(fp_line
			(start -0.7874 -0.4064)
			(end 0.7874 -0.4064)
			(stroke
				(width 0.1524)
				(type default)
			)
			(layer "F.SilkS")
		)
		(fp_line
			(start 0.7874 0.4064)
			(end -0.7874 0.4064)
			(stroke
				(width 0.1524)
				(type default)
			)
			(layer "F.SilkS")
		)
		(fp_line
			(start -0.7874 0.4064)
			(end -0.7874 -0.4064)
			(stroke
				(width 0.1524)
				(type default)
			)
			(layer "F.SilkS")
		)
		(fp_line
			(start -0.12065 -0.305054)
			(end -0.12065 -0.2794)
			(stroke
				(width 0.1)
				(type default)
			)
			(layer "F.Fab")
		)
		(fp_line
			(start -0.67945 -0.305054)
			(end -0.12065 -0.305054)
			(stroke
				(width 0.1)
				(type default)
			)
			(layer "F.Fab")
		)
		(fp_line
			(start 0.67945 -0.3048)
			(end 0.67945 0.3048)
			(stroke
				(width 0.1)
				(type default)
			)
			(layer "F.Fab")
		)
		(fp_line
			(start 0.12065 -0.3048)
			(end 0.67945 -0.3048)
			(stroke
				(width 0.1)
				(type default)
			)
			(layer "F.Fab")
		)
		(fp_line
			(start 0.12065 -0.2794)
			(end 0.12065 -0.3048)
			(stroke
				(width 0.1)
				(type default)
			)
			(layer "F.Fab")
		)
		(fp_line
			(start -0.12065 -0.2794)
			(end 0.12065 -0.2794)
			(stroke
				(width 0.1)
				(type default)
			)
			(layer "F.Fab")
		)
		(fp_line
			(start 0.120396 0.2794)
			(end -0.12065 0.2794)
			(stroke
				(width 0.1)
				(type default)
			)
			(layer "F.Fab")
		)
		(fp_line
			(start -0.12065 0.2794)
			(end -0.12065 0.3048)
			(stroke
				(width 0.1)
				(type default)
			)
			(layer "F.Fab")
		)
		(fp_line
			(start 0.67945 0.3048)
			(end 0.120396 0.3048)
			(stroke
				(width 0.1)
				(type default)
			)
			(layer "F.Fab")
		)
		(fp_line
			(start 0.120396 0.3048)
			(end 0.120396 0.2794)
			(stroke
				(width 0.1)
				(type default)
			)
			(layer "F.Fab")
		)
		(fp_line
			(start -0.12065 0.3048)
			(end -0.67945 0.3048)
			(stroke
				(width 0.1)
				(type default)
			)
			(layer "F.Fab")
		)
		(fp_line
			(start -0.67945 0.3048)
			(end -0.67945 -0.305054)
			(stroke
				(width 0.1)
				(type default)
			)
			(layer "F.Fab")
		)
		(pad "1" smd circle
			(at -0.40005 0 90)
			(size 0 0)
			(layers "F.Cu" "F.Mask" "F.Paste")
			(net "P3V3_AUX_MODE")
		)
		(pad "2" smd circle
			(at 0.40005 0 90)
			(size 0 0)
			(layers "F.Cu" "F.Mask" "F.Paste")
			(net "GND")
		)
	)
	(footprint ""
		(layer "F.Cu")
		(at 176.79289 -9.32053)
		(property "Reference" "PR91"
			(at 0 0 0)
			(layer "F.SilkS")
			(hide yes)
			(effects
				(font
					(size 1.27 1.27)
				)
			)
		)
		(property "Value" ""
			(at 0 0 0)
			(layer "F.Fab")
			(effects
				(font
					(size 1.27 1.27)
				)
			)
		)
		(duplicate_pad_numbers_are_jumpers no)
		(fp_line
			(start -0.7874 -0.4064)
			(end 0.7874 -0.4064)
			(stroke
				(width 0.1524)
				(type default)
			)
			(layer "F.SilkS")
		)
		(fp_line
			(start -0.7874 0.4064)
			(end -0.7874 -0.4064)
			(stroke
				(width 0.1524)
				(type default)
			)
			(layer "F.SilkS")
		)
		(fp_line
			(start 0.7874 -0.4064)
			(end 0.7874 0.4064)
			(stroke
				(width 0.1524)
				(type default)
			)
			(layer "F.SilkS")
		)
		(fp_line
			(start 0.7874 0.4064)
			(end -0.7874 0.4064)
			(stroke
				(width 0.1524)
				(type default)
			)
			(layer "F.SilkS")
		)
		(fp_line
			(start -0.67945 -0.305054)
			(end -0.12065 -0.305054)
			(stroke
				(width 0.1)
				(type default)
			)
			(layer "F.Fab")
		)
		(fp_line
			(start -0.67945 0.3048)
			(end -0.67945 -0.305054)
			(stroke
				(width 0.1)
				(type default)
			)
			(layer "F.Fab")
		)
		(fp_line
			(start -0.12065 -0.305054)
			(end -0.12065 -0.2794)
			(stroke
				(width 0.1)
				(type default)
			)
			(layer "F.Fab")
		)
		(fp_line
			(start -0.12065 -0.2794)
			(end 0.12065 -0.2794)
			(stroke
				(width 0.1)
				(type default)
			)
			(layer "F.Fab")
		)
		(fp_line
			(start -0.12065 0.2794)
			(end -0.12065 0.3048)
			(stroke
				(width 0.1)
				(type default)
			)
			(layer "F.Fab")
		)
		(fp_line
			(start -0.12065 0.3048)
			(end -0.67945 0.3048)
			(stroke
				(width 0.1)
				(type default)
			)
			(layer "F.Fab")
		)
		(fp_line
			(start 0.120396 0.2794)
			(end -0.12065 0.2794)
			(stroke
				(width 0.1)
				(type default)
			)
			(layer "F.Fab")
		)
		(fp_line
			(start 0.120396 0.3048)
			(end 0.120396 0.2794)
			(stroke
				(width 0.1)
				(type default)
			)
			(layer "F.Fab")
		)
		(fp_line
			(start 0.12065 -0.3048)
			(end 0.67945 -0.3048)
			(stroke
				(width 0.1)
				(type default)
			)
			(layer "F.Fab")
		)
		(fp_line
			(start 0.12065 -0.2794)
			(end 0.12065 -0.3048)
			(stroke
				(width 0.1)
				(type default)
			)
			(layer "F.Fab")
		)
		(fp_line
			(start 0.67945 -0.3048)
			(end 0.67945 0.3048)
			(stroke
				(width 0.1)
				(type default)
			)
			(layer "F.Fab")
		)
		(fp_line
			(start 0.67945 0.3048)
			(end 0.120396 0.3048)
			(stroke
				(width 0.1)
				(type default)
			)
			(layer "F.Fab")
		)
		(pad "1" smd circle
			(at -0.40005 0)
			(size 0 0)
			(layers "F.Cu" "F.Mask" "F.Paste")
			(net "P3V3_AUX_FB")
		)
		(pad "2" smd circle
			(at 0.40005 0)
			(size 0 0)
			(layers "F.Cu" "F.Mask" "F.Paste")
			(net "GND")
		)
	)
	(footprint ""
		(layer "F.Cu")
		(at 251.079 -57.912 -90)
		(property "Reference" "H14"
			(at -6.429502 12.066016 0)
			(unlocked yes)
			(layer "F.SilkS")
			(effects
				(font
					(size 0.7874 0.5842)
					(thickness 0.1524)
				)
				(justify left)
			)
		)
		(property "Value" ""
			(at 0 0 270)
			(layer "F.Fab")
			(effects
				(font
					(size 1.27 1.27)
				)
			)
		)
		(duplicate_pad_numbers_are_jumpers no)
		(pad "1" thru_hole oval
			(at 0 0 270)
			(size 10.0076 32.004)
			(drill 3.0226
				(offset 0 10.999978)
			)
			(layers "*.Cu" "*.Mask")
			(remove_unused_layers no)
			(net "GND")
			(clearance -1.995678)
			(padstack
				(mode front_inner_back)
				(layer "Inner"
					(shape circle)
					(size 0 0)
					(clearance 0)
				)
				(layer "B.Cu"
					(shape oval)
					(size 10.0076 32.004)
					(offset 0 10.999978)
					(clearance -1.995678)
				)
			)
		)
	)
	(footprint ""
		(layer "F.Cu")
		(at 292.757098 -34.396172 90)
		(property "Reference" "PR32"
			(at 0 0 90)
			(layer "F.SilkS")
			(hide yes)
			(effects
				(font
					(size 1.27 1.27)
				)
			)
		)
		(property "Value" ""
			(at 0 0 90)
			(layer "F.Fab")
			(effects
				(font
					(size 1.27 1.27)
				)
			)
		)
		(duplicate_pad_numbers_are_jumpers no)
		(fp_line
			(start 1.651 -0.8382)
			(end 1.651 0.8382)
			(stroke
				(width 0.1524)
				(type default)
			)
			(layer "F.SilkS")
		)
		(fp_line
			(start -1.651 -0.8382)
			(end 1.651 -0.8382)
			(stroke
				(width 0.1524)
				(type default)
			)
			(layer "F.SilkS")
		)
		(fp_line
			(start 1.651 0.8382)
			(end -1.651 0.8382)
			(stroke
				(width 0.1524)
				(type default)
			)
			(layer "F.SilkS")
		)
		(fp_line
			(start -1.651 0.8382)
			(end -1.651 -0.8382)
			(stroke
				(width 0.1524)
				(type default)
			)
			(layer "F.SilkS")
		)
		(fp_line
			(start 1.560576 -0.7366)
			(end 1.524 -0.7366)
			(stroke
				(width 0.1)
				(type default)
			)
			(layer "F.Fab")
		)
		(fp_line
			(start 1.524 -0.7366)
			(end -1.524 -0.7366)
			(stroke
				(width 0.1)
				(type default)
			)
			(layer "F.Fab")
		)
		(fp_line
			(start -1.524 -0.7366)
			(end -1.559814 -0.7366)
			(stroke
				(width 0.1)
				(type default)
			)
			(layer "F.Fab")
		)
		(fp_line
			(start -1.559814 -0.7366)
			(end -1.559814 0.7366)
			(stroke
				(width 0.1)
				(type default)
			)
			(layer "F.Fab")
		)
		(fp_line
			(start 1.560576 0.7366)
			(end 1.560576 -0.7366)
			(stroke
				(width 0.1)
				(type default)
			)
			(layer "F.Fab")
		)
		(fp_line
			(start 1.524 0.7366)
			(end 1.560576 0.7366)
			(stroke
				(width 0.1)
				(type default)
			)
			(layer "F.Fab")
		)
		(fp_line
			(start -1.524 0.7366)
			(end 1.524 0.7366)
			(stroke
				(width 0.1)
				(type default)
			)
			(layer "F.Fab")
		)
		(fp_line
			(start -1.559814 0.7366)
			(end -1.524 0.7366)
			(stroke
				(width 0.1)
				(type default)
			)
			(layer "F.Fab")
		)
		(pad "1" smd rect
			(at -0.94996 0 270)
			(size 1.1176 1.3716)
			(layers "F.Cu" "F.Mask" "F.Paste")
			(net "P52V_HS1_DV_DT_R")
		)
		(pad "2" smd rect
			(at 0.94996 0 270)
			(size 1.1176 1.3716)
			(layers "F.Cu" "F.Mask" "F.Paste")
			(net "P52V_HS1_DV_DT")
		)
	)
	(footprint ""
		(layer "F.Cu")
		(at 40.781478 -63.28156)
		(property "Reference" "R5896"
			(at 0 0 0)
			(layer "F.SilkS")
			(hide yes)
			(effects
				(font
					(size 1.27 1.27)
				)
			)
		)
		(property "Value" ""
			(at 0 0 0)
			(layer "F.Fab")
			(effects
				(font
					(size 1.27 1.27)
				)
			)
		)
		(duplicate_pad_numbers_are_jumpers no)
		(fp_line
			(start -0.7874 -0.4064)
			(end 0.7874 -0.4064)
			(stroke
				(width 0.1524)
				(type default)
			)
			(layer "F.SilkS")
		)
		(fp_line
			(start -0.7874 0.4064)
			(end -0.7874 -0.4064)
			(stroke
				(width 0.1524)
				(type default)
			)
			(layer "F.SilkS")
		)
		(fp_line
			(start 0.7874 -0.4064)
			(end 0.7874 0.4064)
			(stroke
				(width 0.1524)
				(type default)
			)
			(layer "F.SilkS")
		)
		(fp_line
			(start 0.7874 0.4064)
			(end -0.7874 0.4064)
			(stroke
				(width 0.1524)
				(type default)
			)
			(layer "F.SilkS")
		)
		(fp_line
			(start -0.67945 -0.305054)
			(end -0.12065 -0.305054)
			(stroke
				(width 0.1)
				(type default)
			)
			(layer "F.Fab")
		)
		(fp_line
			(start -0.67945 0.3048)
			(end -0.67945 -0.305054)
			(stroke
				(width 0.1)
				(type default)
			)
			(layer "F.Fab")
		)
		(fp_line
			(start -0.12065 -0.305054)
			(end -0.12065 -0.2794)
			(stroke
				(width 0.1)
				(type default)
			)
			(layer "F.Fab")
		)
		(fp_line
			(start -0.12065 -0.2794)
			(end 0.12065 -0.2794)
			(stroke
				(width 0.1)
				(type default)
			)
			(layer "F.Fab")
		)
		(fp_line
			(start -0.12065 0.2794)
			(end -0.12065 0.3048)
			(stroke
				(width 0.1)
				(type default)
			)
			(layer "F.Fab")
		)
		(fp_line
			(start -0.12065 0.3048)
			(end -0.67945 0.3048)
			(stroke
				(width 0.1)
				(type default)
			)
			(layer "F.Fab")
		)
		(fp_line
			(start 0.120396 0.2794)
			(end -0.12065 0.2794)
			(stroke
				(width 0.1)
				(type default)
			)
			(layer "F.Fab")
		)
		(fp_line
			(start 0.120396 0.3048)
			(end 0.120396 0.2794)
			(stroke
				(width 0.1)
				(type default)
			)
			(layer "F.Fab")
		)
		(fp_line
			(start 0.12065 -0.3048)
			(end 0.67945 -0.3048)
			(stroke
				(width 0.1)
				(type default)
			)
			(layer "F.Fab")
		)
		(fp_line
			(start 0.12065 -0.2794)
			(end 0.12065 -0.3048)
			(stroke
				(width 0.1)
				(type default)
			)
			(layer "F.Fab")
		)
		(fp_line
			(start 0.67945 -0.3048)
			(end 0.67945 0.3048)
			(stroke
				(width 0.1)
				(type default)
			)
			(layer "F.Fab")
		)
		(fp_line
			(start 0.67945 0.3048)
			(end 0.120396 0.3048)
			(stroke
				(width 0.1)
				(type default)
			)
			(layer "F.Fab")
		)
		(pad "1" smd rect
			(at -0.40005 0 180)
			(size 0.4572 0.508)
			(layers "F.Cu" "F.Mask" "F.Paste")
			(net "P12V_HPDB")
		)
		(pad "2" smd rect
			(at 0.40005 0 180)
			(size 0.4572 0.508)
			(layers "F.Cu" "F.Mask" "F.Paste")
			(net "P12V_HPDB_0_FB")
		)
	)
	(footprint ""
		(layer "F.Cu")
		(at 163.576 -8.382)
		(property "Reference" "R82"
			(at 0 0 0)
			(layer "F.SilkS")
			(hide yes)
			(effects
				(font
					(size 1.27 1.27)
				)
			)
		)
		(property "Value" ""
			(at 0 0 0)
			(layer "F.Fab")
			(effects
				(font
					(size 1.27 1.27)
				)
			)
		)
		(duplicate_pad_numbers_are_jumpers no)
		(fp_line
			(start -0.7874 -0.4064)
			(end 0.7874 -0.4064)
			(stroke
				(width 0.1524)
				(type default)
			)
			(layer "F.SilkS")
		)
		(fp_line
			(start -0.7874 0.4064)
			(end -0.7874 -0.4064)
			(stroke
				(width 0.1524)
				(type default)
			)
			(layer "F.SilkS")
		)
		(fp_line
			(start 0.7874 -0.4064)
			(end 0.7874 0.4064)
			(stroke
				(width 0.1524)
				(type default)
			)
			(layer "F.SilkS")
		)
		(fp_line
			(start 0.7874 0.4064)
			(end -0.7874 0.4064)
			(stroke
				(width 0.1524)
				(type default)
			)
			(layer "F.SilkS")
		)
		(fp_line
			(start -0.67945 -0.305054)
			(end -0.12065 -0.305054)
			(stroke
				(width 0.1)
				(type default)
			)
			(layer "F.Fab")
		)
		(fp_line
			(start -0.67945 0.3048)
			(end -0.67945 -0.305054)
			(stroke
				(width 0.1)
				(type default)
			)
			(layer "F.Fab")
		)
		(fp_line
			(start -0.12065 -0.305054)
			(end -0.12065 -0.2794)
			(stroke
				(width 0.1)
				(type default)
			)
			(layer "F.Fab")
		)
		(fp_line
			(start -0.12065 -0.2794)
			(end 0.12065 -0.2794)
			(stroke
				(width 0.1)
				(type default)
			)
			(layer "F.Fab")
		)
		(fp_line
			(start -0.12065 0.2794)
			(end -0.12065 0.3048)
			(stroke
				(width 0.1)
				(type default)
			)
			(layer "F.Fab")
		)
		(fp_line
			(start -0.12065 0.3048)
			(end -0.67945 0.3048)
			(stroke
				(width 0.1)
				(type default)
			)
			(layer "F.Fab")
		)
		(fp_line
			(start 0.120396 0.2794)
			(end -0.12065 0.2794)
			(stroke
				(width 0.1)
				(type default)
			)
			(layer "F.Fab")
		)
		(fp_line
			(start 0.120396 0.3048)
			(end 0.120396 0.2794)
			(stroke
				(width 0.1)
				(type default)
			)
			(layer "F.Fab")
		)
		(fp_line
			(start 0.12065 -0.3048)
			(end 0.67945 -0.3048)
			(stroke
				(width 0.1)
				(type default)
			)
			(layer "F.Fab")
		)
		(fp_line
			(start 0.12065 -0.2794)
			(end 0.12065 -0.3048)
			(stroke
				(width 0.1)
				(type default)
			)
			(layer "F.Fab")
		)
		(fp_line
			(start 0.67945 -0.3048)
			(end 0.67945 0.3048)
			(stroke
				(width 0.1)
				(type default)
			)
			(layer "F.Fab")
		)
		(fp_line
			(start 0.67945 0.3048)
			(end 0.120396 0.3048)
			(stroke
				(width 0.1)
				(type default)
			)
			(layer "F.Fab")
		)
		(pad "1" smd rect
			(at -0.40005 0 180)
			(size 0.4572 0.508)
			(layers "F.Cu" "F.Mask" "F.Paste")
			(net "P12V_BRICK")
		)
		(pad "2" smd rect
			(at 0.40005 0 180)
			(size 0.4572 0.508)
			(layers "F.Cu" "F.Mask" "F.Paste")
			(net "P12V_BRICK0_PWRGD")
		)
	)
	(footprint ""
		(layer "F.Cu")
		(at 180.34 -12.192 -90)
		(property "Reference" "PC103"
			(at 0 0 270)
			(layer "F.SilkS")
			(hide yes)
			(effects
				(font
					(size 1.27 1.27)
				)
			)
		)
		(property "Value" ""
			(at 0 0 270)
			(layer "F.Fab")
			(effects
				(font
					(size 1.27 1.27)
				)
			)
		)
		(duplicate_pad_numbers_are_jumpers no)
		(fp_line
			(start -0.7874 0.4064)
			(end -0.7874 -0.4064)
			(stroke
				(width 0.1524)
				(type default)
			)
			(layer "F.SilkS")
		)
		(fp_line
			(start 0.7874 0.4064)
			(end -0.7874 0.4064)
			(stroke
				(width 0.1524)
				(type default)
			)
			(layer "F.SilkS")
		)
		(fp_line
			(start -0.7874 -0.4064)
			(end 0.7874 -0.4064)
			(stroke
				(width 0.1524)
				(type default)
			)
			(layer "F.SilkS")
		)
		(fp_line
			(start 0.7874 -0.4064)
			(end 0.7874 0.4064)
			(stroke
				(width 0.1524)
				(type default)
			)
			(layer "F.SilkS")
		)
		(fp_line
			(start -0.67945 0.3048)
			(end -0.67945 -0.305054)
			(stroke
				(width 0.1)
				(type default)
			)
			(layer "F.Fab")
		)
		(fp_line
			(start -0.12065 0.3048)
			(end -0.67945 0.3048)
			(stroke
				(width 0.1)
				(type default)
			)
			(layer "F.Fab")
		)
		(fp_line
			(start 0.120396 0.3048)
			(end 0.120396 0.2794)
			(stroke
				(width 0.1)
				(type default)
			)
			(layer "F.Fab")
		)
		(fp_line
			(start 0.67945 0.3048)
			(end 0.120396 0.3048)
			(stroke
				(width 0.1)
				(type default)
			)
			(layer "F.Fab")
		)
		(fp_line
			(start -0.12065 0.2794)
			(end -0.12065 0.3048)
			(stroke
				(width 0.1)
				(type default)
			)
			(layer "F.Fab")
		)
		(fp_line
			(start 0.120396 0.2794)
			(end -0.12065 0.2794)
			(stroke
				(width 0.1)
				(type default)
			)
			(layer "F.Fab")
		)
		(fp_line
			(start -0.12065 -0.2794)
			(end 0.12065 -0.2794)
			(stroke
				(width 0.1)
				(type default)
			)
			(layer "F.Fab")
		)
		(fp_line
			(start 0.12065 -0.2794)
			(end 0.12065 -0.3048)
			(stroke
				(width 0.1)
				(type default)
			)
			(layer "F.Fab")
		)
		(fp_line
			(start 0.12065 -0.3048)
			(end 0.67945 -0.3048)
			(stroke
				(width 0.1)
				(type default)
			)
			(layer "F.Fab")
		)
		(fp_line
			(start 0.67945 -0.3048)
			(end 0.67945 0.3048)
			(stroke
				(width 0.1)
				(type default)
			)
			(layer "F.Fab")
		)
		(fp_line
			(start -0.67945 -0.305054)
			(end -0.12065 -0.305054)
			(stroke
				(width 0.1)
				(type default)
			)
			(layer "F.Fab")
		)
		(fp_line
			(start -0.12065 -0.305054)
			(end -0.12065 -0.2794)
			(stroke
				(width 0.1)
				(type default)
			)
			(layer "F.Fab")
		)
		(pad "1" smd circle
			(at -0.40005 0 270)
			(size 0 0)
			(layers "F.Cu" "F.Mask" "F.Paste")
			(net "SW_P3V3_AUX_PH")
		)
		(pad "2" smd circle
			(at 0.40005 0 270)
			(size 0 0)
			(layers "F.Cu" "F.Mask" "F.Paste")
			(net "SW_P3V3_AUX_BT_R")
		)
	)
	(footprint ""
		(layer "F.Cu")
		(at 40.781478 -61.24956)
		(property "Reference" "R5899"
			(at 0 0 0)
			(layer "F.SilkS")
			(hide yes)
			(effects
				(font
					(size 1.27 1.27)
				)
			)
		)
		(property "Value" ""
			(at 0 0 0)
			(layer "F.Fab")
			(effects
				(font
					(size 1.27 1.27)
				)
			)
		)
		(duplicate_pad_numbers_are_jumpers no)
		(fp_line
			(start -0.7874 -0.4064)
			(end 0.7874 -0.4064)
			(stroke
				(width 0.1524)
				(type default)
			)
			(layer "F.SilkS")
		)
		(fp_line
			(start -0.7874 0.4064)
			(end -0.7874 -0.4064)
			(stroke
				(width 0.1524)
				(type default)
			)
			(layer "F.SilkS")
		)
		(fp_line
			(start 0.7874 -0.4064)
			(end 0.7874 0.4064)
			(stroke
				(width 0.1524)
				(type default)
			)
			(layer "F.SilkS")
		)
		(fp_line
			(start 0.7874 0.4064)
			(end -0.7874 0.4064)
			(stroke
				(width 0.1524)
				(type default)
			)
			(layer "F.SilkS")
		)
		(fp_line
			(start -0.67945 -0.305054)
			(end -0.12065 -0.305054)
			(stroke
				(width 0.1)
				(type default)
			)
			(layer "F.Fab")
		)
		(fp_line
			(start -0.67945 0.3048)
			(end -0.67945 -0.305054)
			(stroke
				(width 0.1)
				(type default)
			)
			(layer "F.Fab")
		)
		(fp_line
			(start -0.12065 -0.305054)
			(end -0.12065 -0.2794)
			(stroke
				(width 0.1)
				(type default)
			)
			(layer "F.Fab")
		)
		(fp_line
			(start -0.12065 -0.2794)
			(end 0.12065 -0.2794)
			(stroke
				(width 0.1)
				(type default)
			)
			(layer "F.Fab")
		)
		(fp_line
			(start -0.12065 0.2794)
			(end -0.12065 0.3048)
			(stroke
				(width 0.1)
				(type default)
			)
			(layer "F.Fab")
		)
		(fp_line
			(start -0.12065 0.3048)
			(end -0.67945 0.3048)
			(stroke
				(width 0.1)
				(type default)
			)
			(layer "F.Fab")
		)
		(fp_line
			(start 0.120396 0.2794)
			(end -0.12065 0.2794)
			(stroke
				(width 0.1)
				(type default)
			)
			(layer "F.Fab")
		)
		(fp_line
			(start 0.120396 0.3048)
			(end 0.120396 0.2794)
			(stroke
				(width 0.1)
				(type default)
			)
			(layer "F.Fab")
		)
		(fp_line
			(start 0.12065 -0.3048)
			(end 0.67945 -0.3048)
			(stroke
				(width 0.1)
				(type default)
			)
			(layer "F.Fab")
		)
		(fp_line
			(start 0.12065 -0.2794)
			(end 0.12065 -0.3048)
			(stroke
				(width 0.1)
				(type default)
			)
			(layer "F.Fab")
		)
		(fp_line
			(start 0.67945 -0.3048)
			(end 0.67945 0.3048)
			(stroke
				(width 0.1)
				(type default)
			)
			(layer "F.Fab")
		)
		(fp_line
			(start 0.67945 0.3048)
			(end 0.120396 0.3048)
			(stroke
				(width 0.1)
				(type default)
			)
			(layer "F.Fab")
		)
		(pad "1" smd circle
			(at -0.40005 0)
			(size 0 0)
			(layers "F.Cu" "F.Mask" "F.Paste")
			(net "GND")
		)
		(pad "2" smd circle
			(at 0.40005 0)
			(size 0 0)
			(layers "F.Cu" "F.Mask" "F.Paste")
			(net "P12V_HPDB_0_FB")
		)
	)
	(footprint ""
		(layer "F.Cu")
		(at 276.802088 -34.49447 90)
		(property "Reference" "R5932"
			(at 0 0 90)
			(layer "F.SilkS")
			(hide yes)
			(effects
				(font
					(size 1.27 1.27)
				)
			)
		)
		(property "Value" ""
			(at 0 0 90)
			(layer "F.Fab")
			(effects
				(font
					(size 1.27 1.27)
				)
			)
		)
		(duplicate_pad_numbers_are_jumpers no)
		(fp_line
			(start 1.651 -0.8382)
			(end 1.651 0.8382)
			(stroke
				(width 0.1524)
				(type default)
			)
			(layer "F.SilkS")
		)
		(fp_line
			(start -1.651 -0.8382)
			(end 1.651 -0.8382)
			(stroke
				(width 0.1524)
				(type default)
			)
			(layer "F.SilkS")
		)
		(fp_line
			(start 1.651 0.8382)
			(end -1.651 0.8382)
			(stroke
				(width 0.1524)
				(type default)
			)
			(layer "F.SilkS")
		)
		(fp_line
			(start -1.651 0.8382)
			(end -1.651 -0.8382)
			(stroke
				(width 0.1524)
				(type default)
			)
			(layer "F.SilkS")
		)
		(fp_line
			(start 1.560576 -0.7366)
			(end 1.524 -0.7366)
			(stroke
				(width 0.1)
				(type default)
			)
			(layer "F.Fab")
		)
		(fp_line
			(start 1.524 -0.7366)
			(end -1.524 -0.7366)
			(stroke
				(width 0.1)
				(type default)
			)
			(layer "F.Fab")
		)
		(fp_line
			(start -1.524 -0.7366)
			(end -1.559814 -0.7366)
			(stroke
				(width 0.1)
				(type default)
			)
			(layer "F.Fab")
		)
		(fp_line
			(start -1.559814 -0.7366)
			(end -1.559814 0.7366)
			(stroke
				(width 0.1)
				(type default)
			)
			(layer "F.Fab")
		)
		(fp_line
			(start 1.560576 0.7366)
			(end 1.560576 -0.7366)
			(stroke
				(width 0.1)
				(type default)
			)
			(layer "F.Fab")
		)
		(fp_line
			(start 1.524 0.7366)
			(end 1.560576 0.7366)
			(stroke
				(width 0.1)
				(type default)
			)
			(layer "F.Fab")
		)
		(fp_line
			(start -1.524 0.7366)
			(end 1.524 0.7366)
			(stroke
				(width 0.1)
				(type default)
			)
			(layer "F.Fab")
		)
		(fp_line
			(start -1.559814 0.7366)
			(end -1.524 0.7366)
			(stroke
				(width 0.1)
				(type default)
			)
			(layer "F.Fab")
		)
		(pad "1" smd rect
			(at -0.94996 0 270)
			(size 1.1176 1.3716)
			(layers "F.Cu" "F.Mask" "F.Paste")
			(net "P52V_1_R")
		)
		(pad "2" smd rect
			(at 0.94996 0 270)
			(size 1.1176 1.3716)
			(layers "F.Cu" "F.Mask" "F.Paste")
			(net "P52V_HS1_EN_BUF_DELAY")
		)
	)
	(footprint ""
		(layer "F.Cu")
		(at 134.239 -136.906 90)
		(property "Reference" "PC16"
			(at 6.19633 1.143 0)
			(unlocked yes)
			(layer "F.SilkS")
			(effects
				(font
					(size 0.7874 0.5842)
					(thickness 0.1524)
				)
				(justify left)
			)
		)
		(property "Value" ""
			(at 0 0 90)
			(layer "F.Fab")
			(effects
				(font
					(size 1.27 1.27)
				)
			)
		)
		(duplicate_pad_numbers_are_jumpers no)
		(fp_line
			(start 5.2578 2.499868)
			(end -5.2578 2.499868)
			(stroke
				(width 0.1524)
				(type default)
			)
			(layer "F.SilkS")
		)
		(fp_circle
			(center 0 2.500122)
			(end 0 7.758176)
			(stroke
				(width 0.1524)
				(type default)
			)
			(fill no)
			(layer "F.SilkS")
		)
		(fp_poly
			(pts
				(arc
					(start 5.2578 2.499868)
					(mid 0 7.757922)
					(end -5.2578 2.499868)
				)
			)
			(stroke
				(width 0)
				(type default)
			)
			(fill yes)
			(layer "F.SilkS")
		)
		(fp_circle
			(center 0 2.500122)
			(end 0 7.758176)
			(stroke
				(width 0.1)
				(type default)
			)
			(fill no)
			(layer "F.Fab")
		)
		(pad "1" thru_hole rect
			(at 0 0)
			(size 1.5748 1.5748)
			(drill 1.0668)
			(layers "*.Cu" "*.Mask")
			(remove_unused_layers no)
			(net "P52V_HS_FILTER")
			(clearance 0)
			(padstack
				(mode front_inner_back)
				(layer "Inner"
					(shape circle)
					(size 1.5748 1.5748)
					(clearance 0)
				)
				(layer "B.Cu"
					(shape rect)
					(size 1.5748 1.5748)
					(clearance 0)
				)
			)
		)
		(pad "2" thru_hole circle
			(at 0 4.99999)
			(size 1.5748 1.5748)
			(drill 1.0668)
			(layers "*.Cu" "*.Mask")
			(remove_unused_layers no)
			(net "GND")
			(clearance 0)
		)
	)
	(footprint ""
		(layer "F.Cu")
		(at 179.065174 -60.325)
		(property "Reference" "PR321"
			(at 0 0 0)
			(layer "F.SilkS")
			(hide yes)
			(effects
				(font
					(size 1.27 1.27)
				)
			)
		)
		(property "Value" ""
			(at 0 0 0)
			(layer "F.Fab")
			(effects
				(font
					(size 1.27 1.27)
				)
			)
		)
		(duplicate_pad_numbers_are_jumpers no)
		(fp_line
			(start -1.651 -0.8382)
			(end 1.651 -0.8382)
			(stroke
				(width 0.1524)
				(type default)
			)
			(layer "F.SilkS")
		)
		(fp_line
			(start -1.651 0.8382)
			(end -1.651 -0.8382)
			(stroke
				(width 0.1524)
				(type default)
			)
			(layer "F.SilkS")
		)
		(fp_line
			(start 1.651 -0.8382)
			(end 1.651 0.8382)
			(stroke
				(width 0.1524)
				(type default)
			)
			(layer "F.SilkS")
		)
		(fp_line
			(start 1.651 0.8382)
			(end -1.651 0.8382)
			(stroke
				(width 0.1524)
				(type default)
			)
			(layer "F.SilkS")
		)
		(fp_line
			(start -1.559814 -0.7366)
			(end -1.559814 0.7366)
			(stroke
				(width 0.1)
				(type default)
			)
			(layer "F.Fab")
		)
		(fp_line
			(start -1.559814 0.7366)
			(end -1.524 0.7366)
			(stroke
				(width 0.1)
				(type default)
			)
			(layer "F.Fab")
		)
		(fp_line
			(start -1.524 -0.7366)
			(end -1.559814 -0.7366)
			(stroke
				(width 0.1)
				(type default)
			)
			(layer "F.Fab")
		)
		(fp_line
			(start -1.524 0.7366)
			(end 1.524 0.7366)
			(stroke
				(width 0.1)
				(type default)
			)
			(layer "F.Fab")
		)
		(fp_line
			(start 1.524 -0.7366)
			(end -1.524 -0.7366)
			(stroke
				(width 0.1)
				(type default)
			)
			(layer "F.Fab")
		)
		(fp_line
			(start 1.524 0.7366)
			(end 1.560576 0.7366)
			(stroke
				(width 0.1)
				(type default)
			)
			(layer "F.Fab")
		)
		(fp_line
			(start 1.560576 -0.7366)
			(end 1.524 -0.7366)
			(stroke
				(width 0.1)
				(type default)
			)
			(layer "F.Fab")
		)
		(fp_line
			(start 1.560576 0.7366)
			(end 1.560576 -0.7366)
			(stroke
				(width 0.1)
				(type default)
			)
			(layer "F.Fab")
		)
		(pad "1" smd rect
			(at -0.94996 0 180)
			(size 1.1176 1.3716)
			(layers "F.Cu" "F.Mask" "F.Paste")
			(net "P12V_BRICK")
		)
		(pad "2" smd rect
			(at 0.94996 0 180)
			(size 1.1176 1.3716)
			(layers "F.Cu" "F.Mask" "F.Paste")
			(net "GND")
		)
	)
	(footprint ""
		(layer "F.Cu")
		(at 191.643 -10.922)
		(property "Reference" "PC106"
			(at 0 0 0)
			(layer "F.SilkS")
			(hide yes)
			(effects
				(font
					(size 1.27 1.27)
				)
			)
		)
		(property "Value" ""
			(at 0 0 0)
			(layer "F.Fab")
			(effects
				(font
					(size 1.27 1.27)
				)
			)
		)
		(duplicate_pad_numbers_are_jumpers no)
		(fp_line
			(start -1.524 -0.762)
			(end 1.524 -0.762)
			(stroke
				(width 0.1524)
				(type default)
			)
			(layer "F.SilkS")
		)
		(fp_line
			(start -1.524 0.762)
			(end -1.524 -0.762)
			(stroke
				(width 0.1524)
				(type default)
			)
			(layer "F.SilkS")
		)
		(fp_line
			(start 1.524 -0.762)
			(end 1.524 0.762)
			(stroke
				(width 0.1524)
				(type default)
			)
			(layer "F.SilkS")
		)
		(fp_line
			(start 1.524 0.762)
			(end -1.524 0.762)
			(stroke
				(width 0.1524)
				(type default)
			)
			(layer "F.SilkS")
		)
		(fp_line
			(start -1.1049 -0.724916)
			(end -1.1049 0.724916)
			(stroke
				(width 0.1)
				(type default)
			)
			(layer "F.Fab")
		)
		(fp_line
			(start -1.1049 0.724916)
			(end 1.1049 0.724916)
			(stroke
				(width 0.1)
				(type default)
			)
			(layer "F.Fab")
		)
		(fp_line
			(start 1.1049 -0.724916)
			(end -1.1049 -0.724916)
			(stroke
				(width 0.1)
				(type default)
			)
			(layer "F.Fab")
		)
		(fp_line
			(start 1.1049 0.724916)
			(end 1.1049 -0.724916)
			(stroke
				(width 0.1)
				(type default)
			)
			(layer "F.Fab")
		)
		(pad "1" smd rect
			(at -0.889 0 180)
			(size 1.016 1.27)
			(layers "F.Cu" "F.Mask" "F.Paste")
			(net "P3V3_AUX")
		)
		(pad "2" smd rect
			(at 0.889 0 180)
			(size 1.016 1.27)
			(layers "F.Cu" "F.Mask" "F.Paste")
			(net "GND")
		)
	)
	(footprint ""
		(layer "F.Cu")
		(at 189.098174 -130.175)
		(property "Reference" "PC116"
			(at 0 0 0)
			(layer "F.SilkS")
			(hide yes)
			(effects
				(font
					(size 1.27 1.27)
				)
			)
		)
		(property "Value" ""
			(at 0 0 0)
			(layer "F.Fab")
			(effects
				(font
					(size 1.27 1.27)
				)
			)
		)
		(duplicate_pad_numbers_are_jumpers no)
		(fp_line
			(start -2.2098 -0.9398)
			(end 2.2098 -0.9398)
			(stroke
				(width 0.1524)
				(type default)
			)
			(layer "F.SilkS")
		)
		(fp_line
			(start -2.2098 0.9398)
			(end -2.2098 -0.9398)
			(stroke
				(width 0.1524)
				(type default)
			)
			(layer "F.SilkS")
		)
		(fp_line
			(start 2.2098 -0.9398)
			(end 2.2098 0.9398)
			(stroke
				(width 0.1524)
				(type default)
			)
			(layer "F.SilkS")
		)
		(fp_line
			(start 2.2098 0.9398)
			(end -2.2098 0.9398)
			(stroke
				(width 0.1524)
				(type default)
			)
			(layer "F.SilkS")
		)
		(fp_line
			(start -1.700022 -0.899922)
			(end 1.700022 -0.899922)
			(stroke
				(width 0.1)
				(type default)
			)
			(layer "F.Fab")
		)
		(fp_line
			(start -1.700022 0.899922)
			(end -1.700022 -0.899922)
			(stroke
				(width 0.1)
				(type default)
			)
			(layer "F.Fab")
		)
		(fp_line
			(start 1.700022 -0.899922)
			(end 1.700022 0.899922)
			(stroke
				(width 0.1)
				(type default)
			)
			(layer "F.Fab")
		)
		(fp_line
			(start 1.700022 0.899922)
			(end -1.700022 0.899922)
			(stroke
				(width 0.1)
				(type default)
			)
			(layer "F.Fab")
		)
		(pad "1" smd rect
			(at -1.4732 0 180)
			(size 1.1684 1.5748)
			(layers "F.Cu" "F.Mask" "F.Paste")
			(net "P52V_HS_FILTER")
		)
		(pad "2" smd rect
			(at 1.4732 0 180)
			(size 1.1684 1.5748)
			(layers "F.Cu" "F.Mask" "F.Paste")
			(net "GND")
		)
	)
	(footprint ""
		(layer "F.Cu")
		(at 301.602394 -85.2805 180)
		(property "Reference" "PR6964"
			(at 0 0 180)
			(layer "F.SilkS")
			(hide yes)
			(effects
				(font
					(size 1.27 1.27)
				)
			)
		)
		(property "Value" ""
			(at 0 0 180)
			(layer "F.Fab")
			(effects
				(font
					(size 1.27 1.27)
				)
			)
		)
		(duplicate_pad_numbers_are_jumpers no)
		(fp_line
			(start 1.2954 0.5842)
			(end -1.2954 0.5842)
			(stroke
				(width 0.1524)
				(type default)
			)
			(layer "F.SilkS")
		)
		(fp_line
			(start 1.2954 -0.5842)
			(end 1.2954 0.5842)
			(stroke
				(width 0.1524)
				(type default)
			)
			(layer "F.SilkS")
		)
		(fp_line
			(start -1.2954 0.5842)
			(end -1.2954 -0.5842)
			(stroke
				(width 0.1524)
				(type default)
			)
			(layer "F.SilkS")
		)
		(fp_line
			(start -1.2954 -0.5842)
			(end 1.2954 -0.5842)
			(stroke
				(width 0.1524)
				(type default)
			)
			(layer "F.SilkS")
		)
		(fp_line
			(start 1.1938 0.4064)
			(end 0.8636 0.4064)
			(stroke
				(width 0.1)
				(type default)
			)
			(layer "F.Fab")
		)
		(fp_line
			(start 1.1938 -0.406654)
			(end 1.1938 0.4064)
			(stroke
				(width 0.1)
				(type default)
			)
			(layer "F.Fab")
		)
		(fp_line
			(start 0.8636 0.4572)
			(end -0.8636 0.4572)
			(stroke
				(width 0.1)
				(type default)
			)
			(layer "F.Fab")
		)
		(fp_line
			(start 0.8636 0.4064)
			(end 0.8636 0.4572)
			(stroke
				(width 0.1)
				(type default)
			)
			(layer "F.Fab")
		)
		(fp_line
			(start 0.8636 -0.406654)
			(end 1.1938 -0.406654)
			(stroke
				(width 0.1)
				(type default)
			)
			(layer "F.Fab")
		)
		(fp_line
			(start 0.8636 -0.4572)
			(end 0.8636 -0.406654)
			(stroke
				(width 0.1)
				(type default)
			)
			(layer "F.Fab")
		)
		(fp_line
			(start -0.8636 0.4572)
			(end -0.8636 0.4318)
			(stroke
				(width 0.1)
				(type default)
			)
			(layer "F.Fab")
		)
		(fp_line
			(start -0.8636 0.4318)
			(end -0.8636 0.4064)
			(stroke
				(width 0.1)
				(type default)
			)
			(layer "F.Fab")
		)
		(fp_line
			(start -0.8636 0.4064)
			(end -1.1938 0.4064)
			(stroke
				(width 0.1)
				(type default)
			)
			(layer "F.Fab")
		)
		(fp_line
			(start -0.8636 -0.406654)
			(end -0.8636 -0.4572)
			(stroke
				(width 0.1)
				(type default)
			)
			(layer "F.Fab")
		)
		(fp_line
			(start -0.8636 -0.4572)
			(end 0.8636 -0.4572)
			(stroke
				(width 0.1)
				(type default)
			)
			(layer "F.Fab")
		)
		(fp_line
			(start -1.1938 0.4064)
			(end -1.1938 -0.406654)
			(stroke
				(width 0.1)
				(type default)
			)
			(layer "F.Fab")
		)
		(fp_line
			(start -1.1938 -0.406654)
			(end -0.8636 -0.406654)
			(stroke
				(width 0.1)
				(type default)
			)
			(layer "F.Fab")
		)
		(pad "1" smd rect
			(at -0.7366 0 90)
			(size 0.7112 0.8128)
			(layers "F.Cu" "F.Mask" "F.Paste")
			(net "P52V_HS1_SENSE_P_R2")
		)
		(pad "2" smd rect
			(at 0.7366 0 90)
			(size 0.7112 0.8128)
			(layers "F.Cu" "F.Mask" "F.Paste")
			(net "P52V_HS_4287_ADC_P")
		)
	)
	(footprint ""
		(layer "F.Cu")
		(at 191.643 -13.081)
		(property "Reference" "PC107"
			(at 0 0 0)
			(layer "F.SilkS")
			(hide yes)
			(effects
				(font
					(size 1.27 1.27)
				)
			)
		)
		(property "Value" ""
			(at 0 0 0)
			(layer "F.Fab")
			(effects
				(font
					(size 1.27 1.27)
				)
			)
		)
		(duplicate_pad_numbers_are_jumpers no)
		(fp_line
			(start -1.524 -0.762)
			(end 1.524 -0.762)
			(stroke
				(width 0.1524)
				(type default)
			)
			(layer "F.SilkS")
		)
		(fp_line
			(start -1.524 0.762)
			(end -1.524 -0.762)
			(stroke
				(width 0.1524)
				(type default)
			)
			(layer "F.SilkS")
		)
		(fp_line
			(start 1.524 -0.762)
			(end 1.524 0.762)
			(stroke
				(width 0.1524)
				(type default)
			)
			(layer "F.SilkS")
		)
		(fp_line
			(start 1.524 0.762)
			(end -1.524 0.762)
			(stroke
				(width 0.1524)
				(type default)
			)
			(layer "F.SilkS")
		)
		(fp_line
			(start -1.1049 -0.724916)
			(end -1.1049 0.724916)
			(stroke
				(width 0.1)
				(type default)
			)
			(layer "F.Fab")
		)
		(fp_line
			(start -1.1049 0.724916)
			(end 1.1049 0.724916)
			(stroke
				(width 0.1)
				(type default)
			)
			(layer "F.Fab")
		)
		(fp_line
			(start 1.1049 -0.724916)
			(end -1.1049 -0.724916)
			(stroke
				(width 0.1)
				(type default)
			)
			(layer "F.Fab")
		)
		(fp_line
			(start 1.1049 0.724916)
			(end 1.1049 -0.724916)
			(stroke
				(width 0.1)
				(type default)
			)
			(layer "F.Fab")
		)
		(pad "1" smd rect
			(at -0.889 0 180)
			(size 1.016 1.27)
			(layers "F.Cu" "F.Mask" "F.Paste")
			(net "P3V3_AUX")
		)
		(pad "2" smd rect
			(at 0.889 0 180)
			(size 1.016 1.27)
			(layers "F.Cu" "F.Mask" "F.Paste")
			(net "GND")
		)
	)
	(footprint ""
		(layer "F.Cu")
		(at 174.879 -8.255 180)
		(property "Reference" "R83"
			(at 0 0 180)
			(layer "F.SilkS")
			(hide yes)
			(effects
				(font
					(size 1.27 1.27)
				)
			)
		)
		(property "Value" ""
			(at 0 0 180)
			(layer "F.Fab")
			(effects
				(font
					(size 1.27 1.27)
				)
			)
		)
		(duplicate_pad_numbers_are_jumpers no)
		(fp_line
			(start 0.7874 0.4064)
			(end -0.7874 0.4064)
			(stroke
				(width 0.1524)
				(type default)
			)
			(layer "F.SilkS")
		)
		(fp_line
			(start 0.7874 -0.4064)
			(end 0.7874 0.4064)
			(stroke
				(width 0.1524)
				(type default)
			)
			(layer "F.SilkS")
		)
		(fp_line
			(start -0.7874 0.4064)
			(end -0.7874 -0.4064)
			(stroke
				(width 0.1524)
				(type default)
			)
			(layer "F.SilkS")
		)
		(fp_line
			(start -0.7874 -0.4064)
			(end 0.7874 -0.4064)
			(stroke
				(width 0.1524)
				(type default)
			)
			(layer "F.SilkS")
		)
		(fp_line
			(start 0.67945 0.3048)
			(end 0.120396 0.3048)
			(stroke
				(width 0.1)
				(type default)
			)
			(layer "F.Fab")
		)
		(fp_line
			(start 0.67945 -0.3048)
			(end 0.67945 0.3048)
			(stroke
				(width 0.1)
				(type default)
			)
			(layer "F.Fab")
		)
		(fp_line
			(start 0.12065 -0.2794)
			(end 0.12065 -0.3048)
			(stroke
				(width 0.1)
				(type default)
			)
			(layer "F.Fab")
		)
		(fp_line
			(start 0.12065 -0.3048)
			(end 0.67945 -0.3048)
			(stroke
				(width 0.1)
				(type default)
			)
			(layer "F.Fab")
		)
		(fp_line
			(start 0.120396 0.3048)
			(end 0.120396 0.2794)
			(stroke
				(width 0.1)
				(type default)
			)
			(layer "F.Fab")
		)
		(fp_line
			(start 0.120396 0.2794)
			(end -0.12065 0.2794)
			(stroke
				(width 0.1)
				(type default)
			)
			(layer "F.Fab")
		)
		(fp_line
			(start -0.12065 0.3048)
			(end -0.67945 0.3048)
			(stroke
				(width 0.1)
				(type default)
			)
			(layer "F.Fab")
		)
		(fp_line
			(start -0.12065 0.2794)
			(end -0.12065 0.3048)
			(stroke
				(width 0.1)
				(type default)
			)
			(layer "F.Fab")
		)
		(fp_line
			(start -0.12065 -0.2794)
			(end 0.12065 -0.2794)
			(stroke
				(width 0.1)
				(type default)
			)
			(layer "F.Fab")
		)
		(fp_line
			(start -0.12065 -0.305054)
			(end -0.12065 -0.2794)
			(stroke
				(width 0.1)
				(type default)
			)
			(layer "F.Fab")
		)
		(fp_line
			(start -0.67945 0.3048)
			(end -0.67945 -0.305054)
			(stroke
				(width 0.1)
				(type default)
			)
			(layer "F.Fab")
		)
		(fp_line
			(start -0.67945 -0.305054)
			(end -0.12065 -0.305054)
			(stroke
				(width 0.1)
				(type default)
			)
			(layer "F.Fab")
		)
		(pad "1" smd circle
			(at -0.40005 0 180)
			(size 0 0)
			(layers "F.Cu" "F.Mask" "F.Paste")
			(net "P12V_BRICK0_PWRGD")
		)
		(pad "2" smd circle
			(at 0.40005 0 180)
			(size 0 0)
			(layers "F.Cu" "F.Mask" "F.Paste")
			(net "GND")
		)
	)
	(footprint ""
		(layer "F.Cu")
		(at 46.042834 -53.613304 90)
		(property "Reference" "C91"
			(at 0 0 90)
			(layer "F.SilkS")
			(hide yes)
			(effects
				(font
					(size 1.27 1.27)
				)
			)
		)
		(property "Value" ""
			(at 0 0 90)
			(layer "F.Fab")
			(effects
				(font
					(size 1.27 1.27)
				)
			)
		)
		(duplicate_pad_numbers_are_jumpers no)
		(fp_line
			(start 0.7874 -0.4064)
			(end 0.7874 0.4064)
			(stroke
				(width 0.1524)
				(type default)
			)
			(layer "F.SilkS")
		)
		(fp_line
			(start -0.7874 -0.4064)
			(end 0.7874 -0.4064)
			(stroke
				(width 0.1524)
				(type default)
			)
			(layer "F.SilkS")
		)
		(fp_line
			(start 0.7874 0.4064)
			(end -0.7874 0.4064)
			(stroke
				(width 0.1524)
				(type default)
			)
			(layer "F.SilkS")
		)
		(fp_line
			(start -0.7874 0.4064)
			(end -0.7874 -0.4064)
			(stroke
				(width 0.1524)
				(type default)
			)
			(layer "F.SilkS")
		)
		(fp_line
			(start 0.6858 -0.3048)
			(end 0.6858 0.3048)
			(stroke
				(width 0.1)
				(type default)
			)
			(layer "F.Fab")
		)
		(fp_line
			(start 0.1016 -0.3048)
			(end 0.6858 -0.3048)
			(stroke
				(width 0.1)
				(type default)
			)
			(layer "F.Fab")
		)
		(fp_line
			(start -0.1016 -0.3048)
			(end -0.1016 -0.2794)
			(stroke
				(width 0.1)
				(type default)
			)
			(layer "F.Fab")
		)
		(fp_line
			(start -0.6858 -0.3048)
			(end -0.1016 -0.3048)
			(stroke
				(width 0.1)
				(type default)
			)
			(layer "F.Fab")
		)
		(fp_line
			(start 0.1016 -0.2794)
			(end 0.1016 -0.3048)
			(stroke
				(width 0.1)
				(type default)
			)
			(layer "F.Fab")
		)
		(fp_line
			(start -0.1016 -0.2794)
			(end 0.1016 -0.2794)
			(stroke
				(width 0.1)
				(type default)
			)
			(layer "F.Fab")
		)
		(fp_line
			(start 0.1016 0.2794)
			(end -0.1016 0.2794)
			(stroke
				(width 0.1)
				(type default)
			)
			(layer "F.Fab")
		)
		(fp_line
			(start -0.1016 0.2794)
			(end -0.1016 0.3048)
			(stroke
				(width 0.1)
				(type default)
			)
			(layer "F.Fab")
		)
		(fp_line
			(start 0.6858 0.3048)
			(end 0.1016 0.3048)
			(stroke
				(width 0.1)
				(type default)
			)
			(layer "F.Fab")
		)
		(fp_line
			(start 0.1016 0.3048)
			(end 0.1016 0.2794)
			(stroke
				(width 0.1)
				(type default)
			)
			(layer "F.Fab")
		)
		(fp_line
			(start -0.1016 0.3048)
			(end -0.6858 0.3048)
			(stroke
				(width 0.1)
				(type default)
			)
			(layer "F.Fab")
		)
		(fp_line
			(start -0.6858 0.3048)
			(end -0.6858 -0.3048)
			(stroke
				(width 0.1)
				(type default)
			)
			(layer "F.Fab")
		)
		(pad "1" smd rect
			(at -0.40005 0 270)
			(size 0.4572 0.508)
			(layers "F.Cu" "F.Mask" "F.Paste")
			(net "P12V_BRICK")
		)
		(pad "2" smd rect
			(at 0.40005 0 270)
			(size 0.4572 0.508)
			(layers "F.Cu" "F.Mask" "F.Paste")
			(net "GND")
		)
	)
	(footprint ""
		(layer "F.Cu")
		(at 270.383 -129.753868 -90)
		(property "Reference" "PR8"
			(at 0 0 270)
			(layer "F.SilkS")
			(hide yes)
			(effects
				(font
					(size 1.27 1.27)
				)
			)
		)
		(property "Value" ""
			(at 0 0 270)
			(layer "F.Fab")
			(effects
				(font
					(size 1.27 1.27)
				)
			)
		)
		(duplicate_pad_numbers_are_jumpers no)
		(fp_line
			(start -1.2954 0.5842)
			(end -1.2954 -0.5842)
			(stroke
				(width 0.1524)
				(type default)
			)
			(layer "F.SilkS")
		)
		(fp_line
			(start 1.2954 0.5842)
			(end -1.2954 0.5842)
			(stroke
				(width 0.1524)
				(type default)
			)
			(layer "F.SilkS")
		)
		(fp_line
			(start -1.2954 -0.5842)
			(end 1.2954 -0.5842)
			(stroke
				(width 0.1524)
				(type default)
			)
			(layer "F.SilkS")
		)
		(fp_line
			(start 1.2954 -0.5842)
			(end 1.2954 0.5842)
			(stroke
				(width 0.1524)
				(type default)
			)
			(layer "F.SilkS")
		)
		(fp_line
			(start -0.8636 0.4572)
			(end -0.8636 0.4318)
			(stroke
				(width 0.1)
				(type default)
			)
			(layer "F.Fab")
		)
		(fp_line
			(start 0.8636 0.4572)
			(end -0.8636 0.4572)
			(stroke
				(width 0.1)
				(type default)
			)
			(layer "F.Fab")
		)
		(fp_line
			(start -0.8636 0.4318)
			(end -0.8636 0.4064)
			(stroke
				(width 0.1)
				(type default)
			)
			(layer "F.Fab")
		)
		(fp_line
			(start -1.1938 0.4064)
			(end -1.1938 -0.406654)
			(stroke
				(width 0.1)
				(type default)
			)
			(layer "F.Fab")
		)
		(fp_line
			(start -0.8636 0.4064)
			(end -1.1938 0.4064)
			(stroke
				(width 0.1)
				(type default)
			)
			(layer "F.Fab")
		)
		(fp_line
			(start 0.8636 0.4064)
			(end 0.8636 0.4572)
			(stroke
				(width 0.1)
				(type default)
			)
			(layer "F.Fab")
		)
		(fp_line
			(start 1.1938 0.4064)
			(end 0.8636 0.4064)
			(stroke
				(width 0.1)
				(type default)
			)
			(layer "F.Fab")
		)
		(fp_line
			(start -1.1938 -0.406654)
			(end -0.8636 -0.406654)
			(stroke
				(width 0.1)
				(type default)
			)
			(layer "F.Fab")
		)
		(fp_line
			(start -0.8636 -0.406654)
			(end -0.8636 -0.4572)
			(stroke
				(width 0.1)
				(type default)
			)
			(layer "F.Fab")
		)
		(fp_line
			(start 0.8636 -0.406654)
			(end 1.1938 -0.406654)
			(stroke
				(width 0.1)
				(type default)
			)
			(layer "F.Fab")
		)
		(fp_line
			(start 1.1938 -0.406654)
			(end 1.1938 0.4064)
			(stroke
				(width 0.1)
				(type default)
			)
			(layer "F.Fab")
		)
		(fp_line
			(start -0.8636 -0.4572)
			(end 0.8636 -0.4572)
			(stroke
				(width 0.1)
				(type default)
			)
			(layer "F.Fab")
		)
		(fp_line
			(start 0.8636 -0.4572)
			(end 0.8636 -0.406654)
			(stroke
				(width 0.1)
				(type default)
			)
			(layer "F.Fab")
		)
		(pad "1" smd rect
			(at -0.7366 0 180)
			(size 0.7112 0.8128)
			(layers "F.Cu" "F.Mask" "F.Paste")
			(net "P52V_HS1_GATE1_R")
		)
		(pad "2" smd rect
			(at 0.7366 0 180)
			(size 0.7112 0.8128)
			(layers "F.Cu" "F.Mask" "F.Paste")
			(net "P52V_HS1_GATE1")
		)
	)
	(footprint ""
		(layer "F.Cu")
		(at 157.226 -51.816)
		(property "Reference" "PC37"
			(at 0 0 0)
			(layer "F.SilkS")
			(hide yes)
			(effects
				(font
					(size 1.27 1.27)
				)
			)
		)
		(property "Value" ""
			(at 0 0 0)
			(layer "F.Fab")
			(effects
				(font
					(size 1.27 1.27)
				)
			)
		)
		(duplicate_pad_numbers_are_jumpers no)
		(fp_line
			(start -1.524 -0.762)
			(end 1.524 -0.762)
			(stroke
				(width 0.1524)
				(type default)
			)
			(layer "F.SilkS")
		)
		(fp_line
			(start -1.524 0.762)
			(end -1.524 -0.762)
			(stroke
				(width 0.1524)
				(type default)
			)
			(layer "F.SilkS")
		)
		(fp_line
			(start 1.524 -0.762)
			(end 1.524 0.762)
			(stroke
				(width 0.1524)
				(type default)
			)
			(layer "F.SilkS")
		)
		(fp_line
			(start 1.524 0.762)
			(end -1.524 0.762)
			(stroke
				(width 0.1524)
				(type default)
			)
			(layer "F.SilkS")
		)
		(fp_line
			(start -1.1049 -0.724916)
			(end -1.1049 0.724916)
			(stroke
				(width 0.1)
				(type default)
			)
			(layer "F.Fab")
		)
		(fp_line
			(start -1.1049 0.724916)
			(end 1.1049 0.724916)
			(stroke
				(width 0.1)
				(type default)
			)
			(layer "F.Fab")
		)
		(fp_line
			(start 1.1049 -0.724916)
			(end -1.1049 -0.724916)
			(stroke
				(width 0.1)
				(type default)
			)
			(layer "F.Fab")
		)
		(fp_line
			(start 1.1049 0.724916)
			(end 1.1049 -0.724916)
			(stroke
				(width 0.1)
				(type default)
			)
			(layer "F.Fab")
		)
		(pad "1" smd rect
			(at -0.889 0 180)
			(size 1.016 1.27)
			(layers "F.Cu" "F.Mask" "F.Paste")
			(net "P12V_BRICK")
		)
		(pad "2" smd rect
			(at 0.889 0 180)
			(size 1.016 1.27)
			(layers "F.Cu" "F.Mask" "F.Paste")
			(net "GND")
		)
	)
	(footprint ""
		(layer "F.Cu")
		(at 45.67936 -56.09082)
		(property "Reference" "C94"
			(at 0 0 0)
			(layer "F.SilkS")
			(hide yes)
			(effects
				(font
					(size 1.27 1.27)
				)
			)
		)
		(property "Value" ""
			(at 0 0 0)
			(layer "F.Fab")
			(effects
				(font
					(size 1.27 1.27)
				)
			)
		)
		(duplicate_pad_numbers_are_jumpers no)
		(fp_line
			(start -0.7874 -0.4064)
			(end 0.7874 -0.4064)
			(stroke
				(width 0.1524)
				(type default)
			)
			(layer "F.SilkS")
		)
		(fp_line
			(start -0.7874 0.4064)
			(end -0.7874 -0.4064)
			(stroke
				(width 0.1524)
				(type default)
			)
			(layer "F.SilkS")
		)
		(fp_line
			(start 0.7874 -0.4064)
			(end 0.7874 0.4064)
			(stroke
				(width 0.1524)
				(type default)
			)
			(layer "F.SilkS")
		)
		(fp_line
			(start 0.7874 0.4064)
			(end -0.7874 0.4064)
			(stroke
				(width 0.1524)
				(type default)
			)
			(layer "F.SilkS")
		)
		(fp_line
			(start -0.67945 -0.305054)
			(end -0.12065 -0.305054)
			(stroke
				(width 0.1)
				(type default)
			)
			(layer "F.Fab")
		)
		(fp_line
			(start -0.67945 0.3048)
			(end -0.67945 -0.305054)
			(stroke
				(width 0.1)
				(type default)
			)
			(layer "F.Fab")
		)
		(fp_line
			(start -0.12065 -0.305054)
			(end -0.12065 -0.2794)
			(stroke
				(width 0.1)
				(type default)
			)
			(layer "F.Fab")
		)
		(fp_line
			(start -0.12065 -0.2794)
			(end 0.12065 -0.2794)
			(stroke
				(width 0.1)
				(type default)
			)
			(layer "F.Fab")
		)
		(fp_line
			(start -0.12065 0.2794)
			(end -0.12065 0.3048)
			(stroke
				(width 0.1)
				(type default)
			)
			(layer "F.Fab")
		)
		(fp_line
			(start -0.12065 0.3048)
			(end -0.67945 0.3048)
			(stroke
				(width 0.1)
				(type default)
			)
			(layer "F.Fab")
		)
		(fp_line
			(start 0.120396 0.2794)
			(end -0.12065 0.2794)
			(stroke
				(width 0.1)
				(type default)
			)
			(layer "F.Fab")
		)
		(fp_line
			(start 0.120396 0.3048)
			(end 0.120396 0.2794)
			(stroke
				(width 0.1)
				(type default)
			)
			(layer "F.Fab")
		)
		(fp_line
			(start 0.12065 -0.3048)
			(end 0.67945 -0.3048)
			(stroke
				(width 0.1)
				(type default)
			)
			(layer "F.Fab")
		)
		(fp_line
			(start 0.12065 -0.2794)
			(end 0.12065 -0.3048)
			(stroke
				(width 0.1)
				(type default)
			)
			(layer "F.Fab")
		)
		(fp_line
			(start 0.67945 -0.3048)
			(end 0.67945 0.3048)
			(stroke
				(width 0.1)
				(type default)
			)
			(layer "F.Fab")
		)
		(fp_line
			(start 0.67945 0.3048)
			(end 0.120396 0.3048)
			(stroke
				(width 0.1)
				(type default)
			)
			(layer "F.Fab")
		)
		(pad "1" smd circle
			(at -0.40005 0)
			(size 0 0)
			(layers "F.Cu" "F.Mask" "F.Paste")
			(net "P12V_HPDB_0_TIMER")
		)
		(pad "2" smd circle
			(at 0.40005 0)
			(size 0 0)
			(layers "F.Cu" "F.Mask" "F.Paste")
			(net "GND")
		)
	)
	(footprint ""
		(layer "F.Cu")
		(at 213.36 -95.504 -90)
		(property "Reference" "R55"
			(at 0 0 270)
			(layer "F.SilkS")
			(hide yes)
			(effects
				(font
					(size 1.27 1.27)
				)
			)
		)
		(property "Value" ""
			(at 0 0 270)
			(layer "F.Fab")
			(effects
				(font
					(size 1.27 1.27)
				)
			)
		)
		(duplicate_pad_numbers_are_jumpers no)
		(fp_line
			(start -2.234946 0.9271)
			(end -2.234946 -0.9271)
			(stroke
				(width 0.1524)
				(type default)
			)
			(layer "F.SilkS")
		)
		(fp_line
			(start 2.234946 0.9271)
			(end -2.234946 0.9271)
			(stroke
				(width 0.1524)
				(type default)
			)
			(layer "F.SilkS")
		)
		(fp_line
			(start -2.234946 -0.9271)
			(end 2.234946 -0.9271)
			(stroke
				(width 0.1524)
				(type default)
			)
			(layer "F.SilkS")
		)
		(fp_line
			(start 2.234946 -0.9271)
			(end 2.234946 0.9271)
			(stroke
				(width 0.1524)
				(type default)
			)
			(layer "F.SilkS")
		)
		(fp_line
			(start -1.575054 0.824992)
			(end 1.575054 0.824992)
			(stroke
				(width 0.1)
				(type default)
			)
			(layer "F.Fab")
		)
		(fp_line
			(start 1.575054 0.824992)
			(end 1.575054 -0.824992)
			(stroke
				(width 0.1)
				(type default)
			)
			(layer "F.Fab")
		)
		(fp_line
			(start -1.575054 -0.824992)
			(end -1.575054 0.824992)
			(stroke
				(width 0.1)
				(type default)
			)
			(layer "F.Fab")
		)
		(fp_line
			(start 1.575054 -0.824992)
			(end -1.575054 -0.824992)
			(stroke
				(width 0.1)
				(type default)
			)
			(layer "F.Fab")
		)
		(pad "1" smd rect
			(at -1.599946 0 270)
			(size 1.016 1.6002)
			(layers "F.Cu" "F.Mask" "F.Paste")
			(net "P52V_HS")
		)
		(pad "2" smd rect
			(at 1.599946 0 270)
			(size 1.016 1.6002)
			(layers "F.Cu" "F.Mask" "F.Paste")
			(net "LED_D1_R1")
		)
	)
	(footprint ""
		(layer "F.Cu")
		(at 264.808716 -33.341818 180)
		(property "Reference" "PR211"
			(at 0 0 180)
			(layer "F.SilkS")
			(hide yes)
			(effects
				(font
					(size 1.27 1.27)
				)
			)
		)
		(property "Value" ""
			(at 0 0 180)
			(layer "F.Fab")
			(effects
				(font
					(size 1.27 1.27)
				)
			)
		)
		(duplicate_pad_numbers_are_jumpers no)
		(fp_line
			(start 0.7874 0.4064)
			(end -0.7874 0.4064)
			(stroke
				(width 0.1524)
				(type default)
			)
			(layer "F.SilkS")
		)
		(fp_line
			(start 0.7874 -0.4064)
			(end 0.7874 0.4064)
			(stroke
				(width 0.1524)
				(type default)
			)
			(layer "F.SilkS")
		)
		(fp_line
			(start -0.7874 0.4064)
			(end -0.7874 -0.4064)
			(stroke
				(width 0.1524)
				(type default)
			)
			(layer "F.SilkS")
		)
		(fp_line
			(start -0.7874 -0.4064)
			(end 0.7874 -0.4064)
			(stroke
				(width 0.1524)
				(type default)
			)
			(layer "F.SilkS")
		)
		(fp_line
			(start 0.67945 0.3048)
			(end 0.120396 0.3048)
			(stroke
				(width 0.1)
				(type default)
			)
			(layer "F.Fab")
		)
		(fp_line
			(start 0.67945 -0.3048)
			(end 0.67945 0.3048)
			(stroke
				(width 0.1)
				(type default)
			)
			(layer "F.Fab")
		)
		(fp_line
			(start 0.12065 -0.2794)
			(end 0.12065 -0.3048)
			(stroke
				(width 0.1)
				(type default)
			)
			(layer "F.Fab")
		)
		(fp_line
			(start 0.12065 -0.3048)
			(end 0.67945 -0.3048)
			(stroke
				(width 0.1)
				(type default)
			)
			(layer "F.Fab")
		)
		(fp_line
			(start 0.120396 0.3048)
			(end 0.120396 0.2794)
			(stroke
				(width 0.1)
				(type default)
			)
			(layer "F.Fab")
		)
		(fp_line
			(start 0.120396 0.2794)
			(end -0.12065 0.2794)
			(stroke
				(width 0.1)
				(type default)
			)
			(layer "F.Fab")
		)
		(fp_line
			(start -0.12065 0.3048)
			(end -0.67945 0.3048)
			(stroke
				(width 0.1)
				(type default)
			)
			(layer "F.Fab")
		)
		(fp_line
			(start -0.12065 0.2794)
			(end -0.12065 0.3048)
			(stroke
				(width 0.1)
				(type default)
			)
			(layer "F.Fab")
		)
		(fp_line
			(start -0.12065 -0.2794)
			(end 0.12065 -0.2794)
			(stroke
				(width 0.1)
				(type default)
			)
			(layer "F.Fab")
		)
		(fp_line
			(start -0.12065 -0.305054)
			(end -0.12065 -0.2794)
			(stroke
				(width 0.1)
				(type default)
			)
			(layer "F.Fab")
		)
		(fp_line
			(start -0.67945 0.3048)
			(end -0.67945 -0.305054)
			(stroke
				(width 0.1)
				(type default)
			)
			(layer "F.Fab")
		)
		(fp_line
			(start -0.67945 -0.305054)
			(end -0.12065 -0.305054)
			(stroke
				(width 0.1)
				(type default)
			)
			(layer "F.Fab")
		)
		(pad "1" smd circle
			(at -0.40005 0 180)
			(size 0 0)
			(layers "F.Cu" "F.Mask" "F.Paste")
			(net "HS1_TMR2")
		)
		(pad "2" smd circle
			(at 0.40005 0 180)
			(size 0 0)
			(layers "F.Cu" "F.Mask" "F.Paste")
			(net "GND_FIELD_SIGNAL")
		)
	)
	(footprint ""
		(layer "F.Cu")
		(at 291.61359 -37.061902 180)
		(property "Reference" "PC13"
			(at 0 0 180)
			(layer "F.SilkS")
			(hide yes)
			(effects
				(font
					(size 1.27 1.27)
				)
			)
		)
		(property "Value" ""
			(at 0 0 180)
			(layer "F.Fab")
			(effects
				(font
					(size 1.27 1.27)
				)
			)
		)
		(duplicate_pad_numbers_are_jumpers no)
		(fp_line
			(start 1.524 0.762)
			(end -1.524 0.762)
			(stroke
				(width 0.1524)
				(type default)
			)
			(layer "F.SilkS")
		)
		(fp_line
			(start 1.524 -0.762)
			(end 1.524 0.762)
			(stroke
				(width 0.1524)
				(type default)
			)
			(layer "F.SilkS")
		)
		(fp_line
			(start -1.524 0.762)
			(end -1.524 -0.762)
			(stroke
				(width 0.1524)
				(type default)
			)
			(layer "F.SilkS")
		)
		(fp_line
			(start -1.524 -0.762)
			(end 1.524 -0.762)
			(stroke
				(width 0.1524)
				(type default)
			)
			(layer "F.SilkS")
		)
		(fp_line
			(start 1.1049 0.724916)
			(end 1.1049 -0.724916)
			(stroke
				(width 0.1)
				(type default)
			)
			(layer "F.Fab")
		)
		(fp_line
			(start 1.1049 -0.724916)
			(end -1.1049 -0.724916)
			(stroke
				(width 0.1)
				(type default)
			)
			(layer "F.Fab")
		)
		(fp_line
			(start -1.1049 0.724916)
			(end 1.1049 0.724916)
			(stroke
				(width 0.1)
				(type default)
			)
			(layer "F.Fab")
		)
		(fp_line
			(start -1.1049 -0.724916)
			(end -1.1049 0.724916)
			(stroke
				(width 0.1)
				(type default)
			)
			(layer "F.Fab")
		)
		(pad "1" smd rect
			(at -0.889 0)
			(size 1.016 1.27)
			(layers "F.Cu" "F.Mask" "F.Paste")
			(net "P52V_HS1_DV_DT")
		)
		(pad "2" smd rect
			(at 0.889 0)
			(size 1.016 1.27)
			(layers "F.Cu" "F.Mask" "F.Paste")
			(net "GND_FIELD_SIGNAL")
		)
	)
	(footprint ""
		(layer "F.Cu")
		(at 176.784 -6.858)
		(property "Reference" "PC111"
			(at 0 0 0)
			(layer "F.SilkS")
			(hide yes)
			(effects
				(font
					(size 1.27 1.27)
				)
			)
		)
		(property "Value" ""
			(at 0 0 0)
			(layer "F.Fab")
			(effects
				(font
					(size 1.27 1.27)
				)
			)
		)
		(duplicate_pad_numbers_are_jumpers no)
		(fp_line
			(start -0.7874 -0.4064)
			(end 0.7874 -0.4064)
			(stroke
				(width 0.1524)
				(type default)
			)
			(layer "F.SilkS")
		)
		(fp_line
			(start -0.7874 0.4064)
			(end -0.7874 -0.4064)
			(stroke
				(width 0.1524)
				(type default)
			)
			(layer "F.SilkS")
		)
		(fp_line
			(start 0.7874 -0.4064)
			(end 0.7874 0.4064)
			(stroke
				(width 0.1524)
				(type default)
			)
			(layer "F.SilkS")
		)
		(fp_line
			(start 0.7874 0.4064)
			(end -0.7874 0.4064)
			(stroke
				(width 0.1524)
				(type default)
			)
			(layer "F.SilkS")
		)
		(fp_line
			(start -0.67945 -0.305054)
			(end -0.12065 -0.305054)
			(stroke
				(width 0.1)
				(type default)
			)
			(layer "F.Fab")
		)
		(fp_line
			(start -0.67945 0.3048)
			(end -0.67945 -0.305054)
			(stroke
				(width 0.1)
				(type default)
			)
			(layer "F.Fab")
		)
		(fp_line
			(start -0.12065 -0.305054)
			(end -0.12065 -0.2794)
			(stroke
				(width 0.1)
				(type default)
			)
			(layer "F.Fab")
		)
		(fp_line
			(start -0.12065 -0.2794)
			(end 0.12065 -0.2794)
			(stroke
				(width 0.1)
				(type default)
			)
			(layer "F.Fab")
		)
		(fp_line
			(start -0.12065 0.2794)
			(end -0.12065 0.3048)
			(stroke
				(width 0.1)
				(type default)
			)
			(layer "F.Fab")
		)
		(fp_line
			(start -0.12065 0.3048)
			(end -0.67945 0.3048)
			(stroke
				(width 0.1)
				(type default)
			)
			(layer "F.Fab")
		)
		(fp_line
			(start 0.120396 0.2794)
			(end -0.12065 0.2794)
			(stroke
				(width 0.1)
				(type default)
			)
			(layer "F.Fab")
		)
		(fp_line
			(start 0.120396 0.3048)
			(end 0.120396 0.2794)
			(stroke
				(width 0.1)
				(type default)
			)
			(layer "F.Fab")
		)
		(fp_line
			(start 0.12065 -0.3048)
			(end 0.67945 -0.3048)
			(stroke
				(width 0.1)
				(type default)
			)
			(layer "F.Fab")
		)
		(fp_line
			(start 0.12065 -0.2794)
			(end 0.12065 -0.3048)
			(stroke
				(width 0.1)
				(type default)
			)
			(layer "F.Fab")
		)
		(fp_line
			(start 0.67945 -0.3048)
			(end 0.67945 0.3048)
			(stroke
				(width 0.1)
				(type default)
			)
			(layer "F.Fab")
		)
		(fp_line
			(start 0.67945 0.3048)
			(end 0.120396 0.3048)
			(stroke
				(width 0.1)
				(type default)
			)
			(layer "F.Fab")
		)
		(pad "1" smd circle
			(at -0.40005 0)
			(size 0 0)
			(layers "F.Cu" "F.Mask" "F.Paste")
			(net "P3V3_AUX_FB")
		)
		(pad "2" smd circle
			(at 0.40005 0)
			(size 0 0)
			(layers "F.Cu" "F.Mask" "F.Paste")
			(net "P3V3_AUX")
		)
	)
	(footprint ""
		(layer "F.Cu")
		(at 311.410096 -101.454966)
		(property "Reference" "H24"
			(at -1.9812 -4.079748 0)
			(unlocked yes)
			(layer "B.SilkS")
			(effects
				(font
					(size 0.7874 0.5842)
					(thickness 0.1524)
				)
				(justify left mirror)
			)
		)
		(property "Value" ""
			(at 0 0 0)
			(layer "F.Fab")
			(effects
				(font
					(size 1.27 1.27)
				)
			)
		)
		(duplicate_pad_numbers_are_jumpers no)
		(pad "1" thru_hole circle
			(at 0 0)
			(size 8.001 8.001)
			(drill 4.2418)
			(layers "*.Cu" "*.Mask")
			(remove_unused_layers no)
			(net "H24_TP")
			(clearance -1.6256)
			(padstack
				(mode front_inner_back)
				(layer "Inner"
					(shape circle)
					(size 6.0198 6.0198)
					(clearance -0.635)
				)
				(layer "B.Cu"
					(shape circle)
					(size 8.001 8.001)
					(clearance -1.6256)
				)
			)
		)
		(zone
			(layers "F.Cu" "B.Cu" "In1.Cu" "In2.Cu" "In3.Cu" "In4.Cu" "In5.Cu" "In6.Cu"
				"In7.Cu" "In8.Cu"
			)
			(hatch none 0.5)
			(connect_pads
				(clearance 0)
			)
			(min_thickness 0.25)
			(keepout
				(tracks not_allowed)
				(vias allowed)
				(pads allowed)
				(copperpour not_allowed)
				(footprints allowed)
			)
			(placement
				(enabled no)
				(sheetname "")
			)
			(fill
				(thermal_gap 0.5)
				(thermal_bridge_width 0.5)
				(island_removal_mode 0)
			)
			(polygon
				(pts
					(arc
						(start 314.920122 -101.454966)
						(mid 307.90007 -101.454966)
						(end 314.920122 -101.454966)
					)
				)
			)
		)
	)
	(footprint ""
		(layer "F.Cu")
		(at 73.66 -51.943)
		(property "Reference" "PC94"
			(at 0 0 0)
			(layer "F.SilkS")
			(hide yes)
			(effects
				(font
					(size 1.27 1.27)
				)
			)
		)
		(property "Value" ""
			(at 0 0 0)
			(layer "F.Fab")
			(effects
				(font
					(size 1.27 1.27)
				)
			)
		)
		(duplicate_pad_numbers_are_jumpers no)
		(fp_line
			(start -1.524 -0.762)
			(end 1.524 -0.762)
			(stroke
				(width 0.1524)
				(type default)
			)
			(layer "F.SilkS")
		)
		(fp_line
			(start -1.524 0.762)
			(end -1.524 -0.762)
			(stroke
				(width 0.1524)
				(type default)
			)
			(layer "F.SilkS")
		)
		(fp_line
			(start 1.524 -0.762)
			(end 1.524 0.762)
			(stroke
				(width 0.1524)
				(type default)
			)
			(layer "F.SilkS")
		)
		(fp_line
			(start 1.524 0.762)
			(end -1.524 0.762)
			(stroke
				(width 0.1524)
				(type default)
			)
			(layer "F.SilkS")
		)
		(fp_line
			(start -1.1049 -0.724916)
			(end -1.1049 0.724916)
			(stroke
				(width 0.1)
				(type default)
			)
			(layer "F.Fab")
		)
		(fp_line
			(start -1.1049 0.724916)
			(end 1.1049 0.724916)
			(stroke
				(width 0.1)
				(type default)
			)
			(layer "F.Fab")
		)
		(fp_line
			(start 1.1049 -0.724916)
			(end -1.1049 -0.724916)
			(stroke
				(width 0.1)
				(type default)
			)
			(layer "F.Fab")
		)
		(fp_line
			(start 1.1049 0.724916)
			(end 1.1049 -0.724916)
			(stroke
				(width 0.1)
				(type default)
			)
			(layer "F.Fab")
		)
		(pad "1" smd rect
			(at -0.889 0 180)
			(size 1.016 1.27)
			(layers "F.Cu" "F.Mask" "F.Paste")
			(net "P12V_BRICK")
		)
		(pad "2" smd rect
			(at 0.889 0 180)
			(size 1.016 1.27)
			(layers "F.Cu" "F.Mask" "F.Paste")
			(net "GND")
		)
	)
	(footprint ""
		(layer "F.Cu")
		(at 281.94 -49.276 90)
		(property "Reference" "PR9"
			(at 0 0 90)
			(layer "F.SilkS")
			(hide yes)
			(effects
				(font
					(size 1.27 1.27)
				)
			)
		)
		(property "Value" ""
			(at 0 0 90)
			(layer "F.Fab")
			(effects
				(font
					(size 1.27 1.27)
				)
			)
		)
		(duplicate_pad_numbers_are_jumpers no)
		(fp_line
			(start 0.7874 -0.4064)
			(end 0.7874 0.4064)
			(stroke
				(width 0.1524)
				(type default)
			)
			(layer "F.SilkS")
		)
		(fp_line
			(start -0.7874 -0.4064)
			(end 0.7874 -0.4064)
			(stroke
				(width 0.1524)
				(type default)
			)
			(layer "F.SilkS")
		)
		(fp_line
			(start 0.7874 0.4064)
			(end -0.7874 0.4064)
			(stroke
				(width 0.1524)
				(type default)
			)
			(layer "F.SilkS")
		)
		(fp_line
			(start -0.7874 0.4064)
			(end -0.7874 -0.4064)
			(stroke
				(width 0.1524)
				(type default)
			)
			(layer "F.SilkS")
		)
		(fp_line
			(start -0.12065 -0.305054)
			(end -0.12065 -0.2794)
			(stroke
				(width 0.1)
				(type default)
			)
			(layer "F.Fab")
		)
		(fp_line
			(start -0.67945 -0.305054)
			(end -0.12065 -0.305054)
			(stroke
				(width 0.1)
				(type default)
			)
			(layer "F.Fab")
		)
		(fp_line
			(start 0.67945 -0.3048)
			(end 0.67945 0.3048)
			(stroke
				(width 0.1)
				(type default)
			)
			(layer "F.Fab")
		)
		(fp_line
			(start 0.12065 -0.3048)
			(end 0.67945 -0.3048)
			(stroke
				(width 0.1)
				(type default)
			)
			(layer "F.Fab")
		)
		(fp_line
			(start 0.12065 -0.2794)
			(end 0.12065 -0.3048)
			(stroke
				(width 0.1)
				(type default)
			)
			(layer "F.Fab")
		)
		(fp_line
			(start -0.12065 -0.2794)
			(end 0.12065 -0.2794)
			(stroke
				(width 0.1)
				(type default)
			)
			(layer "F.Fab")
		)
		(fp_line
			(start 0.120396 0.2794)
			(end -0.12065 0.2794)
			(stroke
				(width 0.1)
				(type default)
			)
			(layer "F.Fab")
		)
		(fp_line
			(start -0.12065 0.2794)
			(end -0.12065 0.3048)
			(stroke
				(width 0.1)
				(type default)
			)
			(layer "F.Fab")
		)
		(fp_line
			(start 0.67945 0.3048)
			(end 0.120396 0.3048)
			(stroke
				(width 0.1)
				(type default)
			)
			(layer "F.Fab")
		)
		(fp_line
			(start 0.120396 0.3048)
			(end 0.120396 0.2794)
			(stroke
				(width 0.1)
				(type default)
			)
			(layer "F.Fab")
		)
		(fp_line
			(start -0.12065 0.3048)
			(end -0.67945 0.3048)
			(stroke
				(width 0.1)
				(type default)
			)
			(layer "F.Fab")
		)
		(fp_line
			(start -0.67945 0.3048)
			(end -0.67945 -0.305054)
			(stroke
				(width 0.1)
				(type default)
			)
			(layer "F.Fab")
		)
		(pad "1" smd circle
			(at -0.40005 0 90)
			(size 0 0)
			(layers "F.Cu" "F.Mask" "F.Paste")
			(net "P52V_HS1_OV")
		)
		(pad "2" smd circle
			(at 0.40005 0 90)
			(size 0 0)
			(layers "F.Cu" "F.Mask" "F.Paste")
			(net "GND_FIELD_SIGNAL")
		)
	)
	(footprint ""
		(layer "F.Cu")
		(at 178.562 -8.128)
		(property "Reference" "PR87"
			(at 0 0 0)
			(layer "F.SilkS")
			(hide yes)
			(effects
				(font
					(size 1.27 1.27)
				)
			)
		)
		(property "Value" ""
			(at 0 0 0)
			(layer "F.Fab")
			(effects
				(font
					(size 1.27 1.27)
				)
			)
		)
		(duplicate_pad_numbers_are_jumpers no)
		(fp_line
			(start -0.7874 -0.4064)
			(end 0.7874 -0.4064)
			(stroke
				(width 0.1524)
				(type default)
			)
			(layer "F.SilkS")
		)
		(fp_line
			(start -0.7874 0.4064)
			(end -0.7874 -0.4064)
			(stroke
				(width 0.1524)
				(type default)
			)
			(layer "F.SilkS")
		)
		(fp_line
			(start 0.7874 -0.4064)
			(end 0.7874 0.4064)
			(stroke
				(width 0.1524)
				(type default)
			)
			(layer "F.SilkS")
		)
		(fp_line
			(start 0.7874 0.4064)
			(end -0.7874 0.4064)
			(stroke
				(width 0.1524)
				(type default)
			)
			(layer "F.SilkS")
		)
		(fp_line
			(start -0.67945 -0.305054)
			(end -0.12065 -0.305054)
			(stroke
				(width 0.1)
				(type default)
			)
			(layer "F.Fab")
		)
		(fp_line
			(start -0.67945 0.3048)
			(end -0.67945 -0.305054)
			(stroke
				(width 0.1)
				(type default)
			)
			(layer "F.Fab")
		)
		(fp_line
			(start -0.12065 -0.305054)
			(end -0.12065 -0.2794)
			(stroke
				(width 0.1)
				(type default)
			)
			(layer "F.Fab")
		)
		(fp_line
			(start -0.12065 -0.2794)
			(end 0.12065 -0.2794)
			(stroke
				(width 0.1)
				(type default)
			)
			(layer "F.Fab")
		)
		(fp_line
			(start -0.12065 0.2794)
			(end -0.12065 0.3048)
			(stroke
				(width 0.1)
				(type default)
			)
			(layer "F.Fab")
		)
		(fp_line
			(start -0.12065 0.3048)
			(end -0.67945 0.3048)
			(stroke
				(width 0.1)
				(type default)
			)
			(layer "F.Fab")
		)
		(fp_line
			(start 0.120396 0.2794)
			(end -0.12065 0.2794)
			(stroke
				(width 0.1)
				(type default)
			)
			(layer "F.Fab")
		)
		(fp_line
			(start 0.120396 0.3048)
			(end 0.120396 0.2794)
			(stroke
				(width 0.1)
				(type default)
			)
			(layer "F.Fab")
		)
		(fp_line
			(start 0.12065 -0.3048)
			(end 0.67945 -0.3048)
			(stroke
				(width 0.1)
				(type default)
			)
			(layer "F.Fab")
		)
		(fp_line
			(start 0.12065 -0.2794)
			(end 0.12065 -0.3048)
			(stroke
				(width 0.1)
				(type default)
			)
			(layer "F.Fab")
		)
		(fp_line
			(start 0.67945 -0.3048)
			(end 0.67945 0.3048)
			(stroke
				(width 0.1)
				(type default)
			)
			(layer "F.Fab")
		)
		(fp_line
			(start 0.67945 0.3048)
			(end 0.120396 0.3048)
			(stroke
				(width 0.1)
				(type default)
			)
			(layer "F.Fab")
		)
		(pad "1" smd circle
			(at -0.40005 0)
			(size 0 0)
			(layers "F.Cu" "F.Mask" "F.Paste")
			(net "P3V3_AUX")
		)
		(pad "2" smd circle
			(at 0.40005 0)
			(size 0 0)
			(layers "F.Cu" "F.Mask" "F.Paste")
			(net "P3V3_AUX_PWRGD")
		)
	)
	(footprint ""
		(layer "F.Cu")
		(at 109.097826 -130.175)
		(property "Reference" "PC47"
			(at 0 0 0)
			(layer "F.SilkS")
			(hide yes)
			(effects
				(font
					(size 1.27 1.27)
				)
			)
		)
		(property "Value" ""
			(at 0 0 0)
			(layer "F.Fab")
			(effects
				(font
					(size 1.27 1.27)
				)
			)
		)
		(duplicate_pad_numbers_are_jumpers no)
		(fp_line
			(start -2.2098 -0.9398)
			(end 2.2098 -0.9398)
			(stroke
				(width 0.1524)
				(type default)
			)
			(layer "F.SilkS")
		)
		(fp_line
			(start -2.2098 0.9398)
			(end -2.2098 -0.9398)
			(stroke
				(width 0.1524)
				(type default)
			)
			(layer "F.SilkS")
		)
		(fp_line
			(start 2.2098 -0.9398)
			(end 2.2098 0.9398)
			(stroke
				(width 0.1524)
				(type default)
			)
			(layer "F.SilkS")
		)
		(fp_line
			(start 2.2098 0.9398)
			(end -2.2098 0.9398)
			(stroke
				(width 0.1524)
				(type default)
			)
			(layer "F.SilkS")
		)
		(fp_line
			(start -1.700022 -0.899922)
			(end 1.700022 -0.899922)
			(stroke
				(width 0.1)
				(type default)
			)
			(layer "F.Fab")
		)
		(fp_line
			(start -1.700022 0.899922)
			(end -1.700022 -0.899922)
			(stroke
				(width 0.1)
				(type default)
			)
			(layer "F.Fab")
		)
		(fp_line
			(start 1.700022 -0.899922)
			(end 1.700022 0.899922)
			(stroke
				(width 0.1)
				(type default)
			)
			(layer "F.Fab")
		)
		(fp_line
			(start 1.700022 0.899922)
			(end -1.700022 0.899922)
			(stroke
				(width 0.1)
				(type default)
			)
			(layer "F.Fab")
		)
		(pad "1" smd rect
			(at -1.4732 0 180)
			(size 1.1684 1.5748)
			(layers "F.Cu" "F.Mask" "F.Paste")
			(net "P52V_HS_FILTER")
		)
		(pad "2" smd rect
			(at 1.4732 0 180)
			(size 1.1684 1.5748)
			(layers "F.Cu" "F.Mask" "F.Paste")
			(net "GND")
		)
	)
	(footprint ""
		(layer "F.Cu")
		(at 175.6156 -12.5222 90)
		(property "Reference" "PC102"
			(at 0 0 90)
			(layer "F.SilkS")
			(hide yes)
			(effects
				(font
					(size 1.27 1.27)
				)
			)
		)
		(property "Value" ""
			(at 0 0 90)
			(layer "F.Fab")
			(effects
				(font
					(size 1.27 1.27)
				)
			)
		)
		(duplicate_pad_numbers_are_jumpers no)
		(fp_line
			(start 0.7874 -0.4064)
			(end 0.7874 0.4064)
			(stroke
				(width 0.1524)
				(type default)
			)
			(layer "F.SilkS")
		)
		(fp_line
			(start -0.7874 -0.4064)
			(end 0.7874 -0.4064)
			(stroke
				(width 0.1524)
				(type default)
			)
			(layer "F.SilkS")
		)
		(fp_line
			(start 0.7874 0.4064)
			(end -0.7874 0.4064)
			(stroke
				(width 0.1524)
				(type default)
			)
			(layer "F.SilkS")
		)
		(fp_line
			(start -0.7874 0.4064)
			(end -0.7874 -0.4064)
			(stroke
				(width 0.1524)
				(type default)
			)
			(layer "F.SilkS")
		)
		(fp_line
			(start 0.6858 -0.3048)
			(end 0.6858 0.3048)
			(stroke
				(width 0.1)
				(type default)
			)
			(layer "F.Fab")
		)
		(fp_line
			(start 0.1016 -0.3048)
			(end 0.6858 -0.3048)
			(stroke
				(width 0.1)
				(type default)
			)
			(layer "F.Fab")
		)
		(fp_line
			(start -0.1016 -0.3048)
			(end -0.1016 -0.2794)
			(stroke
				(width 0.1)
				(type default)
			)
			(layer "F.Fab")
		)
		(fp_line
			(start -0.6858 -0.3048)
			(end -0.1016 -0.3048)
			(stroke
				(width 0.1)
				(type default)
			)
			(layer "F.Fab")
		)
		(fp_line
			(start 0.1016 -0.2794)
			(end 0.1016 -0.3048)
			(stroke
				(width 0.1)
				(type default)
			)
			(layer "F.Fab")
		)
		(fp_line
			(start -0.1016 -0.2794)
			(end 0.1016 -0.2794)
			(stroke
				(width 0.1)
				(type default)
			)
			(layer "F.Fab")
		)
		(fp_line
			(start 0.1016 0.2794)
			(end -0.1016 0.2794)
			(stroke
				(width 0.1)
				(type default)
			)
			(layer "F.Fab")
		)
		(fp_line
			(start -0.1016 0.2794)
			(end -0.1016 0.3048)
			(stroke
				(width 0.1)
				(type default)
			)
			(layer "F.Fab")
		)
		(fp_line
			(start 0.6858 0.3048)
			(end 0.1016 0.3048)
			(stroke
				(width 0.1)
				(type default)
			)
			(layer "F.Fab")
		)
		(fp_line
			(start 0.1016 0.3048)
			(end 0.1016 0.2794)
			(stroke
				(width 0.1)
				(type default)
			)
			(layer "F.Fab")
		)
		(fp_line
			(start -0.1016 0.3048)
			(end -0.6858 0.3048)
			(stroke
				(width 0.1)
				(type default)
			)
			(layer "F.Fab")
		)
		(fp_line
			(start -0.6858 0.3048)
			(end -0.6858 -0.3048)
			(stroke
				(width 0.1)
				(type default)
			)
			(layer "F.Fab")
		)
		(pad "1" smd rect
			(at -0.40005 0 270)
			(size 0.4572 0.508)
			(layers "F.Cu" "F.Mask" "F.Paste")
			(net "SW_P12V_FILT__P3V3_AUX")
		)
		(pad "2" smd rect
			(at 0.40005 0 270)
			(size 0.4572 0.508)
			(layers "F.Cu" "F.Mask" "F.Paste")
			(net "GND")
		)
	)
	(footprint ""
		(layer "F.Cu")
		(at 100.965 -51.943)
		(property "Reference" "PC66"
			(at 0 0 0)
			(layer "F.SilkS")
			(hide yes)
			(effects
				(font
					(size 1.27 1.27)
				)
			)
		)
		(property "Value" ""
			(at 0 0 0)
			(layer "F.Fab")
			(effects
				(font
					(size 1.27 1.27)
				)
			)
		)
		(duplicate_pad_numbers_are_jumpers no)
		(fp_line
			(start -1.524 -0.762)
			(end 1.524 -0.762)
			(stroke
				(width 0.1524)
				(type default)
			)
			(layer "F.SilkS")
		)
		(fp_line
			(start -1.524 0.762)
			(end -1.524 -0.762)
			(stroke
				(width 0.1524)
				(type default)
			)
			(layer "F.SilkS")
		)
		(fp_line
			(start 1.524 -0.762)
			(end 1.524 0.762)
			(stroke
				(width 0.1524)
				(type default)
			)
			(layer "F.SilkS")
		)
		(fp_line
			(start 1.524 0.762)
			(end -1.524 0.762)
			(stroke
				(width 0.1524)
				(type default)
			)
			(layer "F.SilkS")
		)
		(fp_line
			(start -1.1049 -0.724916)
			(end -1.1049 0.724916)
			(stroke
				(width 0.1)
				(type default)
			)
			(layer "F.Fab")
		)
		(fp_line
			(start -1.1049 0.724916)
			(end 1.1049 0.724916)
			(stroke
				(width 0.1)
				(type default)
			)
			(layer "F.Fab")
		)
		(fp_line
			(start 1.1049 -0.724916)
			(end -1.1049 -0.724916)
			(stroke
				(width 0.1)
				(type default)
			)
			(layer "F.Fab")
		)
		(fp_line
			(start 1.1049 0.724916)
			(end 1.1049 -0.724916)
			(stroke
				(width 0.1)
				(type default)
			)
			(layer "F.Fab")
		)
		(pad "1" smd rect
			(at -0.889 0 180)
			(size 1.016 1.27)
			(layers "F.Cu" "F.Mask" "F.Paste")
			(net "P12V_BRICK")
		)
		(pad "2" smd rect
			(at 0.889 0 180)
			(size 1.016 1.27)
			(layers "F.Cu" "F.Mask" "F.Paste")
			(net "GND")
		)
	)
	(footprint ""
		(layer "F.Cu")
		(at 205.05801 -113.24717 90)
		(property "Reference" "L5"
			(at -7.576566 -6.472174 0)
			(unlocked yes)
			(layer "F.SilkS")
			(effects
				(font
					(size 0.7874 0.5842)
					(thickness 0.1524)
				)
				(justify left)
			)
		)
		(property "Value" ""
			(at 0 0 90)
			(layer "F.Fab")
			(effects
				(font
					(size 1.27 1.27)
				)
			)
		)
		(duplicate_pad_numbers_are_jumpers no)
		(fp_line
			(start 6.849872 -6.450076)
			(end -6.849872 -6.450076)
			(stroke
				(width 0.1524)
				(type default)
			)
			(layer "F.SilkS")
		)
		(fp_line
			(start -6.849872 -6.450076)
			(end -6.849872 -2.6416)
			(stroke
				(width 0.1524)
				(type default)
			)
			(layer "F.SilkS")
		)
		(fp_line
			(start 6.849872 -2.6416)
			(end 6.849872 -6.450076)
			(stroke
				(width 0.1524)
				(type default)
			)
			(layer "F.SilkS")
		)
		(fp_line
			(start -6.849872 2.6416)
			(end -6.849872 6.450076)
			(stroke
				(width 0.1524)
				(type default)
			)
			(layer "F.SilkS")
		)
		(fp_line
			(start 6.849872 6.450076)
			(end 6.849872 2.6416)
			(stroke
				(width 0.1524)
				(type default)
			)
			(layer "F.SilkS")
		)
		(fp_line
			(start -6.849872 6.450076)
			(end 6.849872 6.450076)
			(stroke
				(width 0.1524)
				(type default)
			)
			(layer "F.SilkS")
		)
		(fp_line
			(start 6.849872 -6.450076)
			(end -6.849872 -6.450076)
			(stroke
				(width 0.1)
				(type default)
			)
			(layer "F.Fab")
		)
		(fp_line
			(start -6.849872 -6.450076)
			(end -6.849872 6.450076)
			(stroke
				(width 0.1)
				(type default)
			)
			(layer "F.Fab")
		)
		(fp_line
			(start 6.849872 6.450076)
			(end 6.849872 -6.450076)
			(stroke
				(width 0.1)
				(type default)
			)
			(layer "F.Fab")
		)
		(fp_line
			(start -6.849872 6.450076)
			(end 6.849872 6.450076)
			(stroke
				(width 0.1)
				(type default)
			)
			(layer "F.Fab")
		)
		(pad "1" smd rect
			(at -5.407406 0 90)
			(size 2.9464 5.0038)
			(layers "F.Cu" "F.Mask" "F.Paste")
			(net "P52V_HS")
		)
		(pad "2" smd rect
			(at 5.407406 0 90)
			(size 2.9464 5.0038)
			(layers "F.Cu" "F.Mask" "F.Paste")
			(net "P52V_HS_FILTER")
		)
	)
	(footprint ""
		(layer "F.Cu")
		(at 56.905906 -127.889)
		(property "Reference" "PC77"
			(at 0 0 0)
			(layer "F.SilkS")
			(hide yes)
			(effects
				(font
					(size 1.27 1.27)
				)
			)
		)
		(property "Value" ""
			(at 0 0 0)
			(layer "F.Fab")
			(effects
				(font
					(size 1.27 1.27)
				)
			)
		)
		(duplicate_pad_numbers_are_jumpers no)
		(fp_line
			(start -2.2098 -0.9398)
			(end 2.2098 -0.9398)
			(stroke
				(width 0.1524)
				(type default)
			)
			(layer "F.SilkS")
		)
		(fp_line
			(start -2.2098 0.9398)
			(end -2.2098 -0.9398)
			(stroke
				(width 0.1524)
				(type default)
			)
			(layer "F.SilkS")
		)
		(fp_line
			(start 2.2098 -0.9398)
			(end 2.2098 0.9398)
			(stroke
				(width 0.1524)
				(type default)
			)
			(layer "F.SilkS")
		)
		(fp_line
			(start 2.2098 0.9398)
			(end -2.2098 0.9398)
			(stroke
				(width 0.1524)
				(type default)
			)
			(layer "F.SilkS")
		)
		(fp_line
			(start -1.700022 -0.899922)
			(end 1.700022 -0.899922)
			(stroke
				(width 0.1)
				(type default)
			)
			(layer "F.Fab")
		)
		(fp_line
			(start -1.700022 0.899922)
			(end -1.700022 -0.899922)
			(stroke
				(width 0.1)
				(type default)
			)
			(layer "F.Fab")
		)
		(fp_line
			(start 1.700022 -0.899922)
			(end 1.700022 0.899922)
			(stroke
				(width 0.1)
				(type default)
			)
			(layer "F.Fab")
		)
		(fp_line
			(start 1.700022 0.899922)
			(end -1.700022 0.899922)
			(stroke
				(width 0.1)
				(type default)
			)
			(layer "F.Fab")
		)
		(pad "1" smd rect
			(at -1.4732 0 180)
			(size 1.1684 1.5748)
			(layers "F.Cu" "F.Mask" "F.Paste")
			(net "P52V_HS_FILTER")
		)
		(pad "2" smd rect
			(at 1.4732 0 180)
			(size 1.1684 1.5748)
			(layers "F.Cu" "F.Mask" "F.Paste")
			(net "GND")
		)
	)
	(footprint ""
		(layer "F.Cu")
		(at 176.906174 -130.175)
		(property "Reference" "PC117"
			(at 0 0 0)
			(layer "F.SilkS")
			(hide yes)
			(effects
				(font
					(size 1.27 1.27)
				)
			)
		)
		(property "Value" ""
			(at 0 0 0)
			(layer "F.Fab")
			(effects
				(font
					(size 1.27 1.27)
				)
			)
		)
		(duplicate_pad_numbers_are_jumpers no)
		(fp_line
			(start -2.2098 -0.9398)
			(end 2.2098 -0.9398)
			(stroke
				(width 0.1524)
				(type default)
			)
			(layer "F.SilkS")
		)
		(fp_line
			(start -2.2098 0.9398)
			(end -2.2098 -0.9398)
			(stroke
				(width 0.1524)
				(type default)
			)
			(layer "F.SilkS")
		)
		(fp_line
			(start 2.2098 -0.9398)
			(end 2.2098 0.9398)
			(stroke
				(width 0.1524)
				(type default)
			)
			(layer "F.SilkS")
		)
		(fp_line
			(start 2.2098 0.9398)
			(end -2.2098 0.9398)
			(stroke
				(width 0.1524)
				(type default)
			)
			(layer "F.SilkS")
		)
		(fp_line
			(start -1.700022 -0.899922)
			(end 1.700022 -0.899922)
			(stroke
				(width 0.1)
				(type default)
			)
			(layer "F.Fab")
		)
		(fp_line
			(start -1.700022 0.899922)
			(end -1.700022 -0.899922)
			(stroke
				(width 0.1)
				(type default)
			)
			(layer "F.Fab")
		)
		(fp_line
			(start 1.700022 -0.899922)
			(end 1.700022 0.899922)
			(stroke
				(width 0.1)
				(type default)
			)
			(layer "F.Fab")
		)
		(fp_line
			(start 1.700022 0.899922)
			(end -1.700022 0.899922)
			(stroke
				(width 0.1)
				(type default)
			)
			(layer "F.Fab")
		)
		(pad "1" smd rect
			(at -1.4732 0 180)
			(size 1.1684 1.5748)
			(layers "F.Cu" "F.Mask" "F.Paste")
			(net "P52V_HS_FILTER")
		)
		(pad "2" smd rect
			(at 1.4732 0 180)
			(size 1.1684 1.5748)
			(layers "F.Cu" "F.Mask" "F.Paste")
			(net "GND")
		)
	)
	(footprint ""
		(layer "F.Cu")
		(at 191.643 -6.985)
		(property "Reference" "PC104"
			(at 0 0 0)
			(layer "F.SilkS")
			(hide yes)
			(effects
				(font
					(size 1.27 1.27)
				)
			)
		)
		(property "Value" ""
			(at 0 0 0)
			(layer "F.Fab")
			(effects
				(font
					(size 1.27 1.27)
				)
			)
		)
		(duplicate_pad_numbers_are_jumpers no)
		(fp_line
			(start -0.7874 -0.4064)
			(end 0.7874 -0.4064)
			(stroke
				(width 0.1524)
				(type default)
			)
			(layer "F.SilkS")
		)
		(fp_line
			(start -0.7874 0.4064)
			(end -0.7874 -0.4064)
			(stroke
				(width 0.1524)
				(type default)
			)
			(layer "F.SilkS")
		)
		(fp_line
			(start 0.7874 -0.4064)
			(end 0.7874 0.4064)
			(stroke
				(width 0.1524)
				(type default)
			)
			(layer "F.SilkS")
		)
		(fp_line
			(start 0.7874 0.4064)
			(end -0.7874 0.4064)
			(stroke
				(width 0.1524)
				(type default)
			)
			(layer "F.SilkS")
		)
		(fp_line
			(start -0.67945 -0.305054)
			(end -0.12065 -0.305054)
			(stroke
				(width 0.1)
				(type default)
			)
			(layer "F.Fab")
		)
		(fp_line
			(start -0.67945 0.3048)
			(end -0.67945 -0.305054)
			(stroke
				(width 0.1)
				(type default)
			)
			(layer "F.Fab")
		)
		(fp_line
			(start -0.12065 -0.305054)
			(end -0.12065 -0.2794)
			(stroke
				(width 0.1)
				(type default)
			)
			(layer "F.Fab")
		)
		(fp_line
			(start -0.12065 -0.2794)
			(end 0.12065 -0.2794)
			(stroke
				(width 0.1)
				(type default)
			)
			(layer "F.Fab")
		)
		(fp_line
			(start -0.12065 0.2794)
			(end -0.12065 0.3048)
			(stroke
				(width 0.1)
				(type default)
			)
			(layer "F.Fab")
		)
		(fp_line
			(start -0.12065 0.3048)
			(end -0.67945 0.3048)
			(stroke
				(width 0.1)
				(type default)
			)
			(layer "F.Fab")
		)
		(fp_line
			(start 0.120396 0.2794)
			(end -0.12065 0.2794)
			(stroke
				(width 0.1)
				(type default)
			)
			(layer "F.Fab")
		)
		(fp_line
			(start 0.120396 0.3048)
			(end 0.120396 0.2794)
			(stroke
				(width 0.1)
				(type default)
			)
			(layer "F.Fab")
		)
		(fp_line
			(start 0.12065 -0.3048)
			(end 0.67945 -0.3048)
			(stroke
				(width 0.1)
				(type default)
			)
			(layer "F.Fab")
		)
		(fp_line
			(start 0.12065 -0.2794)
			(end 0.12065 -0.3048)
			(stroke
				(width 0.1)
				(type default)
			)
			(layer "F.Fab")
		)
		(fp_line
			(start 0.67945 -0.3048)
			(end 0.67945 0.3048)
			(stroke
				(width 0.1)
				(type default)
			)
			(layer "F.Fab")
		)
		(fp_line
			(start 0.67945 0.3048)
			(end 0.120396 0.3048)
			(stroke
				(width 0.1)
				(type default)
			)
			(layer "F.Fab")
		)
		(pad "1" smd circle
			(at -0.40005 0)
			(size 0 0)
			(layers "F.Cu" "F.Mask" "F.Paste")
			(net "P3V3_AUX")
		)
		(pad "2" smd circle
			(at 0.40005 0)
			(size 0 0)
			(layers "F.Cu" "F.Mask" "F.Paste")
			(net "GND")
		)
	)
	(footprint ""
		(layer "F.Cu")
		(at 292.354 -22.9616 90)
		(property "Reference" "JP3"
			(at 2.13233 -1.27 0)
			(unlocked yes)
			(layer "F.SilkS")
			(effects
				(font
					(size 0.7874 0.5842)
					(thickness 0.1524)
				)
				(justify left)
			)
		)
		(property "Value" ""
			(at 0 0 90)
			(layer "F.Fab")
			(effects
				(font
					(size 1.27 1.27)
				)
			)
		)
		(duplicate_pad_numbers_are_jumpers no)
		(fp_line
			(start 1.234948 -1.335024)
			(end 1.234948 6.415024)
			(stroke
				(width 0.1524)
				(type default)
			)
			(layer "F.SilkS")
		)
		(fp_line
			(start -1.234948 -1.335024)
			(end 1.234948 -1.335024)
			(stroke
				(width 0.1524)
				(type default)
			)
			(layer "F.SilkS")
		)
		(fp_line
			(start 1.234948 6.415024)
			(end -1.234948 6.415024)
			(stroke
				(width 0.1524)
				(type default)
			)
			(layer "F.SilkS")
		)
		(fp_line
			(start -1.234948 6.415024)
			(end -1.234948 -1.335024)
			(stroke
				(width 0.1524)
				(type default)
			)
			(layer "F.SilkS")
		)
		(fp_poly
			(pts
				(xy 0.508 -2.530348) (xy -0.508 -2.530348) (xy 0 -1.514348)
			)
			(stroke
				(width 0)
				(type default)
			)
			(fill yes)
			(layer "F.SilkS")
		)
		(fp_line
			(start 1.234948 -1.335024)
			(end 1.234948 6.415024)
			(stroke
				(width 0.1)
				(type default)
			)
			(layer "F.Fab")
		)
		(fp_line
			(start -1.234948 -1.335024)
			(end 1.234948 -1.335024)
			(stroke
				(width 0.1)
				(type default)
			)
			(layer "F.Fab")
		)
		(fp_line
			(start 1.234948 6.415024)
			(end -1.234948 6.415024)
			(stroke
				(width 0.1)
				(type default)
			)
			(layer "F.Fab")
		)
		(fp_line
			(start -1.234948 6.415024)
			(end -1.234948 -1.335024)
			(stroke
				(width 0.1)
				(type default)
			)
			(layer "F.Fab")
		)
		(fp_poly
			(pts
				(xy 0.508 -2.530348) (xy -0.508 -2.530348) (xy 0 -1.514348)
			)
			(stroke
				(width 0)
				(type default)
			)
			(fill yes)
			(layer "F.Fab")
		)
		(fp_text user "3"
			(at -2.05867 4.826 0)
			(unlocked yes)
			(layer "F.SilkS")
			(effects
				(font
					(size 0.7874 0.5842)
					(thickness 0.1524)
				)
				(justify left)
			)
		)
		(fp_text user "1"
			(at -0.00127 -0.954024 0)
			(unlocked yes)
			(layer "B.SilkS")
			(effects
				(font
					(size 0.7874 0.5842)
					(thickness 0.1524)
				)
				(justify left mirror)
			)
		)
		(fp_text user "3"
			(at -0.00127 6.640576 0)
			(unlocked yes)
			(layer "B.SilkS")
			(effects
				(font
					(size 0.7874 0.5842)
					(thickness 0.1524)
				)
				(justify left mirror)
			)
		)
		(fp_text user "1"
			(at -0.00127 -0.954024 0)
			(unlocked yes)
			(layer "B.Fab")
			(effects
				(font
					(size 0.7874 0.5842)
					(thickness 0.1524)
				)
				(justify left mirror)
			)
		)
		(fp_text user "3"
			(at -0.00127 6.640576 0)
			(unlocked yes)
			(layer "B.Fab")
			(effects
				(font
					(size 0.7874 0.5842)
					(thickness 0.1524)
				)
				(justify left mirror)
			)
		)
		(fp_text user "3"
			(at -0.009652 6.5659 0)
			(unlocked yes)
			(layer "F.Fab")
			(effects
				(font
					(size 0.7874 0.5842)
					(thickness 0.1524)
				)
				(justify left)
			)
		)
		(pad "1" thru_hole rect
			(at 0 0)
			(size 1.6764 1.6764)
			(drill 1.1684)
			(layers "*.Cu" "*.Mask")
			(remove_unused_layers no)
			(net "FM_HSC_EN_BUSBAR")
			(clearance 0)
			(padstack
				(mode front_inner_back)
				(layer "Inner"
					(shape circle)
					(size 1.6764 1.6764)
					(clearance 0)
				)
				(layer "B.Cu"
					(shape rect)
					(size 1.6764 1.6764)
					(clearance 0)
				)
			)
		)
		(pad "2" thru_hole circle
			(at 0 2.54)
			(size 1.6764 1.6764)
			(drill 1.1684)
			(layers "*.Cu" "*.Mask")
			(remove_unused_layers no)
			(net "P52V_HS1_EN")
			(clearance 0)
		)
		(pad "3" thru_hole circle
			(at 0 5.08)
			(size 1.6764 1.6764)
			(drill 1.1684)
			(layers "*.Cu" "*.Mask")
			(remove_unused_layers no)
			(net "FM_HSC_EN_FUSE")
			(clearance 0)
		)
	)
	(footprint ""
		(layer "F.Cu")
		(at 146.431 -136.906 90)
		(property "Reference" "PC15"
			(at 6.06933 1.27 0)
			(unlocked yes)
			(layer "F.SilkS")
			(effects
				(font
					(size 0.7874 0.5842)
					(thickness 0.1524)
				)
				(justify left)
			)
		)
		(property "Value" ""
			(at 0 0 90)
			(layer "F.Fab")
			(effects
				(font
					(size 1.27 1.27)
				)
			)
		)
		(duplicate_pad_numbers_are_jumpers no)
		(fp_line
			(start 5.2578 2.499868)
			(end -5.2578 2.499868)
			(stroke
				(width 0.1524)
				(type default)
			)
			(layer "F.SilkS")
		)
		(fp_circle
			(center 0 2.500122)
			(end 0 7.758176)
			(stroke
				(width 0.1524)
				(type default)
			)
			(fill no)
			(layer "F.SilkS")
		)
		(fp_poly
			(pts
				(arc
					(start 5.2578 2.499868)
					(mid 0 7.757922)
					(end -5.2578 2.499868)
				)
			)
			(stroke
				(width 0)
				(type default)
			)
			(fill yes)
			(layer "F.SilkS")
		)
		(fp_circle
			(center 0 2.500122)
			(end 0 7.758176)
			(stroke
				(width 0.1)
				(type default)
			)
			(fill no)
			(layer "F.Fab")
		)
		(pad "1" thru_hole rect
			(at 0 0)
			(size 1.5748 1.5748)
			(drill 1.0668)
			(layers "*.Cu" "*.Mask")
			(remove_unused_layers no)
			(net "P52V_HS_FILTER")
			(clearance 0)
			(padstack
				(mode front_inner_back)
				(layer "Inner"
					(shape circle)
					(size 1.5748 1.5748)
					(clearance 0)
				)
				(layer "B.Cu"
					(shape rect)
					(size 1.5748 1.5748)
					(clearance 0)
				)
			)
		)
		(pad "2" thru_hole circle
			(at 0 4.99999)
			(size 1.5748 1.5748)
			(drill 1.0668)
			(layers "*.Cu" "*.Mask")
			(remove_unused_layers no)
			(net "GND")
			(clearance 0)
		)
	)
	(footprint ""
		(layer "F.Cu")
		(at 220.218 -95.504 -90)
		(property "Reference" "C27"
			(at 0 0 270)
			(layer "F.SilkS")
			(hide yes)
			(effects
				(font
					(size 1.27 1.27)
				)
			)
		)
		(property "Value" ""
			(at 0 0 270)
			(layer "F.Fab")
			(effects
				(font
					(size 1.27 1.27)
				)
			)
		)
		(duplicate_pad_numbers_are_jumpers no)
		(fp_line
			(start -2.2098 0.9398)
			(end -2.2098 -0.9398)
			(stroke
				(width 0.1524)
				(type default)
			)
			(layer "F.SilkS")
		)
		(fp_line
			(start 2.2098 0.9398)
			(end -2.2098 0.9398)
			(stroke
				(width 0.1524)
				(type default)
			)
			(layer "F.SilkS")
		)
		(fp_line
			(start -2.2098 -0.9398)
			(end 2.2098 -0.9398)
			(stroke
				(width 0.1524)
				(type default)
			)
			(layer "F.SilkS")
		)
		(fp_line
			(start 2.2098 -0.9398)
			(end 2.2098 0.9398)
			(stroke
				(width 0.1524)
				(type default)
			)
			(layer "F.SilkS")
		)
		(fp_line
			(start -1.700022 0.899922)
			(end -1.700022 -0.899922)
			(stroke
				(width 0.1)
				(type default)
			)
			(layer "F.Fab")
		)
		(fp_line
			(start 1.700022 0.899922)
			(end -1.700022 0.899922)
			(stroke
				(width 0.1)
				(type default)
			)
			(layer "F.Fab")
		)
		(fp_line
			(start -1.700022 -0.899922)
			(end 1.700022 -0.899922)
			(stroke
				(width 0.1)
				(type default)
			)
			(layer "F.Fab")
		)
		(fp_line
			(start 1.700022 -0.899922)
			(end 1.700022 0.899922)
			(stroke
				(width 0.1)
				(type default)
			)
			(layer "F.Fab")
		)
		(pad "1" smd rect
			(at -1.4732 0 90)
			(size 1.1684 1.5748)
			(layers "F.Cu" "F.Mask" "F.Paste")
			(net "P52V_HS")
		)
		(pad "2" smd rect
			(at 1.4732 0 90)
			(size 1.1684 1.5748)
			(layers "F.Cu" "F.Mask" "F.Paste")
			(net "GND")
		)
	)
	(footprint ""
		(layer "F.Cu")
		(at 176.784 -8.128)
		(property "Reference" "PR90"
			(at 0 0 0)
			(layer "F.SilkS")
			(hide yes)
			(effects
				(font
					(size 1.27 1.27)
				)
			)
		)
		(property "Value" ""
			(at 0 0 0)
			(layer "F.Fab")
			(effects
				(font
					(size 1.27 1.27)
				)
			)
		)
		(duplicate_pad_numbers_are_jumpers no)
		(fp_line
			(start -0.7874 -0.4064)
			(end 0.7874 -0.4064)
			(stroke
				(width 0.1524)
				(type default)
			)
			(layer "F.SilkS")
		)
		(fp_line
			(start -0.7874 0.4064)
			(end -0.7874 -0.4064)
			(stroke
				(width 0.1524)
				(type default)
			)
			(layer "F.SilkS")
		)
		(fp_line
			(start 0.7874 -0.4064)
			(end 0.7874 0.4064)
			(stroke
				(width 0.1524)
				(type default)
			)
			(layer "F.SilkS")
		)
		(fp_line
			(start 0.7874 0.4064)
			(end -0.7874 0.4064)
			(stroke
				(width 0.1524)
				(type default)
			)
			(layer "F.SilkS")
		)
		(fp_line
			(start -0.67945 -0.305054)
			(end -0.12065 -0.305054)
			(stroke
				(width 0.1)
				(type default)
			)
			(layer "F.Fab")
		)
		(fp_line
			(start -0.67945 0.3048)
			(end -0.67945 -0.305054)
			(stroke
				(width 0.1)
				(type default)
			)
			(layer "F.Fab")
		)
		(fp_line
			(start -0.12065 -0.305054)
			(end -0.12065 -0.2794)
			(stroke
				(width 0.1)
				(type default)
			)
			(layer "F.Fab")
		)
		(fp_line
			(start -0.12065 -0.2794)
			(end 0.12065 -0.2794)
			(stroke
				(width 0.1)
				(type default)
			)
			(layer "F.Fab")
		)
		(fp_line
			(start -0.12065 0.2794)
			(end -0.12065 0.3048)
			(stroke
				(width 0.1)
				(type default)
			)
			(layer "F.Fab")
		)
		(fp_line
			(start -0.12065 0.3048)
			(end -0.67945 0.3048)
			(stroke
				(width 0.1)
				(type default)
			)
			(layer "F.Fab")
		)
		(fp_line
			(start 0.120396 0.2794)
			(end -0.12065 0.2794)
			(stroke
				(width 0.1)
				(type default)
			)
			(layer "F.Fab")
		)
		(fp_line
			(start 0.120396 0.3048)
			(end 0.120396 0.2794)
			(stroke
				(width 0.1)
				(type default)
			)
			(layer "F.Fab")
		)
		(fp_line
			(start 0.12065 -0.3048)
			(end 0.67945 -0.3048)
			(stroke
				(width 0.1)
				(type default)
			)
			(layer "F.Fab")
		)
		(fp_line
			(start 0.12065 -0.2794)
			(end 0.12065 -0.3048)
			(stroke
				(width 0.1)
				(type default)
			)
			(layer "F.Fab")
		)
		(fp_line
			(start 0.67945 -0.3048)
			(end 0.67945 0.3048)
			(stroke
				(width 0.1)
				(type default)
			)
			(layer "F.Fab")
		)
		(fp_line
			(start 0.67945 0.3048)
			(end 0.120396 0.3048)
			(stroke
				(width 0.1)
				(type default)
			)
			(layer "F.Fab")
		)
		(pad "1" smd circle
			(at -0.40005 0)
			(size 0 0)
			(layers "F.Cu" "F.Mask" "F.Paste")
			(net "P3V3_AUX_FB")
		)
		(pad "2" smd circle
			(at 0.40005 0)
			(size 0 0)
			(layers "F.Cu" "F.Mask" "F.Paste")
			(net "P3V3_AUX")
		)
	)
	(footprint ""
		(layer "F.Cu")
		(at 51.054 -5.207)
		(property "Reference" ""
			(at 0 0 0)
			(layer "F.SilkS")
			(hide yes)
			(effects
				(font
					(size 1.27 1.27)
				)
			)
		)
		(property "Value" ""
			(at 0 0 0)
			(layer "F.Fab")
			(effects
				(font
					(size 1.27 1.27)
				)
			)
		)
		(duplicate_pad_numbers_are_jumpers no)
		(pad "1" smd circle
			(at 0 0)
			(size 0.9906 0.9906)
			(layers "F.Cu" "F.Mask" "F.Paste")
			(net "Net_279")
		)
		(zone
			(layer "F.Cu")
			(hatch none 0.5)
			(connect_pads
				(clearance 0)
			)
			(min_thickness 0.25)
			(keepout
				(tracks not_allowed)
				(vias allowed)
				(pads allowed)
				(copperpour not_allowed)
				(footprints allowed)
			)
			(placement
				(enabled no)
				(sheetname "")
			)
			(fill
				(thermal_gap 0.5)
				(thermal_bridge_width 0.5)
				(island_removal_mode 0)
			)
			(polygon
				(pts
					(arc
						(start 52.6796 -5.207)
						(mid 49.4284 -5.207)
						(end 52.6796 -5.207)
					)
				)
			)
		)
	)
	(footprint ""
		(layer "F.Cu")
		(at 146.431 -7.747)
		(property "Reference" "ME5"
			(at 0 0 0)
			(layer "F.SilkS")
			(hide yes)
			(effects
				(font
					(size 1.27 1.27)
				)
			)
		)
		(property "Value" ""
			(at 0 0 0)
			(layer "F.Fab")
			(effects
				(font
					(size 1.27 1.27)
				)
			)
		)
		(duplicate_pad_numbers_are_jumpers no)
	)
	(footprint ""
		(layer "F.Cu")
		(at 82.046826 -136.906 90)
		(property "Reference" "PC45"
			(at 6.06933 1.011174 0)
			(unlocked yes)
			(layer "F.SilkS")
			(effects
				(font
					(size 0.7874 0.5842)
					(thickness 0.1524)
				)
				(justify left)
			)
		)
		(property "Value" ""
			(at 0 0 90)
			(layer "F.Fab")
			(effects
				(font
					(size 1.27 1.27)
				)
			)
		)
		(duplicate_pad_numbers_are_jumpers no)
		(fp_line
			(start 5.2578 2.499868)
			(end -5.2578 2.499868)
			(stroke
				(width 0.1524)
				(type default)
			)
			(layer "F.SilkS")
		)
		(fp_circle
			(center 0 2.500122)
			(end 0 7.758176)
			(stroke
				(width 0.1524)
				(type default)
			)
			(fill no)
			(layer "F.SilkS")
		)
		(fp_poly
			(pts
				(arc
					(start 5.2578 2.499868)
					(mid 0 7.757922)
					(end -5.2578 2.499868)
				)
			)
			(stroke
				(width 0)
				(type default)
			)
			(fill yes)
			(layer "F.SilkS")
		)
		(fp_circle
			(center 0 2.500122)
			(end 0 7.758176)
			(stroke
				(width 0.1)
				(type default)
			)
			(fill no)
			(layer "F.Fab")
		)
		(pad "1" thru_hole rect
			(at 0 0)
			(size 1.5748 1.5748)
			(drill 1.0668)
			(layers "*.Cu" "*.Mask")
			(remove_unused_layers no)
			(net "P52V_HS_FILTER")
			(clearance 0)
			(padstack
				(mode front_inner_back)
				(layer "Inner"
					(shape circle)
					(size 1.5748 1.5748)
					(clearance 0)
				)
				(layer "B.Cu"
					(shape rect)
					(size 1.5748 1.5748)
					(clearance 0)
				)
			)
		)
		(pad "2" thru_hole circle
			(at 0 4.99999)
			(size 1.5748 1.5748)
			(drill 1.0668)
			(layers "*.Cu" "*.Mask")
			(remove_unused_layers no)
			(net "GND")
			(clearance 0)
		)
	)
	(footprint ""
		(layer "F.Cu")
		(at 106.430826 -136.906 90)
		(property "Reference" "PC43"
			(at 6.06933 1.138174 0)
			(unlocked yes)
			(layer "F.SilkS")
			(effects
				(font
					(size 0.7874 0.5842)
					(thickness 0.1524)
				)
				(justify left)
			)
		)
		(property "Value" ""
			(at 0 0 90)
			(layer "F.Fab")
			(effects
				(font
					(size 1.27 1.27)
				)
			)
		)
		(duplicate_pad_numbers_are_jumpers no)
		(fp_line
			(start 5.2578 2.499868)
			(end -5.2578 2.499868)
			(stroke
				(width 0.1524)
				(type default)
			)
			(layer "F.SilkS")
		)
		(fp_circle
			(center 0 2.500122)
			(end 0 7.758176)
			(stroke
				(width 0.1524)
				(type default)
			)
			(fill no)
			(layer "F.SilkS")
		)
		(fp_poly
			(pts
				(arc
					(start 5.2578 2.499868)
					(mid 0 7.757922)
					(end -5.2578 2.499868)
				)
			)
			(stroke
				(width 0)
				(type default)
			)
			(fill yes)
			(layer "F.SilkS")
		)
		(fp_circle
			(center 0 2.500122)
			(end 0 7.758176)
			(stroke
				(width 0.1)
				(type default)
			)
			(fill no)
			(layer "F.Fab")
		)
		(pad "1" thru_hole rect
			(at 0 0)
			(size 1.5748 1.5748)
			(drill 1.0668)
			(layers "*.Cu" "*.Mask")
			(remove_unused_layers no)
			(net "P52V_HS_FILTER")
			(clearance 0)
			(padstack
				(mode front_inner_back)
				(layer "Inner"
					(shape circle)
					(size 1.5748 1.5748)
					(clearance 0)
				)
				(layer "B.Cu"
					(shape rect)
					(size 1.5748 1.5748)
					(clearance 0)
				)
			)
		)
		(pad "2" thru_hole circle
			(at 0 4.99999)
			(size 1.5748 1.5748)
			(drill 1.0668)
			(layers "*.Cu" "*.Mask")
			(remove_unused_layers no)
			(net "GND")
			(clearance 0)
		)
	)
	(footprint ""
		(layer "F.Cu")
		(at 297.561 -121.4755 180)
		(property "Reference" "PR6962"
			(at 0 0 180)
			(layer "F.SilkS")
			(hide yes)
			(effects
				(font
					(size 1.27 1.27)
				)
			)
		)
		(property "Value" ""
			(at 0 0 180)
			(layer "F.Fab")
			(effects
				(font
					(size 1.27 1.27)
				)
			)
		)
		(duplicate_pad_numbers_are_jumpers no)
		(fp_line
			(start 1.2954 0.5842)
			(end -1.2954 0.5842)
			(stroke
				(width 0.1524)
				(type default)
			)
			(layer "F.SilkS")
		)
		(fp_line
			(start 1.2954 -0.5842)
			(end 1.2954 0.5842)
			(stroke
				(width 0.1524)
				(type default)
			)
			(layer "F.SilkS")
		)
		(fp_line
			(start -1.2954 0.5842)
			(end -1.2954 -0.5842)
			(stroke
				(width 0.1524)
				(type default)
			)
			(layer "F.SilkS")
		)
		(fp_line
			(start -1.2954 -0.5842)
			(end 1.2954 -0.5842)
			(stroke
				(width 0.1524)
				(type default)
			)
			(layer "F.SilkS")
		)
		(fp_line
			(start 1.1938 0.4064)
			(end 0.8636 0.4064)
			(stroke
				(width 0.1)
				(type default)
			)
			(layer "F.Fab")
		)
		(fp_line
			(start 1.1938 -0.406654)
			(end 1.1938 0.4064)
			(stroke
				(width 0.1)
				(type default)
			)
			(layer "F.Fab")
		)
		(fp_line
			(start 0.8636 0.4572)
			(end -0.8636 0.4572)
			(stroke
				(width 0.1)
				(type default)
			)
			(layer "F.Fab")
		)
		(fp_line
			(start 0.8636 0.4064)
			(end 0.8636 0.4572)
			(stroke
				(width 0.1)
				(type default)
			)
			(layer "F.Fab")
		)
		(fp_line
			(start 0.8636 -0.406654)
			(end 1.1938 -0.406654)
			(stroke
				(width 0.1)
				(type default)
			)
			(layer "F.Fab")
		)
		(fp_line
			(start 0.8636 -0.4572)
			(end 0.8636 -0.406654)
			(stroke
				(width 0.1)
				(type default)
			)
			(layer "F.Fab")
		)
		(fp_line
			(start -0.8636 0.4572)
			(end -0.8636 0.4318)
			(stroke
				(width 0.1)
				(type default)
			)
			(layer "F.Fab")
		)
		(fp_line
			(start -0.8636 0.4318)
			(end -0.8636 0.4064)
			(stroke
				(width 0.1)
				(type default)
			)
			(layer "F.Fab")
		)
		(fp_line
			(start -0.8636 0.4064)
			(end -1.1938 0.4064)
			(stroke
				(width 0.1)
				(type default)
			)
			(layer "F.Fab")
		)
		(fp_line
			(start -0.8636 -0.406654)
			(end -0.8636 -0.4572)
			(stroke
				(width 0.1)
				(type default)
			)
			(layer "F.Fab")
		)
		(fp_line
			(start -0.8636 -0.4572)
			(end 0.8636 -0.4572)
			(stroke
				(width 0.1)
				(type default)
			)
			(layer "F.Fab")
		)
		(fp_line
			(start -1.1938 0.4064)
			(end -1.1938 -0.406654)
			(stroke
				(width 0.1)
				(type default)
			)
			(layer "F.Fab")
		)
		(fp_line
			(start -1.1938 -0.406654)
			(end -0.8636 -0.406654)
			(stroke
				(width 0.1)
				(type default)
			)
			(layer "F.Fab")
		)
		(pad "1" smd rect
			(at -0.7366 0 90)
			(size 0.7112 0.8128)
			(layers "F.Cu" "F.Mask" "F.Paste")
			(net "P52V_HS_4287_ADC_N")
		)
		(pad "2" smd rect
			(at 0.7366 0 90)
			(size 0.7112 0.8128)
			(layers "F.Cu" "F.Mask" "F.Paste")
			(net "P52V_HS1_SENSE_N_R1")
		)
	)
	(footprint ""
		(layer "F.Cu")
		(at 84.76488 -16.69288)
		(property "Reference" "ME4"
			(at 0 0 0)
			(layer "F.SilkS")
			(hide yes)
			(effects
				(font
					(size 1.27 1.27)
				)
			)
		)
		(property "Value" ""
			(at 0 0 0)
			(layer "F.Fab")
			(effects
				(font
					(size 1.27 1.27)
				)
			)
		)
		(duplicate_pad_numbers_are_jumpers no)
		(fp_line
			(start 0 -6.999986)
			(end 0 -5.475986)
			(stroke
				(width 0.1524)
				(type default)
			)
			(layer "F.SilkS")
		)
		(fp_line
			(start 0 -1.524)
			(end 0 0)
			(stroke
				(width 0.1524)
				(type default)
			)
			(layer "F.SilkS")
		)
		(fp_line
			(start 0 0)
			(end 1.524 0)
			(stroke
				(width 0.1524)
				(type default)
			)
			(layer "F.SilkS")
		)
		(fp_line
			(start 1.524 -6.999986)
			(end 0 -6.999986)
			(stroke
				(width 0.1524)
				(type default)
			)
			(layer "F.SilkS")
		)
		(fp_line
			(start 5.475986 -6.999986)
			(end 6.999986 -6.999986)
			(stroke
				(width 0.1524)
				(type default)
			)
			(layer "F.SilkS")
		)
		(fp_line
			(start 6.999986 -6.999986)
			(end 6.999986 -5.475986)
			(stroke
				(width 0.1524)
				(type default)
			)
			(layer "F.SilkS")
		)
		(fp_line
			(start 6.999986 -1.524)
			(end 6.999986 0)
			(stroke
				(width 0.1524)
				(type default)
			)
			(layer "F.SilkS")
		)
		(fp_line
			(start 6.999986 0)
			(end 5.475986 0)
			(stroke
				(width 0.1524)
				(type default)
			)
			(layer "F.SilkS")
		)
		(fp_text user "S/N"
			(at 0.361188 -5.450078 0)
			(unlocked yes)
			(layer "F.SilkS")
			(effects
				(font
					(size 1.905 1.4224)
					(thickness 0.1524)
				)
				(justify left)
			)
		)
	)
	(footprint ""
		(layer "F.Cu")
		(at 84.713826 -130.175)
		(property "Reference" "PC51"
			(at 0 0 0)
			(layer "F.SilkS")
			(hide yes)
			(effects
				(font
					(size 1.27 1.27)
				)
			)
		)
		(property "Value" ""
			(at 0 0 0)
			(layer "F.Fab")
			(effects
				(font
					(size 1.27 1.27)
				)
			)
		)
		(duplicate_pad_numbers_are_jumpers no)
		(fp_line
			(start -2.2098 -0.9398)
			(end 2.2098 -0.9398)
			(stroke
				(width 0.1524)
				(type default)
			)
			(layer "F.SilkS")
		)
		(fp_line
			(start -2.2098 0.9398)
			(end -2.2098 -0.9398)
			(stroke
				(width 0.1524)
				(type default)
			)
			(layer "F.SilkS")
		)
		(fp_line
			(start 2.2098 -0.9398)
			(end 2.2098 0.9398)
			(stroke
				(width 0.1524)
				(type default)
			)
			(layer "F.SilkS")
		)
		(fp_line
			(start 2.2098 0.9398)
			(end -2.2098 0.9398)
			(stroke
				(width 0.1524)
				(type default)
			)
			(layer "F.SilkS")
		)
		(fp_line
			(start -1.700022 -0.899922)
			(end 1.700022 -0.899922)
			(stroke
				(width 0.1)
				(type default)
			)
			(layer "F.Fab")
		)
		(fp_line
			(start -1.700022 0.899922)
			(end -1.700022 -0.899922)
			(stroke
				(width 0.1)
				(type default)
			)
			(layer "F.Fab")
		)
		(fp_line
			(start 1.700022 -0.899922)
			(end 1.700022 0.899922)
			(stroke
				(width 0.1)
				(type default)
			)
			(layer "F.Fab")
		)
		(fp_line
			(start 1.700022 0.899922)
			(end -1.700022 0.899922)
			(stroke
				(width 0.1)
				(type default)
			)
			(layer "F.Fab")
		)
		(pad "1" smd rect
			(at -1.4732 0 180)
			(size 1.1684 1.5748)
			(layers "F.Cu" "F.Mask" "F.Paste")
			(net "P52V_HS_FILTER")
		)
		(pad "2" smd rect
			(at 1.4732 0 180)
			(size 1.1684 1.5748)
			(layers "F.Cu" "F.Mask" "F.Paste")
			(net "GND")
		)
	)
	(footprint ""
		(layer "F.Cu")
		(at 282.78201 -56.957214 180)
		(property "Reference" "PR6968"
			(at 0 0 180)
			(layer "F.SilkS")
			(hide yes)
			(effects
				(font
					(size 1.27 1.27)
				)
			)
		)
		(property "Value" ""
			(at 0 0 180)
			(layer "F.Fab")
			(effects
				(font
					(size 1.27 1.27)
				)
			)
		)
		(duplicate_pad_numbers_are_jumpers no)
		(fp_line
			(start 0.7874 0.4064)
			(end -0.7874 0.4064)
			(stroke
				(width 0.1524)
				(type default)
			)
			(layer "F.SilkS")
		)
		(fp_line
			(start 0.7874 -0.4064)
			(end 0.7874 0.4064)
			(stroke
				(width 0.1524)
				(type default)
			)
			(layer "F.SilkS")
		)
		(fp_line
			(start -0.7874 0.4064)
			(end -0.7874 -0.4064)
			(stroke
				(width 0.1524)
				(type default)
			)
			(layer "F.SilkS")
		)
		(fp_line
			(start -0.7874 -0.4064)
			(end 0.7874 -0.4064)
			(stroke
				(width 0.1524)
				(type default)
			)
			(layer "F.SilkS")
		)
		(fp_line
			(start 0.67945 0.3048)
			(end 0.120396 0.3048)
			(stroke
				(width 0.1)
				(type default)
			)
			(layer "F.Fab")
		)
		(fp_line
			(start 0.67945 -0.3048)
			(end 0.67945 0.3048)
			(stroke
				(width 0.1)
				(type default)
			)
			(layer "F.Fab")
		)
		(fp_line
			(start 0.12065 -0.2794)
			(end 0.12065 -0.3048)
			(stroke
				(width 0.1)
				(type default)
			)
			(layer "F.Fab")
		)
		(fp_line
			(start 0.12065 -0.3048)
			(end 0.67945 -0.3048)
			(stroke
				(width 0.1)
				(type default)
			)
			(layer "F.Fab")
		)
		(fp_line
			(start 0.120396 0.3048)
			(end 0.120396 0.2794)
			(stroke
				(width 0.1)
				(type default)
			)
			(layer "F.Fab")
		)
		(fp_line
			(start 0.120396 0.2794)
			(end -0.12065 0.2794)
			(stroke
				(width 0.1)
				(type default)
			)
			(layer "F.Fab")
		)
		(fp_line
			(start -0.12065 0.3048)
			(end -0.67945 0.3048)
			(stroke
				(width 0.1)
				(type default)
			)
			(layer "F.Fab")
		)
		(fp_line
			(start -0.12065 0.2794)
			(end -0.12065 0.3048)
			(stroke
				(width 0.1)
				(type default)
			)
			(layer "F.Fab")
		)
		(fp_line
			(start -0.12065 -0.2794)
			(end 0.12065 -0.2794)
			(stroke
				(width 0.1)
				(type default)
			)
			(layer "F.Fab")
		)
		(fp_line
			(start -0.12065 -0.305054)
			(end -0.12065 -0.2794)
			(stroke
				(width 0.1)
				(type default)
			)
			(layer "F.Fab")
		)
		(fp_line
			(start -0.67945 0.3048)
			(end -0.67945 -0.305054)
			(stroke
				(width 0.1)
				(type default)
			)
			(layer "F.Fab")
		)
		(fp_line
			(start -0.67945 -0.305054)
			(end -0.12065 -0.305054)
			(stroke
				(width 0.1)
				(type default)
			)
			(layer "F.Fab")
		)
		(pad "1" smd rect
			(at -0.40005 0)
			(size 0.4572 0.508)
			(layers "F.Cu" "F.Mask" "F.Paste")
			(net "P52V_HS1_TEMPN")
		)
		(pad "2" smd rect
			(at 0.40005 0)
			(size 0.4572 0.508)
			(layers "F.Cu" "F.Mask" "F.Paste")
			(net "P52V_HS1_TEMPN_R")
		)
	)
	(footprint ""
		(layer "F.Cu")
		(at 297.561 -119.6975 180)
		(property "Reference" "PR6958"
			(at 0 0 180)
			(layer "F.SilkS")
			(hide yes)
			(effects
				(font
					(size 1.27 1.27)
				)
			)
		)
		(property "Value" ""
			(at 0 0 180)
			(layer "F.Fab")
			(effects
				(font
					(size 1.27 1.27)
				)
			)
		)
		(duplicate_pad_numbers_are_jumpers no)
		(fp_line
			(start 1.2954 0.5842)
			(end -1.2954 0.5842)
			(stroke
				(width 0.1524)
				(type default)
			)
			(layer "F.SilkS")
		)
		(fp_line
			(start 1.2954 -0.5842)
			(end 1.2954 0.5842)
			(stroke
				(width 0.1524)
				(type default)
			)
			(layer "F.SilkS")
		)
		(fp_line
			(start -1.2954 0.5842)
			(end -1.2954 -0.5842)
			(stroke
				(width 0.1524)
				(type default)
			)
			(layer "F.SilkS")
		)
		(fp_line
			(start -1.2954 -0.5842)
			(end 1.2954 -0.5842)
			(stroke
				(width 0.1524)
				(type default)
			)
			(layer "F.SilkS")
		)
		(fp_line
			(start 1.1938 0.4064)
			(end 0.8636 0.4064)
			(stroke
				(width 0.1)
				(type default)
			)
			(layer "F.Fab")
		)
		(fp_line
			(start 1.1938 -0.406654)
			(end 1.1938 0.4064)
			(stroke
				(width 0.1)
				(type default)
			)
			(layer "F.Fab")
		)
		(fp_line
			(start 0.8636 0.4572)
			(end -0.8636 0.4572)
			(stroke
				(width 0.1)
				(type default)
			)
			(layer "F.Fab")
		)
		(fp_line
			(start 0.8636 0.4064)
			(end 0.8636 0.4572)
			(stroke
				(width 0.1)
				(type default)
			)
			(layer "F.Fab")
		)
		(fp_line
			(start 0.8636 -0.406654)
			(end 1.1938 -0.406654)
			(stroke
				(width 0.1)
				(type default)
			)
			(layer "F.Fab")
		)
		(fp_line
			(start 0.8636 -0.4572)
			(end 0.8636 -0.406654)
			(stroke
				(width 0.1)
				(type default)
			)
			(layer "F.Fab")
		)
		(fp_line
			(start -0.8636 0.4572)
			(end -0.8636 0.4318)
			(stroke
				(width 0.1)
				(type default)
			)
			(layer "F.Fab")
		)
		(fp_line
			(start -0.8636 0.4318)
			(end -0.8636 0.4064)
			(stroke
				(width 0.1)
				(type default)
			)
			(layer "F.Fab")
		)
		(fp_line
			(start -0.8636 0.4064)
			(end -1.1938 0.4064)
			(stroke
				(width 0.1)
				(type default)
			)
			(layer "F.Fab")
		)
		(fp_line
			(start -0.8636 -0.406654)
			(end -0.8636 -0.4572)
			(stroke
				(width 0.1)
				(type default)
			)
			(layer "F.Fab")
		)
		(fp_line
			(start -0.8636 -0.4572)
			(end 0.8636 -0.4572)
			(stroke
				(width 0.1)
				(type default)
			)
			(layer "F.Fab")
		)
		(fp_line
			(start -1.1938 0.4064)
			(end -1.1938 -0.406654)
			(stroke
				(width 0.1)
				(type default)
			)
			(layer "F.Fab")
		)
		(fp_line
			(start -1.1938 -0.406654)
			(end -0.8636 -0.406654)
			(stroke
				(width 0.1)
				(type default)
			)
			(layer "F.Fab")
		)
		(pad "1" smd rect
			(at -0.7366 0 90)
			(size 0.7112 0.8128)
			(layers "F.Cu" "F.Mask" "F.Paste")
			(net "P52V_HS_1272_S_N")
		)
		(pad "2" smd rect
			(at 0.7366 0 90)
			(size 0.7112 0.8128)
			(layers "F.Cu" "F.Mask" "F.Paste")
			(net "P52V_HS1_SENSE_N_R1")
		)
	)
	(footprint ""
		(layer "F.Cu")
		(at 202.654916 -67.083686 -90)
		(property "Reference" "D2"
			(at 3.202686 -0.063754 90)
			(unlocked yes)
			(layer "F.SilkS")
			(effects
				(font
					(size 0.7874 0.5842)
					(thickness 0.1524)
				)
				(justify left)
			)
		)
		(property "Value" ""
			(at 0 0 270)
			(layer "F.Fab")
			(effects
				(font
					(size 1.27 1.27)
				)
			)
		)
		(duplicate_pad_numbers_are_jumpers no)
		(fp_line
			(start -0.90678 0.4826)
			(end -0.90678 -0.4699)
			(stroke
				(width 0.1524)
				(type default)
			)
			(layer "F.SilkS")
		)
		(fp_line
			(start 0.90678 0.4826)
			(end -0.90678 0.4826)
			(stroke
				(width 0.1524)
				(type default)
			)
			(layer "F.SilkS")
		)
		(fp_line
			(start 1.03378 0.4826)
			(end -0.79248 0.4826)
			(stroke
				(width 0.1524)
				(type default)
			)
			(layer "F.SilkS")
		)
		(fp_line
			(start 1.16078 0.4826)
			(end -0.64008 0.4826)
			(stroke
				(width 0.1524)
				(type default)
			)
			(layer "F.SilkS")
		)
		(fp_line
			(start -0.89408 -0.4826)
			(end 0.90678 -0.4826)
			(stroke
				(width 0.1524)
				(type default)
			)
			(layer "F.SilkS")
		)
		(fp_line
			(start -0.79248 -0.4826)
			(end 1.03378 -0.4826)
			(stroke
				(width 0.1524)
				(type default)
			)
			(layer "F.SilkS")
		)
		(fp_line
			(start -0.64008 -0.4826)
			(end 1.16078 -0.4826)
			(stroke
				(width 0.1524)
				(type default)
			)
			(layer "F.SilkS")
		)
		(fp_line
			(start 0.90678 -0.4826)
			(end 0.90678 0.4826)
			(stroke
				(width 0.1524)
				(type default)
			)
			(layer "F.SilkS")
		)
		(fp_line
			(start 1.03378 -0.4826)
			(end 1.03378 0.4826)
			(stroke
				(width 0.1524)
				(type default)
			)
			(layer "F.SilkS")
		)
		(fp_line
			(start 1.16078 -0.4826)
			(end 1.16078 0.4826)
			(stroke
				(width 0.1524)
				(type default)
			)
			(layer "F.SilkS")
		)
		(fp_line
			(start -0.499872 0.249936)
			(end -0.499872 -0.249936)
			(stroke
				(width 0.1)
				(type default)
			)
			(layer "F.Fab")
		)
		(fp_line
			(start 0.499872 0.249936)
			(end -0.499872 0.249936)
			(stroke
				(width 0.1)
				(type default)
			)
			(layer "F.Fab")
		)
		(fp_line
			(start -0.499872 -0.249936)
			(end 0.499872 -0.249936)
			(stroke
				(width 0.1)
				(type default)
			)
			(layer "F.Fab")
		)
		(fp_line
			(start 0.499872 -0.249936)
			(end 0.499872 0.249936)
			(stroke
				(width 0.1)
				(type default)
			)
			(layer "F.Fab")
		)
		(pad "A" smd rect
			(at -0.47498 0 270)
			(size 0.6096 0.7112)
			(layers "F.Cu" "F.Mask" "F.Paste")
			(net "LED_D2_R3")
		)
		(pad "C" smd rect
			(at 0.47498 0 270)
			(size 0.6096 0.7112)
			(layers "F.Cu" "F.Mask" "F.Paste")
			(net "GND")
		)
	)
	(footprint ""
		(layer "F.Cu")
		(at 45.67936 -60.53582)
		(property "Reference" "C97"
			(at 0 0 0)
			(layer "F.SilkS")
			(hide yes)
			(effects
				(font
					(size 1.27 1.27)
				)
			)
		)
		(property "Value" ""
			(at 0 0 0)
			(layer "F.Fab")
			(effects
				(font
					(size 1.27 1.27)
				)
			)
		)
		(duplicate_pad_numbers_are_jumpers no)
		(fp_line
			(start -0.7874 -0.4064)
			(end 0.7874 -0.4064)
			(stroke
				(width 0.1524)
				(type default)
			)
			(layer "F.SilkS")
		)
		(fp_line
			(start -0.7874 0.4064)
			(end -0.7874 -0.4064)
			(stroke
				(width 0.1524)
				(type default)
			)
			(layer "F.SilkS")
		)
		(fp_line
			(start 0.7874 -0.4064)
			(end 0.7874 0.4064)
			(stroke
				(width 0.1524)
				(type default)
			)
			(layer "F.SilkS")
		)
		(fp_line
			(start 0.7874 0.4064)
			(end -0.7874 0.4064)
			(stroke
				(width 0.1524)
				(type default)
			)
			(layer "F.SilkS")
		)
		(fp_line
			(start -0.67945 -0.305054)
			(end -0.12065 -0.305054)
			(stroke
				(width 0.1)
				(type default)
			)
			(layer "F.Fab")
		)
		(fp_line
			(start -0.67945 0.3048)
			(end -0.67945 -0.305054)
			(stroke
				(width 0.1)
				(type default)
			)
			(layer "F.Fab")
		)
		(fp_line
			(start -0.12065 -0.305054)
			(end -0.12065 -0.2794)
			(stroke
				(width 0.1)
				(type default)
			)
			(layer "F.Fab")
		)
		(fp_line
			(start -0.12065 -0.2794)
			(end 0.12065 -0.2794)
			(stroke
				(width 0.1)
				(type default)
			)
			(layer "F.Fab")
		)
		(fp_line
			(start -0.12065 0.2794)
			(end -0.12065 0.3048)
			(stroke
				(width 0.1)
				(type default)
			)
			(layer "F.Fab")
		)
		(fp_line
			(start -0.12065 0.3048)
			(end -0.67945 0.3048)
			(stroke
				(width 0.1)
				(type default)
			)
			(layer "F.Fab")
		)
		(fp_line
			(start 0.120396 0.2794)
			(end -0.12065 0.2794)
			(stroke
				(width 0.1)
				(type default)
			)
			(layer "F.Fab")
		)
		(fp_line
			(start 0.120396 0.3048)
			(end 0.120396 0.2794)
			(stroke
				(width 0.1)
				(type default)
			)
			(layer "F.Fab")
		)
		(fp_line
			(start 0.12065 -0.3048)
			(end 0.67945 -0.3048)
			(stroke
				(width 0.1)
				(type default)
			)
			(layer "F.Fab")
		)
		(fp_line
			(start 0.12065 -0.2794)
			(end 0.12065 -0.3048)
			(stroke
				(width 0.1)
				(type default)
			)
			(layer "F.Fab")
		)
		(fp_line
			(start 0.67945 -0.3048)
			(end 0.67945 0.3048)
			(stroke
				(width 0.1)
				(type default)
			)
			(layer "F.Fab")
		)
		(fp_line
			(start 0.67945 0.3048)
			(end 0.120396 0.3048)
			(stroke
				(width 0.1)
				(type default)
			)
			(layer "F.Fab")
		)
		(pad "1" smd circle
			(at -0.40005 0)
			(size 0 0)
			(layers "F.Cu" "F.Mask" "F.Paste")
			(net "P12V_HPDB_0_IMON")
		)
		(pad "2" smd circle
			(at 0.40005 0)
			(size 0 0)
			(layers "F.Cu" "F.Mask" "F.Paste")
			(net "GND")
		)
	)
	(footprint ""
		(layer "F.Cu")
		(at 285.354014 -32.577024 90)
		(property "Reference" "R148"
			(at 0 0 90)
			(layer "F.SilkS")
			(hide yes)
			(effects
				(font
					(size 1.27 1.27)
				)
			)
		)
		(property "Value" ""
			(at 0 0 90)
			(layer "F.Fab")
			(effects
				(font
					(size 1.27 1.27)
				)
			)
		)
		(duplicate_pad_numbers_are_jumpers no)
		(fp_line
			(start 1.651 -0.8382)
			(end 1.651 0.8382)
			(stroke
				(width 0.1524)
				(type default)
			)
			(layer "F.SilkS")
		)
		(fp_line
			(start -1.651 -0.8382)
			(end 1.651 -0.8382)
			(stroke
				(width 0.1524)
				(type default)
			)
			(layer "F.SilkS")
		)
		(fp_line
			(start 1.651 0.8382)
			(end -1.651 0.8382)
			(stroke
				(width 0.1524)
				(type default)
			)
			(layer "F.SilkS")
		)
		(fp_line
			(start -1.651 0.8382)
			(end -1.651 -0.8382)
			(stroke
				(width 0.1524)
				(type default)
			)
			(layer "F.SilkS")
		)
		(fp_line
			(start 1.560576 -0.7366)
			(end 1.524 -0.7366)
			(stroke
				(width 0.1)
				(type default)
			)
			(layer "F.Fab")
		)
		(fp_line
			(start 1.524 -0.7366)
			(end -1.524 -0.7366)
			(stroke
				(width 0.1)
				(type default)
			)
			(layer "F.Fab")
		)
		(fp_line
			(start -1.524 -0.7366)
			(end -1.559814 -0.7366)
			(stroke
				(width 0.1)
				(type default)
			)
			(layer "F.Fab")
		)
		(fp_line
			(start -1.559814 -0.7366)
			(end -1.559814 0.7366)
			(stroke
				(width 0.1)
				(type default)
			)
			(layer "F.Fab")
		)
		(fp_line
			(start 1.560576 0.7366)
			(end 1.560576 -0.7366)
			(stroke
				(width 0.1)
				(type default)
			)
			(layer "F.Fab")
		)
		(fp_line
			(start 1.524 0.7366)
			(end 1.560576 0.7366)
			(stroke
				(width 0.1)
				(type default)
			)
			(layer "F.Fab")
		)
		(fp_line
			(start -1.524 0.7366)
			(end 1.524 0.7366)
			(stroke
				(width 0.1)
				(type default)
			)
			(layer "F.Fab")
		)
		(fp_line
			(start -1.559814 0.7366)
			(end -1.524 0.7366)
			(stroke
				(width 0.1)
				(type default)
			)
			(layer "F.Fab")
		)
		(pad "1" smd rect
			(at -0.94996 0 270)
			(size 1.1176 1.3716)
			(layers "F.Cu" "F.Mask" "F.Paste")
			(net "P52V_HS")
		)
		(pad "2" smd rect
			(at 0.94996 0 270)
			(size 1.1176 1.3716)
			(layers "F.Cu" "F.Mask" "F.Paste")
			(net "PWRGD_P52V_HS1_PG")
		)
	)
	(footprint ""
		(layer "F.Cu")
		(at 69.097906 -127.889)
		(property "Reference" "PC78"
			(at 0 0 0)
			(layer "F.SilkS")
			(hide yes)
			(effects
				(font
					(size 1.27 1.27)
				)
			)
		)
		(property "Value" ""
			(at 0 0 0)
			(layer "F.Fab")
			(effects
				(font
					(size 1.27 1.27)
				)
			)
		)
		(duplicate_pad_numbers_are_jumpers no)
		(fp_line
			(start -2.2098 -0.9398)
			(end 2.2098 -0.9398)
			(stroke
				(width 0.1524)
				(type default)
			)
			(layer "F.SilkS")
		)
		(fp_line
			(start -2.2098 0.9398)
			(end -2.2098 -0.9398)
			(stroke
				(width 0.1524)
				(type default)
			)
			(layer "F.SilkS")
		)
		(fp_line
			(start 2.2098 -0.9398)
			(end 2.2098 0.9398)
			(stroke
				(width 0.1524)
				(type default)
			)
			(layer "F.SilkS")
		)
		(fp_line
			(start 2.2098 0.9398)
			(end -2.2098 0.9398)
			(stroke
				(width 0.1524)
				(type default)
			)
			(layer "F.SilkS")
		)
		(fp_line
			(start -1.700022 -0.899922)
			(end 1.700022 -0.899922)
			(stroke
				(width 0.1)
				(type default)
			)
			(layer "F.Fab")
		)
		(fp_line
			(start -1.700022 0.899922)
			(end -1.700022 -0.899922)
			(stroke
				(width 0.1)
				(type default)
			)
			(layer "F.Fab")
		)
		(fp_line
			(start 1.700022 -0.899922)
			(end 1.700022 0.899922)
			(stroke
				(width 0.1)
				(type default)
			)
			(layer "F.Fab")
		)
		(fp_line
			(start 1.700022 0.899922)
			(end -1.700022 0.899922)
			(stroke
				(width 0.1)
				(type default)
			)
			(layer "F.Fab")
		)
		(pad "1" smd rect
			(at -1.4732 0 180)
			(size 1.1684 1.5748)
			(layers "F.Cu" "F.Mask" "F.Paste")
			(net "P52V_HS_FILTER")
		)
		(pad "2" smd rect
			(at 1.4732 0 180)
			(size 1.1684 1.5748)
			(layers "F.Cu" "F.Mask" "F.Paste")
			(net "GND")
		)
	)
	(footprint ""
		(layer "F.Cu")
		(at 174.879 -9.271 180)
		(property "Reference" "PR89"
			(at 0 0 180)
			(layer "F.SilkS")
			(hide yes)
			(effects
				(font
					(size 1.27 1.27)
				)
			)
		)
		(property "Value" ""
			(at 0 0 180)
			(layer "F.Fab")
			(effects
				(font
					(size 1.27 1.27)
				)
			)
		)
		(duplicate_pad_numbers_are_jumpers no)
		(fp_line
			(start 0.7874 0.4064)
			(end -0.7874 0.4064)
			(stroke
				(width 0.1524)
				(type default)
			)
			(layer "F.SilkS")
		)
		(fp_line
			(start 0.7874 -0.4064)
			(end 0.7874 0.4064)
			(stroke
				(width 0.1524)
				(type default)
			)
			(layer "F.SilkS")
		)
		(fp_line
			(start -0.7874 0.4064)
			(end -0.7874 -0.4064)
			(stroke
				(width 0.1524)
				(type default)
			)
			(layer "F.SilkS")
		)
		(fp_line
			(start -0.7874 -0.4064)
			(end 0.7874 -0.4064)
			(stroke
				(width 0.1524)
				(type default)
			)
			(layer "F.SilkS")
		)
		(fp_line
			(start 0.67945 0.3048)
			(end 0.120396 0.3048)
			(stroke
				(width 0.1)
				(type default)
			)
			(layer "F.Fab")
		)
		(fp_line
			(start 0.67945 -0.3048)
			(end 0.67945 0.3048)
			(stroke
				(width 0.1)
				(type default)
			)
			(layer "F.Fab")
		)
		(fp_line
			(start 0.12065 -0.2794)
			(end 0.12065 -0.3048)
			(stroke
				(width 0.1)
				(type default)
			)
			(layer "F.Fab")
		)
		(fp_line
			(start 0.12065 -0.3048)
			(end 0.67945 -0.3048)
			(stroke
				(width 0.1)
				(type default)
			)
			(layer "F.Fab")
		)
		(fp_line
			(start 0.120396 0.3048)
			(end 0.120396 0.2794)
			(stroke
				(width 0.1)
				(type default)
			)
			(layer "F.Fab")
		)
		(fp_line
			(start 0.120396 0.2794)
			(end -0.12065 0.2794)
			(stroke
				(width 0.1)
				(type default)
			)
			(layer "F.Fab")
		)
		(fp_line
			(start -0.12065 0.3048)
			(end -0.67945 0.3048)
			(stroke
				(width 0.1)
				(type default)
			)
			(layer "F.Fab")
		)
		(fp_line
			(start -0.12065 0.2794)
			(end -0.12065 0.3048)
			(stroke
				(width 0.1)
				(type default)
			)
			(layer "F.Fab")
		)
		(fp_line
			(start -0.12065 -0.2794)
			(end 0.12065 -0.2794)
			(stroke
				(width 0.1)
				(type default)
			)
			(layer "F.Fab")
		)
		(fp_line
			(start -0.12065 -0.305054)
			(end -0.12065 -0.2794)
			(stroke
				(width 0.1)
				(type default)
			)
			(layer "F.Fab")
		)
		(fp_line
			(start -0.67945 0.3048)
			(end -0.67945 -0.305054)
			(stroke
				(width 0.1)
				(type default)
			)
			(layer "F.Fab")
		)
		(fp_line
			(start -0.67945 -0.305054)
			(end -0.12065 -0.305054)
			(stroke
				(width 0.1)
				(type default)
			)
			(layer "F.Fab")
		)
		(pad "1" smd circle
			(at -0.40005 0 180)
			(size 0 0)
			(layers "F.Cu" "F.Mask" "F.Paste")
			(net "P3V3_AUX_CS")
		)
		(pad "2" smd circle
			(at 0.40005 0 180)
			(size 0 0)
			(layers "F.Cu" "F.Mask" "F.Paste")
			(net "GND")
		)
	)
	(footprint ""
		(layer "F.Cu")
		(at 43.19016 -61.93282 90)
		(property "Reference" "R5897"
			(at 0 0 90)
			(layer "F.SilkS")
			(hide yes)
			(effects
				(font
					(size 1.27 1.27)
				)
			)
		)
		(property "Value" ""
			(at 0 0 90)
			(layer "F.Fab")
			(effects
				(font
					(size 1.27 1.27)
				)
			)
		)
		(duplicate_pad_numbers_are_jumpers no)
		(fp_line
			(start 0.7874 -0.4064)
			(end 0.7874 0.4064)
			(stroke
				(width 0.1524)
				(type default)
			)
			(layer "F.SilkS")
		)
		(fp_line
			(start -0.7874 -0.4064)
			(end 0.7874 -0.4064)
			(stroke
				(width 0.1524)
				(type default)
			)
			(layer "F.SilkS")
		)
		(fp_line
			(start 0.7874 0.4064)
			(end -0.7874 0.4064)
			(stroke
				(width 0.1524)
				(type default)
			)
			(layer "F.SilkS")
		)
		(fp_line
			(start -0.7874 0.4064)
			(end -0.7874 -0.4064)
			(stroke
				(width 0.1524)
				(type default)
			)
			(layer "F.SilkS")
		)
		(fp_line
			(start -0.12065 -0.305054)
			(end -0.12065 -0.2794)
			(stroke
				(width 0.1)
				(type default)
			)
			(layer "F.Fab")
		)
		(fp_line
			(start -0.67945 -0.305054)
			(end -0.12065 -0.305054)
			(stroke
				(width 0.1)
				(type default)
			)
			(layer "F.Fab")
		)
		(fp_line
			(start 0.67945 -0.3048)
			(end 0.67945 0.3048)
			(stroke
				(width 0.1)
				(type default)
			)
			(layer "F.Fab")
		)
		(fp_line
			(start 0.12065 -0.3048)
			(end 0.67945 -0.3048)
			(stroke
				(width 0.1)
				(type default)
			)
			(layer "F.Fab")
		)
		(fp_line
			(start 0.12065 -0.2794)
			(end 0.12065 -0.3048)
			(stroke
				(width 0.1)
				(type default)
			)
			(layer "F.Fab")
		)
		(fp_line
			(start -0.12065 -0.2794)
			(end 0.12065 -0.2794)
			(stroke
				(width 0.1)
				(type default)
			)
			(layer "F.Fab")
		)
		(fp_line
			(start 0.120396 0.2794)
			(end -0.12065 0.2794)
			(stroke
				(width 0.1)
				(type default)
			)
			(layer "F.Fab")
		)
		(fp_line
			(start -0.12065 0.2794)
			(end -0.12065 0.3048)
			(stroke
				(width 0.1)
				(type default)
			)
			(layer "F.Fab")
		)
		(fp_line
			(start 0.67945 0.3048)
			(end 0.120396 0.3048)
			(stroke
				(width 0.1)
				(type default)
			)
			(layer "F.Fab")
		)
		(fp_line
			(start 0.120396 0.3048)
			(end 0.120396 0.2794)
			(stroke
				(width 0.1)
				(type default)
			)
			(layer "F.Fab")
		)
		(fp_line
			(start -0.12065 0.3048)
			(end -0.67945 0.3048)
			(stroke
				(width 0.1)
				(type default)
			)
			(layer "F.Fab")
		)
		(fp_line
			(start -0.67945 0.3048)
			(end -0.67945 -0.305054)
			(stroke
				(width 0.1)
				(type default)
			)
			(layer "F.Fab")
		)
		(pad "1" smd circle
			(at -0.40005 0 90)
			(size 0 0)
			(layers "F.Cu" "F.Mask" "F.Paste")
			(net "P12V_HPDB_0_FLTB")
		)
		(pad "2" smd circle
			(at 0.40005 0 90)
			(size 0 0)
			(layers "F.Cu" "F.Mask" "F.Paste")
			(net "P3V3_AUX")
		)
	)
	(footprint ""
		(layer "F.Cu")
		(at 60.452 -61.722)
		(property "Reference" "PC85"
			(at 0 0 0)
			(layer "F.SilkS")
			(hide yes)
			(effects
				(font
					(size 1.27 1.27)
				)
			)
		)
		(property "Value" ""
			(at 0 0 0)
			(layer "F.Fab")
			(effects
				(font
					(size 1.27 1.27)
				)
			)
		)
		(duplicate_pad_numbers_are_jumpers no)
		(fp_line
			(start -0.7874 -0.4064)
			(end 0.7874 -0.4064)
			(stroke
				(width 0.1524)
				(type default)
			)
			(layer "F.SilkS")
		)
		(fp_line
			(start -0.7874 0.4064)
			(end -0.7874 -0.4064)
			(stroke
				(width 0.1524)
				(type default)
			)
			(layer "F.SilkS")
		)
		(fp_line
			(start 0.7874 -0.4064)
			(end 0.7874 0.4064)
			(stroke
				(width 0.1524)
				(type default)
			)
			(layer "F.SilkS")
		)
		(fp_line
			(start 0.7874 0.4064)
			(end -0.7874 0.4064)
			(stroke
				(width 0.1524)
				(type default)
			)
			(layer "F.SilkS")
		)
		(fp_line
			(start -0.6858 -0.3048)
			(end -0.1016 -0.3048)
			(stroke
				(width 0.1)
				(type default)
			)
			(layer "F.Fab")
		)
		(fp_line
			(start -0.6858 0.3048)
			(end -0.6858 -0.3048)
			(stroke
				(width 0.1)
				(type default)
			)
			(layer "F.Fab")
		)
		(fp_line
			(start -0.1016 -0.3048)
			(end -0.1016 -0.2794)
			(stroke
				(width 0.1)
				(type default)
			)
			(layer "F.Fab")
		)
		(fp_line
			(start -0.1016 -0.2794)
			(end 0.1016 -0.2794)
			(stroke
				(width 0.1)
				(type default)
			)
			(layer "F.Fab")
		)
		(fp_line
			(start -0.1016 0.2794)
			(end -0.1016 0.3048)
			(stroke
				(width 0.1)
				(type default)
			)
			(layer "F.Fab")
		)
		(fp_line
			(start -0.1016 0.3048)
			(end -0.6858 0.3048)
			(stroke
				(width 0.1)
				(type default)
			)
			(layer "F.Fab")
		)
		(fp_line
			(start 0.1016 -0.3048)
			(end 0.6858 -0.3048)
			(stroke
				(width 0.1)
				(type default)
			)
			(layer "F.Fab")
		)
		(fp_line
			(start 0.1016 -0.2794)
			(end 0.1016 -0.3048)
			(stroke
				(width 0.1)
				(type default)
			)
			(layer "F.Fab")
		)
		(fp_line
			(start 0.1016 0.2794)
			(end -0.1016 0.2794)
			(stroke
				(width 0.1)
				(type default)
			)
			(layer "F.Fab")
		)
		(fp_line
			(start 0.1016 0.3048)
			(end 0.1016 0.2794)
			(stroke
				(width 0.1)
				(type default)
			)
			(layer "F.Fab")
		)
		(fp_line
			(start 0.6858 -0.3048)
			(end 0.6858 0.3048)
			(stroke
				(width 0.1)
				(type default)
			)
			(layer "F.Fab")
		)
		(fp_line
			(start 0.6858 0.3048)
			(end 0.1016 0.3048)
			(stroke
				(width 0.1)
				(type default)
			)
			(layer "F.Fab")
		)
		(pad "1" smd rect
			(at -0.40005 0 180)
			(size 0.4572 0.508)
			(layers "F.Cu" "F.Mask" "F.Paste")
			(net "P12V_BRICK")
		)
		(pad "2" smd rect
			(at 0.40005 0 180)
			(size 0.4572 0.508)
			(layers "F.Cu" "F.Mask" "F.Paste")
			(net "GND")
		)
	)
	(footprint ""
		(layer "F.Cu")
		(at 84.582 -51.943)
		(property "Reference" "PC90"
			(at 0 0 0)
			(layer "F.SilkS")
			(hide yes)
			(effects
				(font
					(size 1.27 1.27)
				)
			)
		)
		(property "Value" ""
			(at 0 0 0)
			(layer "F.Fab")
			(effects
				(font
					(size 1.27 1.27)
				)
			)
		)
		(duplicate_pad_numbers_are_jumpers no)
		(fp_line
			(start -1.524 -0.762)
			(end 1.524 -0.762)
			(stroke
				(width 0.1524)
				(type default)
			)
			(layer "F.SilkS")
		)
		(fp_line
			(start -1.524 0.762)
			(end -1.524 -0.762)
			(stroke
				(width 0.1524)
				(type default)
			)
			(layer "F.SilkS")
		)
		(fp_line
			(start 1.524 -0.762)
			(end 1.524 0.762)
			(stroke
				(width 0.1524)
				(type default)
			)
			(layer "F.SilkS")
		)
		(fp_line
			(start 1.524 0.762)
			(end -1.524 0.762)
			(stroke
				(width 0.1524)
				(type default)
			)
			(layer "F.SilkS")
		)
		(fp_line
			(start -1.1049 -0.724916)
			(end -1.1049 0.724916)
			(stroke
				(width 0.1)
				(type default)
			)
			(layer "F.Fab")
		)
		(fp_line
			(start -1.1049 0.724916)
			(end 1.1049 0.724916)
			(stroke
				(width 0.1)
				(type default)
			)
			(layer "F.Fab")
		)
		(fp_line
			(start 1.1049 -0.724916)
			(end -1.1049 -0.724916)
			(stroke
				(width 0.1)
				(type default)
			)
			(layer "F.Fab")
		)
		(fp_line
			(start 1.1049 0.724916)
			(end 1.1049 -0.724916)
			(stroke
				(width 0.1)
				(type default)
			)
			(layer "F.Fab")
		)
		(pad "1" smd rect
			(at -0.889 0 180)
			(size 1.016 1.27)
			(layers "F.Cu" "F.Mask" "F.Paste")
			(net "P12V_BRICK")
		)
		(pad "2" smd rect
			(at 0.889 0 180)
			(size 1.016 1.27)
			(layers "F.Cu" "F.Mask" "F.Paste")
			(net "GND")
		)
	)
	(footprint ""
		(layer "F.Cu")
		(at 224.259394 -130.31978 180)
		(property "Reference" "L3"
			(at -5.568442 -7.377176 0)
			(unlocked yes)
			(layer "F.SilkS")
			(effects
				(font
					(size 0.7874 0.5842)
					(thickness 0.1524)
				)
				(justify left)
			)
		)
		(property "Value" ""
			(at 0 0 180)
			(layer "F.Fab")
			(effects
				(font
					(size 1.27 1.27)
				)
			)
		)
		(duplicate_pad_numbers_are_jumpers no)
		(fp_line
			(start 6.849872 6.450076)
			(end 6.849872 2.6416)
			(stroke
				(width 0.1524)
				(type default)
			)
			(layer "F.SilkS")
		)
		(fp_line
			(start 6.849872 -2.6416)
			(end 6.849872 -6.450076)
			(stroke
				(width 0.1524)
				(type default)
			)
			(layer "F.SilkS")
		)
		(fp_line
			(start 6.849872 -6.450076)
			(end -6.849872 -6.450076)
			(stroke
				(width 0.1524)
				(type default)
			)
			(layer "F.SilkS")
		)
		(fp_line
			(start -6.849872 6.450076)
			(end 6.849872 6.450076)
			(stroke
				(width 0.1524)
				(type default)
			)
			(layer "F.SilkS")
		)
		(fp_line
			(start -6.849872 2.6416)
			(end -6.849872 6.450076)
			(stroke
				(width 0.1524)
				(type default)
			)
			(layer "F.SilkS")
		)
		(fp_line
			(start -6.849872 -6.450076)
			(end -6.849872 -2.6416)
			(stroke
				(width 0.1524)
				(type default)
			)
			(layer "F.SilkS")
		)
		(fp_line
			(start 6.849872 6.450076)
			(end 6.849872 -6.450076)
			(stroke
				(width 0.1)
				(type default)
			)
			(layer "F.Fab")
		)
		(fp_line
			(start 6.849872 -6.450076)
			(end -6.849872 -6.450076)
			(stroke
				(width 0.1)
				(type default)
			)
			(layer "F.Fab")
		)
		(fp_line
			(start -6.849872 6.450076)
			(end 6.849872 6.450076)
			(stroke
				(width 0.1)
				(type default)
			)
			(layer "F.Fab")
		)
		(fp_line
			(start -6.849872 -6.450076)
			(end -6.849872 6.450076)
			(stroke
				(width 0.1)
				(type default)
			)
			(layer "F.Fab")
		)
		(pad "1" smd rect
			(at -5.407406 0 180)
			(size 2.9464 5.0038)
			(layers "F.Cu" "F.Mask" "F.Paste")
			(net "P52V_HS")
		)
		(pad "2" smd rect
			(at 5.407406 0 180)
			(size 2.9464 5.0038)
			(layers "F.Cu" "F.Mask" "F.Paste")
			(net "P52V_HS_FILTER")
		)
	)
	(footprint ""
		(layer "F.Cu")
		(at 90.678 -60.96)
		(property "Reference" "PC96"
			(at -1.397 -3.52933 0)
			(unlocked yes)
			(layer "F.SilkS")
			(effects
				(font
					(size 0.7874 0.5842)
					(thickness 0.1524)
				)
				(justify left)
			)
		)
		(property "Value" ""
			(at 0 0 0)
			(layer "F.Fab")
			(effects
				(font
					(size 1.27 1.27)
				)
			)
		)
		(duplicate_pad_numbers_are_jumpers no)
		(fp_line
			(start 5.2578 2.499868)
			(end -5.2578 2.499868)
			(stroke
				(width 0.1524)
				(type default)
			)
			(layer "F.SilkS")
		)
		(fp_circle
			(center 0 2.499868)
			(end 5.2578 2.499868)
			(stroke
				(width 0.1524)
				(type default)
			)
			(fill no)
			(layer "F.SilkS")
		)
		(fp_poly
			(pts
				(arc
					(start 5.2578 2.499868)
					(mid 0 7.757922)
					(end -5.2578 2.499868)
				)
			)
			(stroke
				(width 0)
				(type default)
			)
			(fill yes)
			(layer "F.SilkS")
		)
		(fp_circle
			(center 0 2.499868)
			(end 5.2578 2.499868)
			(stroke
				(width 0.1)
				(type default)
			)
			(fill no)
			(layer "F.Fab")
		)
		(pad "1" thru_hole rect
			(at 0 0 270)
			(size 1.524 1.524)
			(drill 1.016)
			(layers "*.Cu" "*.Mask")
			(remove_unused_layers no)
			(net "P12V_BRICK")
			(clearance 0)
			(padstack
				(mode front_inner_back)
				(layer "Inner"
					(shape circle)
					(size 1.524 1.524)
					(clearance 0)
				)
				(layer "B.Cu"
					(shape rect)
					(size 1.524 1.524)
					(clearance 0)
				)
			)
		)
		(pad "2" thru_hole circle
			(at 0 4.99999 270)
			(size 1.524 1.524)
			(drill 1.016)
			(layers "*.Cu" "*.Mask")
			(remove_unused_layers no)
			(net "GND")
			(clearance 0)
		)
	)
	(footprint ""
		(layer "F.Cu")
		(at 301.625 -121.4755)
		(property "Reference" "PR6963"
			(at 0 0 0)
			(layer "F.SilkS")
			(hide yes)
			(effects
				(font
					(size 1.27 1.27)
				)
			)
		)
		(property "Value" ""
			(at 0 0 0)
			(layer "F.Fab")
			(effects
				(font
					(size 1.27 1.27)
				)
			)
		)
		(duplicate_pad_numbers_are_jumpers no)
		(fp_line
			(start -1.2954 -0.5842)
			(end 1.2954 -0.5842)
			(stroke
				(width 0.1524)
				(type default)
			)
			(layer "F.SilkS")
		)
		(fp_line
			(start -1.2954 0.5842)
			(end -1.2954 -0.5842)
			(stroke
				(width 0.1524)
				(type default)
			)
			(layer "F.SilkS")
		)
		(fp_line
			(start 1.2954 -0.5842)
			(end 1.2954 0.5842)
			(stroke
				(width 0.1524)
				(type default)
			)
			(layer "F.SilkS")
		)
		(fp_line
			(start 1.2954 0.5842)
			(end -1.2954 0.5842)
			(stroke
				(width 0.1524)
				(type default)
			)
			(layer "F.SilkS")
		)
		(fp_line
			(start -1.1938 -0.406654)
			(end -0.8636 -0.406654)
			(stroke
				(width 0.1)
				(type default)
			)
			(layer "F.Fab")
		)
		(fp_line
			(start -1.1938 0.4064)
			(end -1.1938 -0.406654)
			(stroke
				(width 0.1)
				(type default)
			)
			(layer "F.Fab")
		)
		(fp_line
			(start -0.8636 -0.4572)
			(end 0.8636 -0.4572)
			(stroke
				(width 0.1)
				(type default)
			)
			(layer "F.Fab")
		)
		(fp_line
			(start -0.8636 -0.406654)
			(end -0.8636 -0.4572)
			(stroke
				(width 0.1)
				(type default)
			)
			(layer "F.Fab")
		)
		(fp_line
			(start -0.8636 0.4064)
			(end -1.1938 0.4064)
			(stroke
				(width 0.1)
				(type default)
			)
			(layer "F.Fab")
		)
		(fp_line
			(start -0.8636 0.4318)
			(end -0.8636 0.4064)
			(stroke
				(width 0.1)
				(type default)
			)
			(layer "F.Fab")
		)
		(fp_line
			(start -0.8636 0.4572)
			(end -0.8636 0.4318)
			(stroke
				(width 0.1)
				(type default)
			)
			(layer "F.Fab")
		)
		(fp_line
			(start 0.8636 -0.4572)
			(end 0.8636 -0.406654)
			(stroke
				(width 0.1)
				(type default)
			)
			(layer "F.Fab")
		)
		(fp_line
			(start 0.8636 -0.406654)
			(end 1.1938 -0.406654)
			(stroke
				(width 0.1)
				(type default)
			)
			(layer "F.Fab")
		)
		(fp_line
			(start 0.8636 0.4064)
			(end 0.8636 0.4572)
			(stroke
				(width 0.1)
				(type default)
			)
			(layer "F.Fab")
		)
		(fp_line
			(start 0.8636 0.4572)
			(end -0.8636 0.4572)
			(stroke
				(width 0.1)
				(type default)
			)
			(layer "F.Fab")
		)
		(fp_line
			(start 1.1938 -0.406654)
			(end 1.1938 0.4064)
			(stroke
				(width 0.1)
				(type default)
			)
			(layer "F.Fab")
		)
		(fp_line
			(start 1.1938 0.4064)
			(end 0.8636 0.4064)
			(stroke
				(width 0.1)
				(type default)
			)
			(layer "F.Fab")
		)
		(pad "1" smd rect
			(at -0.7366 0 270)
			(size 0.7112 0.8128)
			(layers "F.Cu" "F.Mask" "F.Paste")
			(net "P52V_HS_4287_ADC_P")
		)
		(pad "2" smd rect
			(at 0.7366 0 270)
			(size 0.7112 0.8128)
			(layers "F.Cu" "F.Mask" "F.Paste")
			(net "P52V_HS1_SENSE_P_R1")
		)
	)
	(footprint ""
		(layer "F.Cu")
		(at 179.06746 -49.911)
		(property "Reference" "PC132"
			(at 0 0 0)
			(layer "F.SilkS")
			(hide yes)
			(effects
				(font
					(size 1.27 1.27)
				)
			)
		)
		(property "Value" ""
			(at 0 0 0)
			(layer "F.Fab")
			(effects
				(font
					(size 1.27 1.27)
				)
			)
		)
		(duplicate_pad_numbers_are_jumpers no)
		(fp_line
			(start -1.524 -0.762)
			(end 1.524 -0.762)
			(stroke
				(width 0.1524)
				(type default)
			)
			(layer "F.SilkS")
		)
		(fp_line
			(start -1.524 0.762)
			(end -1.524 -0.762)
			(stroke
				(width 0.1524)
				(type default)
			)
			(layer "F.SilkS")
		)
		(fp_line
			(start 1.524 -0.762)
			(end 1.524 0.762)
			(stroke
				(width 0.1524)
				(type default)
			)
			(layer "F.SilkS")
		)
		(fp_line
			(start 1.524 0.762)
			(end -1.524 0.762)
			(stroke
				(width 0.1524)
				(type default)
			)
			(layer "F.SilkS")
		)
		(fp_line
			(start -1.1049 -0.724916)
			(end -1.1049 0.724916)
			(stroke
				(width 0.1)
				(type default)
			)
			(layer "F.Fab")
		)
		(fp_line
			(start -1.1049 0.724916)
			(end 1.1049 0.724916)
			(stroke
				(width 0.1)
				(type default)
			)
			(layer "F.Fab")
		)
		(fp_line
			(start 1.1049 -0.724916)
			(end -1.1049 -0.724916)
			(stroke
				(width 0.1)
				(type default)
			)
			(layer "F.Fab")
		)
		(fp_line
			(start 1.1049 0.724916)
			(end 1.1049 -0.724916)
			(stroke
				(width 0.1)
				(type default)
			)
			(layer "F.Fab")
		)
		(pad "1" smd rect
			(at -0.889 0 180)
			(size 1.016 1.27)
			(layers "F.Cu" "F.Mask" "F.Paste")
			(net "P12V_BRICK")
		)
		(pad "2" smd rect
			(at 0.889 0 180)
			(size 1.016 1.27)
			(layers "F.Cu" "F.Mask" "F.Paste")
			(net "GND")
		)
	)
	(footprint ""
		(layer "F.Cu")
		(at 189.098174 -127.889)
		(property "Reference" "PC119"
			(at 0 0 0)
			(layer "F.SilkS")
			(hide yes)
			(effects
				(font
					(size 1.27 1.27)
				)
			)
		)
		(property "Value" ""
			(at 0 0 0)
			(layer "F.Fab")
			(effects
				(font
					(size 1.27 1.27)
				)
			)
		)
		(duplicate_pad_numbers_are_jumpers no)
		(fp_line
			(start -2.2098 -0.9398)
			(end 2.2098 -0.9398)
			(stroke
				(width 0.1524)
				(type default)
			)
			(layer "F.SilkS")
		)
		(fp_line
			(start -2.2098 0.9398)
			(end -2.2098 -0.9398)
			(stroke
				(width 0.1524)
				(type default)
			)
			(layer "F.SilkS")
		)
		(fp_line
			(start 2.2098 -0.9398)
			(end 2.2098 0.9398)
			(stroke
				(width 0.1524)
				(type default)
			)
			(layer "F.SilkS")
		)
		(fp_line
			(start 2.2098 0.9398)
			(end -2.2098 0.9398)
			(stroke
				(width 0.1524)
				(type default)
			)
			(layer "F.SilkS")
		)
		(fp_line
			(start -1.700022 -0.899922)
			(end 1.700022 -0.899922)
			(stroke
				(width 0.1)
				(type default)
			)
			(layer "F.Fab")
		)
		(fp_line
			(start -1.700022 0.899922)
			(end -1.700022 -0.899922)
			(stroke
				(width 0.1)
				(type default)
			)
			(layer "F.Fab")
		)
		(fp_line
			(start 1.700022 -0.899922)
			(end 1.700022 0.899922)
			(stroke
				(width 0.1)
				(type default)
			)
			(layer "F.Fab")
		)
		(fp_line
			(start 1.700022 0.899922)
			(end -1.700022 0.899922)
			(stroke
				(width 0.1)
				(type default)
			)
			(layer "F.Fab")
		)
		(pad "1" smd rect
			(at -1.4732 0 180)
			(size 1.1684 1.5748)
			(layers "F.Cu" "F.Mask" "F.Paste")
			(net "P52V_HS_FILTER")
		)
		(pad "2" smd rect
			(at 1.4732 0 180)
			(size 1.1684 1.5748)
			(layers "F.Cu" "F.Mask" "F.Paste")
			(net "GND")
		)
	)
	(footprint ""
		(layer "F.Cu")
		(at 236.982 -95.504 -90)
		(property "Reference" "C41"
			(at 0 0 270)
			(layer "F.SilkS")
			(hide yes)
			(effects
				(font
					(size 1.27 1.27)
				)
			)
		)
		(property "Value" ""
			(at 0 0 270)
			(layer "F.Fab")
			(effects
				(font
					(size 1.27 1.27)
				)
			)
		)
		(duplicate_pad_numbers_are_jumpers no)
		(fp_line
			(start -2.2098 0.9398)
			(end -2.2098 -0.9398)
			(stroke
				(width 0.1524)
				(type default)
			)
			(layer "F.SilkS")
		)
		(fp_line
			(start 2.2098 0.9398)
			(end -2.2098 0.9398)
			(stroke
				(width 0.1524)
				(type default)
			)
			(layer "F.SilkS")
		)
		(fp_line
			(start -2.2098 -0.9398)
			(end 2.2098 -0.9398)
			(stroke
				(width 0.1524)
				(type default)
			)
			(layer "F.SilkS")
		)
		(fp_line
			(start 2.2098 -0.9398)
			(end 2.2098 0.9398)
			(stroke
				(width 0.1524)
				(type default)
			)
			(layer "F.SilkS")
		)
		(fp_line
			(start -1.700022 0.899922)
			(end -1.700022 -0.899922)
			(stroke
				(width 0.1)
				(type default)
			)
			(layer "F.Fab")
		)
		(fp_line
			(start 1.700022 0.899922)
			(end -1.700022 0.899922)
			(stroke
				(width 0.1)
				(type default)
			)
			(layer "F.Fab")
		)
		(fp_line
			(start -1.700022 -0.899922)
			(end 1.700022 -0.899922)
			(stroke
				(width 0.1)
				(type default)
			)
			(layer "F.Fab")
		)
		(fp_line
			(start 1.700022 -0.899922)
			(end 1.700022 0.899922)
			(stroke
				(width 0.1)
				(type default)
			)
			(layer "F.Fab")
		)
		(pad "1" smd rect
			(at -1.4732 0 90)
			(size 1.1684 1.5748)
			(layers "F.Cu" "F.Mask" "F.Paste")
			(net "P52V_HS")
		)
		(pad "2" smd rect
			(at 1.4732 0 90)
			(size 1.1684 1.5748)
			(layers "F.Cu" "F.Mask" "F.Paste")
			(net "GND")
		)
	)
	(footprint ""
		(layer "F.Cu")
		(at 285.995872 -57.92724)
		(property "Reference" "PQ15"
			(at -1.905 -2.25933 0)
			(unlocked yes)
			(layer "F.SilkS")
			(effects
				(font
					(size 0.7874 0.5842)
					(thickness 0.1524)
				)
				(justify left)
			)
		)
		(property "Value" ""
			(at 0 0 0)
			(layer "F.Fab")
			(effects
				(font
					(size 1.27 1.27)
				)
			)
		)
		(duplicate_pad_numbers_are_jumpers no)
		(fp_line
			(start -1.905 -1.651)
			(end 1.905 -1.651)
			(stroke
				(width 0.1524)
				(type default)
			)
			(layer "F.SilkS")
		)
		(fp_line
			(start -1.905 1.651)
			(end -1.905 -1.651)
			(stroke
				(width 0.1524)
				(type default)
			)
			(layer "F.SilkS")
		)
		(fp_line
			(start 1.905 -1.651)
			(end 1.905 1.651)
			(stroke
				(width 0.1524)
				(type default)
			)
			(layer "F.SilkS")
		)
		(fp_line
			(start 1.905 1.651)
			(end -1.905 1.651)
			(stroke
				(width 0.1524)
				(type default)
			)
			(layer "F.SilkS")
		)
		(fp_line
			(start -1.249934 -1.169924)
			(end -0.649986 -1.169924)
			(stroke
				(width 0.1)
				(type default)
			)
			(layer "F.Fab")
		)
		(fp_line
			(start -1.249934 -0.729996)
			(end -1.249934 -1.169924)
			(stroke
				(width 0.1)
				(type default)
			)
			(layer "F.Fab")
		)
		(fp_line
			(start -1.249934 0.729996)
			(end -0.6985 0.729996)
			(stroke
				(width 0.1)
				(type default)
			)
			(layer "F.Fab")
		)
		(fp_line
			(start -1.249934 1.169924)
			(end -1.249934 0.729996)
			(stroke
				(width 0.1)
				(type default)
			)
			(layer "F.Fab")
		)
		(fp_line
			(start -0.6985 -0.729996)
			(end -1.249934 -0.729996)
			(stroke
				(width 0.1)
				(type default)
			)
			(layer "F.Fab")
		)
		(fp_line
			(start -0.6985 0.729996)
			(end -0.6985 -0.729996)
			(stroke
				(width 0.1)
				(type default)
			)
			(layer "F.Fab")
		)
		(fp_line
			(start -0.649986 -1.524)
			(end 0.6985 -1.524)
			(stroke
				(width 0.1)
				(type default)
			)
			(layer "F.Fab")
		)
		(fp_line
			(start -0.649986 -1.169924)
			(end -0.649986 -1.524)
			(stroke
				(width 0.1)
				(type default)
			)
			(layer "F.Fab")
		)
		(fp_line
			(start -0.649986 1.169924)
			(end -1.249934 1.169924)
			(stroke
				(width 0.1)
				(type default)
			)
			(layer "F.Fab")
		)
		(fp_line
			(start -0.649986 1.524)
			(end -0.649986 1.169924)
			(stroke
				(width 0.1)
				(type default)
			)
			(layer "F.Fab")
		)
		(fp_line
			(start 0.6985 -1.524)
			(end 0.6985 -0.219964)
			(stroke
				(width 0.1)
				(type default)
			)
			(layer "F.Fab")
		)
		(fp_line
			(start 0.6985 -0.219964)
			(end 1.249934 -0.219964)
			(stroke
				(width 0.1)
				(type default)
			)
			(layer "F.Fab")
		)
		(fp_line
			(start 0.6985 0.219964)
			(end 0.6985 1.524)
			(stroke
				(width 0.1)
				(type default)
			)
			(layer "F.Fab")
		)
		(fp_line
			(start 0.6985 1.524)
			(end -0.649986 1.524)
			(stroke
				(width 0.1)
				(type default)
			)
			(layer "F.Fab")
		)
		(fp_line
			(start 1.249934 -0.219964)
			(end 1.249934 0.219964)
			(stroke
				(width 0.1)
				(type default)
			)
			(layer "F.Fab")
		)
		(fp_line
			(start 1.249934 0.219964)
			(end 0.6985 0.219964)
			(stroke
				(width 0.1)
				(type default)
			)
			(layer "F.Fab")
		)
		(pad "B" smd rect
			(at -1.1176 -1.016 270)
			(size 1.016 1.27)
			(layers "F.Cu" "F.Mask" "F.Paste")
			(net "P52V_HS1_TEMP_R")
		)
		(pad "C" smd rect
			(at 1.1176 0 270)
			(size 1.016 1.27)
			(layers "F.Cu" "F.Mask" "F.Paste")
			(net "P52V_HS1_TEMP_R")
		)
		(pad "E" smd rect
			(at -1.1176 1.016 270)
			(size 1.016 1.27)
			(layers "F.Cu" "F.Mask" "F.Paste")
			(net "P52V_HS1_TEMPN_R")
		)
	)
	(footprint ""
		(layer "F.Cu")
		(at 259.334 -24.892 180)
		(property "Reference" "PR92"
			(at 0 0 180)
			(layer "F.SilkS")
			(hide yes)
			(effects
				(font
					(size 1.27 1.27)
				)
			)
		)
		(property "Value" ""
			(at 0 0 180)
			(layer "F.Fab")
			(effects
				(font
					(size 1.27 1.27)
				)
			)
		)
		(duplicate_pad_numbers_are_jumpers no)
		(fp_line
			(start 0.7874 0.4064)
			(end -0.7874 0.4064)
			(stroke
				(width 0.1524)
				(type default)
			)
			(layer "F.SilkS")
		)
		(fp_line
			(start 0.7874 -0.4064)
			(end 0.7874 0.4064)
			(stroke
				(width 0.1524)
				(type default)
			)
			(layer "F.SilkS")
		)
		(fp_line
			(start -0.7874 0.4064)
			(end -0.7874 -0.4064)
			(stroke
				(width 0.1524)
				(type default)
			)
			(layer "F.SilkS")
		)
		(fp_line
			(start -0.7874 -0.4064)
			(end 0.7874 -0.4064)
			(stroke
				(width 0.1524)
				(type default)
			)
			(layer "F.SilkS")
		)
		(fp_line
			(start 0.67945 0.3048)
			(end 0.120396 0.3048)
			(stroke
				(width 0.1)
				(type default)
			)
			(layer "F.Fab")
		)
		(fp_line
			(start 0.67945 -0.3048)
			(end 0.67945 0.3048)
			(stroke
				(width 0.1)
				(type default)
			)
			(layer "F.Fab")
		)
		(fp_line
			(start 0.12065 -0.2794)
			(end 0.12065 -0.3048)
			(stroke
				(width 0.1)
				(type default)
			)
			(layer "F.Fab")
		)
		(fp_line
			(start 0.12065 -0.3048)
			(end 0.67945 -0.3048)
			(stroke
				(width 0.1)
				(type default)
			)
			(layer "F.Fab")
		)
		(fp_line
			(start 0.120396 0.3048)
			(end 0.120396 0.2794)
			(stroke
				(width 0.1)
				(type default)
			)
			(layer "F.Fab")
		)
		(fp_line
			(start 0.120396 0.2794)
			(end -0.12065 0.2794)
			(stroke
				(width 0.1)
				(type default)
			)
			(layer "F.Fab")
		)
		(fp_line
			(start -0.12065 0.3048)
			(end -0.67945 0.3048)
			(stroke
				(width 0.1)
				(type default)
			)
			(layer "F.Fab")
		)
		(fp_line
			(start -0.12065 0.2794)
			(end -0.12065 0.3048)
			(stroke
				(width 0.1)
				(type default)
			)
			(layer "F.Fab")
		)
		(fp_line
			(start -0.12065 -0.2794)
			(end 0.12065 -0.2794)
			(stroke
				(width 0.1)
				(type default)
			)
			(layer "F.Fab")
		)
		(fp_line
			(start -0.12065 -0.305054)
			(end -0.12065 -0.2794)
			(stroke
				(width 0.1)
				(type default)
			)
			(layer "F.Fab")
		)
		(fp_line
			(start -0.67945 0.3048)
			(end -0.67945 -0.305054)
			(stroke
				(width 0.1)
				(type default)
			)
			(layer "F.Fab")
		)
		(fp_line
			(start -0.67945 -0.305054)
			(end -0.12065 -0.305054)
			(stroke
				(width 0.1)
				(type default)
			)
			(layer "F.Fab")
		)
		(pad "1" smd circle
			(at -0.40005 0 180)
			(size 0 0)
			(layers "F.Cu" "F.Mask" "F.Paste")
			(net "SMB_P52V_HSC_SDA")
		)
		(pad "2" smd circle
			(at 0.40005 0 180)
			(size 0 0)
			(layers "F.Cu" "F.Mask" "F.Paste")
			(net "SMB_P52V_VPDB_DEBUG_SDA")
		)
	)
	(footprint ""
		(layer "F.Cu")
		(at 42.046906 -136.906 90)
		(property "Reference" "PC73"
			(at 6.06933 1.133094 0)
			(unlocked yes)
			(layer "F.SilkS")
			(effects
				(font
					(size 0.7874 0.5842)
					(thickness 0.1524)
				)
				(justify left)
			)
		)
		(property "Value" ""
			(at 0 0 90)
			(layer "F.Fab")
			(effects
				(font
					(size 1.27 1.27)
				)
			)
		)
		(duplicate_pad_numbers_are_jumpers no)
		(fp_line
			(start 5.2578 2.499868)
			(end -5.2578 2.499868)
			(stroke
				(width 0.1524)
				(type default)
			)
			(layer "F.SilkS")
		)
		(fp_circle
			(center 0 2.500122)
			(end 0 7.758176)
			(stroke
				(width 0.1524)
				(type default)
			)
			(fill no)
			(layer "F.SilkS")
		)
		(fp_poly
			(pts
				(arc
					(start 5.2578 2.499868)
					(mid 0 7.757922)
					(end -5.2578 2.499868)
				)
			)
			(stroke
				(width 0)
				(type default)
			)
			(fill yes)
			(layer "F.SilkS")
		)
		(fp_circle
			(center 0 2.500122)
			(end 0 7.758176)
			(stroke
				(width 0.1)
				(type default)
			)
			(fill no)
			(layer "F.Fab")
		)
		(pad "1" thru_hole rect
			(at 0 0)
			(size 1.5748 1.5748)
			(drill 1.0668)
			(layers "*.Cu" "*.Mask")
			(remove_unused_layers no)
			(net "P52V_HS_FILTER")
			(clearance 0)
			(padstack
				(mode front_inner_back)
				(layer "Inner"
					(shape circle)
					(size 1.5748 1.5748)
					(clearance 0)
				)
				(layer "B.Cu"
					(shape rect)
					(size 1.5748 1.5748)
					(clearance 0)
				)
			)
		)
		(pad "2" thru_hole circle
			(at 0 4.99999)
			(size 1.5748 1.5748)
			(drill 1.0668)
			(layers "*.Cu" "*.Mask")
			(remove_unused_layers no)
			(net "GND")
			(clearance 0)
		)
	)
	(footprint ""
		(layer "F.Cu")
		(at 38.6588 -60.5282 -90)
		(property "Reference" "C95"
			(at 0 0 270)
			(layer "F.SilkS")
			(hide yes)
			(effects
				(font
					(size 1.27 1.27)
				)
			)
		)
		(property "Value" ""
			(at 0 0 270)
			(layer "F.Fab")
			(effects
				(font
					(size 1.27 1.27)
				)
			)
		)
		(duplicate_pad_numbers_are_jumpers no)
		(fp_line
			(start -1.2954 0.5842)
			(end -1.2954 -0.5842)
			(stroke
				(width 0.1524)
				(type default)
			)
			(layer "F.SilkS")
		)
		(fp_line
			(start 1.2954 0.5842)
			(end -1.2954 0.5842)
			(stroke
				(width 0.1524)
				(type default)
			)
			(layer "F.SilkS")
		)
		(fp_line
			(start -1.2954 -0.5842)
			(end 1.2954 -0.5842)
			(stroke
				(width 0.1524)
				(type default)
			)
			(layer "F.SilkS")
		)
		(fp_line
			(start 1.2954 -0.5842)
			(end 1.2954 0.5842)
			(stroke
				(width 0.1524)
				(type default)
			)
			(layer "F.SilkS")
		)
		(fp_line
			(start -0.8636 0.4572)
			(end -0.8636 0.4064)
			(stroke
				(width 0.1)
				(type default)
			)
			(layer "F.Fab")
		)
		(fp_line
			(start 0.8636 0.4572)
			(end -0.8636 0.4572)
			(stroke
				(width 0.1)
				(type default)
			)
			(layer "F.Fab")
		)
		(fp_line
			(start -1.1938 0.4064)
			(end -1.1938 -0.4064)
			(stroke
				(width 0.1)
				(type default)
			)
			(layer "F.Fab")
		)
		(fp_line
			(start -0.8636 0.4064)
			(end -1.1938 0.4064)
			(stroke
				(width 0.1)
				(type default)
			)
			(layer "F.Fab")
		)
		(fp_line
			(start 0.8636 0.4064)
			(end 0.8636 0.4572)
			(stroke
				(width 0.1)
				(type default)
			)
			(layer "F.Fab")
		)
		(fp_line
			(start 1.1938 0.4064)
			(end 0.8636 0.4064)
			(stroke
				(width 0.1)
				(type default)
			)
			(layer "F.Fab")
		)
		(fp_line
			(start -1.1938 -0.4064)
			(end -0.8636 -0.4064)
			(stroke
				(width 0.1)
				(type default)
			)
			(layer "F.Fab")
		)
		(fp_line
			(start -0.8636 -0.4064)
			(end -0.8636 -0.4572)
			(stroke
				(width 0.1)
				(type default)
			)
			(layer "F.Fab")
		)
		(fp_line
			(start 0.8636 -0.4064)
			(end 1.1938 -0.4064)
			(stroke
				(width 0.1)
				(type default)
			)
			(layer "F.Fab")
		)
		(fp_line
			(start 1.1938 -0.4064)
			(end 1.1938 0.4064)
			(stroke
				(width 0.1)
				(type default)
			)
			(layer "F.Fab")
		)
		(fp_line
			(start -0.8636 -0.4572)
			(end 0.8636 -0.4572)
			(stroke
				(width 0.1)
				(type default)
			)
			(layer "F.Fab")
		)
		(fp_line
			(start 0.8636 -0.4572)
			(end 0.8636 -0.4064)
			(stroke
				(width 0.1)
				(type default)
			)
			(layer "F.Fab")
		)
		(pad "1" smd rect
			(at -0.7366 0 180)
			(size 0.7112 0.8128)
			(layers "F.Cu" "F.Mask" "F.Paste")
			(net "GND")
		)
		(pad "2" smd rect
			(at 0.7366 0 180)
			(size 0.7112 0.8128)
			(layers "F.Cu" "F.Mask" "F.Paste")
			(net "P12V_HPDB_0_PD")
		)
	)
	(footprint ""
		(layer "F.Cu")
		(at 136.906 -127.889)
		(property "Reference" "PC20"
			(at 0 0 0)
			(layer "F.SilkS")
			(hide yes)
			(effects
				(font
					(size 1.27 1.27)
				)
			)
		)
		(property "Value" ""
			(at 0 0 0)
			(layer "F.Fab")
			(effects
				(font
					(size 1.27 1.27)
				)
			)
		)
		(duplicate_pad_numbers_are_jumpers no)
		(fp_line
			(start -2.2098 -0.9398)
			(end 2.2098 -0.9398)
			(stroke
				(width 0.1524)
				(type default)
			)
			(layer "F.SilkS")
		)
		(fp_line
			(start -2.2098 0.9398)
			(end -2.2098 -0.9398)
			(stroke
				(width 0.1524)
				(type default)
			)
			(layer "F.SilkS")
		)
		(fp_line
			(start 2.2098 -0.9398)
			(end 2.2098 0.9398)
			(stroke
				(width 0.1524)
				(type default)
			)
			(layer "F.SilkS")
		)
		(fp_line
			(start 2.2098 0.9398)
			(end -2.2098 0.9398)
			(stroke
				(width 0.1524)
				(type default)
			)
			(layer "F.SilkS")
		)
		(fp_line
			(start -1.700022 -0.899922)
			(end 1.700022 -0.899922)
			(stroke
				(width 0.1)
				(type default)
			)
			(layer "F.Fab")
		)
		(fp_line
			(start -1.700022 0.899922)
			(end -1.700022 -0.899922)
			(stroke
				(width 0.1)
				(type default)
			)
			(layer "F.Fab")
		)
		(fp_line
			(start 1.700022 -0.899922)
			(end 1.700022 0.899922)
			(stroke
				(width 0.1)
				(type default)
			)
			(layer "F.Fab")
		)
		(fp_line
			(start 1.700022 0.899922)
			(end -1.700022 0.899922)
			(stroke
				(width 0.1)
				(type default)
			)
			(layer "F.Fab")
		)
		(pad "1" smd rect
			(at -1.4732 0 180)
			(size 1.1684 1.5748)
			(layers "F.Cu" "F.Mask" "F.Paste")
			(net "P52V_HS_FILTER")
		)
		(pad "2" smd rect
			(at 1.4732 0 180)
			(size 1.1684 1.5748)
			(layers "F.Cu" "F.Mask" "F.Paste")
			(net "GND")
		)
	)
	(footprint ""
		(layer "F.Cu")
		(at 299.570394 -88.0745 180)
		(property "Reference" "PR5864"
			(at 0 0 180)
			(layer "F.SilkS")
			(hide yes)
			(effects
				(font
					(size 1.27 1.27)
				)
			)
		)
		(property "Value" ""
			(at 0 0 180)
			(layer "F.Fab")
			(effects
				(font
					(size 1.27 1.27)
				)
			)
		)
		(duplicate_pad_numbers_are_jumpers no)
		(fp_line
			(start 0.7874 0.4064)
			(end -0.7874 0.4064)
			(stroke
				(width 0.1524)
				(type default)
			)
			(layer "F.SilkS")
		)
		(fp_line
			(start 0.7874 -0.4064)
			(end 0.7874 0.4064)
			(stroke
				(width 0.1524)
				(type default)
			)
			(layer "F.SilkS")
		)
		(fp_line
			(start -0.7874 0.4064)
			(end -0.7874 -0.4064)
			(stroke
				(width 0.1524)
				(type default)
			)
			(layer "F.SilkS")
		)
		(fp_line
			(start -0.7874 -0.4064)
			(end 0.7874 -0.4064)
			(stroke
				(width 0.1524)
				(type default)
			)
			(layer "F.SilkS")
		)
		(fp_line
			(start 0.67945 0.3048)
			(end 0.120396 0.3048)
			(stroke
				(width 0.1)
				(type default)
			)
			(layer "F.Fab")
		)
		(fp_line
			(start 0.67945 -0.3048)
			(end 0.67945 0.3048)
			(stroke
				(width 0.1)
				(type default)
			)
			(layer "F.Fab")
		)
		(fp_line
			(start 0.12065 -0.2794)
			(end 0.12065 -0.3048)
			(stroke
				(width 0.1)
				(type default)
			)
			(layer "F.Fab")
		)
		(fp_line
			(start 0.12065 -0.3048)
			(end 0.67945 -0.3048)
			(stroke
				(width 0.1)
				(type default)
			)
			(layer "F.Fab")
		)
		(fp_line
			(start 0.120396 0.3048)
			(end 0.120396 0.2794)
			(stroke
				(width 0.1)
				(type default)
			)
			(layer "F.Fab")
		)
		(fp_line
			(start 0.120396 0.2794)
			(end -0.12065 0.2794)
			(stroke
				(width 0.1)
				(type default)
			)
			(layer "F.Fab")
		)
		(fp_line
			(start -0.12065 0.3048)
			(end -0.67945 0.3048)
			(stroke
				(width 0.1)
				(type default)
			)
			(layer "F.Fab")
		)
		(fp_line
			(start -0.12065 0.2794)
			(end -0.12065 0.3048)
			(stroke
				(width 0.1)
				(type default)
			)
			(layer "F.Fab")
		)
		(fp_line
			(start -0.12065 -0.2794)
			(end 0.12065 -0.2794)
			(stroke
				(width 0.1)
				(type default)
			)
			(layer "F.Fab")
		)
		(fp_line
			(start -0.12065 -0.305054)
			(end -0.12065 -0.2794)
			(stroke
				(width 0.1)
				(type default)
			)
			(layer "F.Fab")
		)
		(fp_line
			(start -0.67945 0.3048)
			(end -0.67945 -0.305054)
			(stroke
				(width 0.1)
				(type default)
			)
			(layer "F.Fab")
		)
		(fp_line
			(start -0.67945 -0.305054)
			(end -0.12065 -0.305054)
			(stroke
				(width 0.1)
				(type default)
			)
			(layer "F.Fab")
		)
		(pad "1" smd circle
			(at -0.40005 0 180)
			(size 0 0)
			(layers "F.Cu" "F.Mask" "F.Paste")
			(net "P52V_HS_4287_S2P")
		)
		(pad "2" smd circle
			(at 0.40005 0 180)
			(size 0 0)
			(layers "F.Cu" "F.Mask" "F.Paste")
			(net "P52V_HS_4287_S2N")
		)
	)
	(footprint ""
		(layer "F.Cu")
		(at 267.589 -47.625 -90)
		(property "Reference" "R5856"
			(at 0 0 270)
			(layer "F.SilkS")
			(hide yes)
			(effects
				(font
					(size 1.27 1.27)
				)
			)
		)
		(property "Value" ""
			(at 0 0 270)
			(layer "F.Fab")
			(effects
				(font
					(size 1.27 1.27)
				)
			)
		)
		(duplicate_pad_numbers_are_jumpers no)
		(fp_line
			(start -0.7874 0.4064)
			(end -0.7874 -0.4064)
			(stroke
				(width 0.1524)
				(type default)
			)
			(layer "F.SilkS")
		)
		(fp_line
			(start 0.7874 0.4064)
			(end -0.7874 0.4064)
			(stroke
				(width 0.1524)
				(type default)
			)
			(layer "F.SilkS")
		)
		(fp_line
			(start -0.7874 -0.4064)
			(end 0.7874 -0.4064)
			(stroke
				(width 0.1524)
				(type default)
			)
			(layer "F.SilkS")
		)
		(fp_line
			(start 0.7874 -0.4064)
			(end 0.7874 0.4064)
			(stroke
				(width 0.1524)
				(type default)
			)
			(layer "F.SilkS")
		)
		(fp_line
			(start -0.67945 0.3048)
			(end -0.67945 -0.305054)
			(stroke
				(width 0.1)
				(type default)
			)
			(layer "F.Fab")
		)
		(fp_line
			(start -0.12065 0.3048)
			(end -0.67945 0.3048)
			(stroke
				(width 0.1)
				(type default)
			)
			(layer "F.Fab")
		)
		(fp_line
			(start 0.120396 0.3048)
			(end 0.120396 0.2794)
			(stroke
				(width 0.1)
				(type default)
			)
			(layer "F.Fab")
		)
		(fp_line
			(start 0.67945 0.3048)
			(end 0.120396 0.3048)
			(stroke
				(width 0.1)
				(type default)
			)
			(layer "F.Fab")
		)
		(fp_line
			(start -0.12065 0.2794)
			(end -0.12065 0.3048)
			(stroke
				(width 0.1)
				(type default)
			)
			(layer "F.Fab")
		)
		(fp_line
			(start 0.120396 0.2794)
			(end -0.12065 0.2794)
			(stroke
				(width 0.1)
				(type default)
			)
			(layer "F.Fab")
		)
		(fp_line
			(start -0.12065 -0.2794)
			(end 0.12065 -0.2794)
			(stroke
				(width 0.1)
				(type default)
			)
			(layer "F.Fab")
		)
		(fp_line
			(start 0.12065 -0.2794)
			(end 0.12065 -0.3048)
			(stroke
				(width 0.1)
				(type default)
			)
			(layer "F.Fab")
		)
		(fp_line
			(start 0.12065 -0.3048)
			(end 0.67945 -0.3048)
			(stroke
				(width 0.1)
				(type default)
			)
			(layer "F.Fab")
		)
		(fp_line
			(start 0.67945 -0.3048)
			(end 0.67945 0.3048)
			(stroke
				(width 0.1)
				(type default)
			)
			(layer "F.Fab")
		)
		(fp_line
			(start -0.67945 -0.305054)
			(end -0.12065 -0.305054)
			(stroke
				(width 0.1)
				(type default)
			)
			(layer "F.Fab")
		)
		(fp_line
			(start -0.12065 -0.305054)
			(end -0.12065 -0.2794)
			(stroke
				(width 0.1)
				(type default)
			)
			(layer "F.Fab")
		)
		(pad "1" smd circle
			(at -0.40005 0 270)
			(size 0 0)
			(layers "F.Cu" "F.Mask" "F.Paste")
			(net "SMB_P52V_HSC_SDA")
		)
		(pad "2" smd circle
			(at 0.40005 0 270)
			(size 0 0)
			(layers "F.Cu" "F.Mask" "F.Paste")
			(net "SMB_P52V_HS1_SDAO")
		)
	)
	(footprint ""
		(layer "F.Cu")
		(at 184.52846 -51.816)
		(property "Reference" "PC128"
			(at 0 0 0)
			(layer "F.SilkS")
			(hide yes)
			(effects
				(font
					(size 1.27 1.27)
				)
			)
		)
		(property "Value" ""
			(at 0 0 0)
			(layer "F.Fab")
			(effects
				(font
					(size 1.27 1.27)
				)
			)
		)
		(duplicate_pad_numbers_are_jumpers no)
		(fp_line
			(start -1.524 -0.762)
			(end 1.524 -0.762)
			(stroke
				(width 0.1524)
				(type default)
			)
			(layer "F.SilkS")
		)
		(fp_line
			(start -1.524 0.762)
			(end -1.524 -0.762)
			(stroke
				(width 0.1524)
				(type default)
			)
			(layer "F.SilkS")
		)
		(fp_line
			(start 1.524 -0.762)
			(end 1.524 0.762)
			(stroke
				(width 0.1524)
				(type default)
			)
			(layer "F.SilkS")
		)
		(fp_line
			(start 1.524 0.762)
			(end -1.524 0.762)
			(stroke
				(width 0.1524)
				(type default)
			)
			(layer "F.SilkS")
		)
		(fp_line
			(start -1.1049 -0.724916)
			(end -1.1049 0.724916)
			(stroke
				(width 0.1)
				(type default)
			)
			(layer "F.Fab")
		)
		(fp_line
			(start -1.1049 0.724916)
			(end 1.1049 0.724916)
			(stroke
				(width 0.1)
				(type default)
			)
			(layer "F.Fab")
		)
		(fp_line
			(start 1.1049 -0.724916)
			(end -1.1049 -0.724916)
			(stroke
				(width 0.1)
				(type default)
			)
			(layer "F.Fab")
		)
		(fp_line
			(start 1.1049 0.724916)
			(end 1.1049 -0.724916)
			(stroke
				(width 0.1)
				(type default)
			)
			(layer "F.Fab")
		)
		(pad "1" smd rect
			(at -0.889 0 180)
			(size 1.016 1.27)
			(layers "F.Cu" "F.Mask" "F.Paste")
			(net "P12V_BRICK")
		)
		(pad "2" smd rect
			(at 0.889 0 180)
			(size 1.016 1.27)
			(layers "F.Cu" "F.Mask" "F.Paste")
			(net "GND")
		)
	)
	(footprint ""
		(layer "F.Cu")
		(at 96.905826 -130.175)
		(property "Reference" "PC48"
			(at 0 0 0)
			(layer "F.SilkS")
			(hide yes)
			(effects
				(font
					(size 1.27 1.27)
				)
			)
		)
		(property "Value" ""
			(at 0 0 0)
			(layer "F.Fab")
			(effects
				(font
					(size 1.27 1.27)
				)
			)
		)
		(duplicate_pad_numbers_are_jumpers no)
		(fp_line
			(start -2.2098 -0.9398)
			(end 2.2098 -0.9398)
			(stroke
				(width 0.1524)
				(type default)
			)
			(layer "F.SilkS")
		)
		(fp_line
			(start -2.2098 0.9398)
			(end -2.2098 -0.9398)
			(stroke
				(width 0.1524)
				(type default)
			)
			(layer "F.SilkS")
		)
		(fp_line
			(start 2.2098 -0.9398)
			(end 2.2098 0.9398)
			(stroke
				(width 0.1524)
				(type default)
			)
			(layer "F.SilkS")
		)
		(fp_line
			(start 2.2098 0.9398)
			(end -2.2098 0.9398)
			(stroke
				(width 0.1524)
				(type default)
			)
			(layer "F.SilkS")
		)
		(fp_line
			(start -1.700022 -0.899922)
			(end 1.700022 -0.899922)
			(stroke
				(width 0.1)
				(type default)
			)
			(layer "F.Fab")
		)
		(fp_line
			(start -1.700022 0.899922)
			(end -1.700022 -0.899922)
			(stroke
				(width 0.1)
				(type default)
			)
			(layer "F.Fab")
		)
		(fp_line
			(start 1.700022 -0.899922)
			(end 1.700022 0.899922)
			(stroke
				(width 0.1)
				(type default)
			)
			(layer "F.Fab")
		)
		(fp_line
			(start 1.700022 0.899922)
			(end -1.700022 0.899922)
			(stroke
				(width 0.1)
				(type default)
			)
			(layer "F.Fab")
		)
		(pad "1" smd rect
			(at -1.4732 0 180)
			(size 1.1684 1.5748)
			(layers "F.Cu" "F.Mask" "F.Paste")
			(net "P52V_HS_FILTER")
		)
		(pad "2" smd rect
			(at 1.4732 0 180)
			(size 1.1684 1.5748)
			(layers "F.Cu" "F.Mask" "F.Paste")
			(net "GND")
		)
	)
	(footprint ""
		(layer "F.Cu")
		(at 271.412716 -33.849818 -90)
		(property "Reference" "PC487"
			(at 0 0 270)
			(layer "F.SilkS")
			(hide yes)
			(effects
				(font
					(size 1.27 1.27)
				)
			)
		)
		(property "Value" ""
			(at 0 0 270)
			(layer "F.Fab")
			(effects
				(font
					(size 1.27 1.27)
				)
			)
		)
		(duplicate_pad_numbers_are_jumpers no)
		(fp_line
			(start -2.2098 0.9398)
			(end -2.2098 -0.9398)
			(stroke
				(width 0.1524)
				(type default)
			)
			(layer "F.SilkS")
		)
		(fp_line
			(start 2.2098 0.9398)
			(end -2.2098 0.9398)
			(stroke
				(width 0.1524)
				(type default)
			)
			(layer "F.SilkS")
		)
		(fp_line
			(start -2.2098 -0.9398)
			(end 2.2098 -0.9398)
			(stroke
				(width 0.1524)
				(type default)
			)
			(layer "F.SilkS")
		)
		(fp_line
			(start 2.2098 -0.9398)
			(end 2.2098 0.9398)
			(stroke
				(width 0.1524)
				(type default)
			)
			(layer "F.SilkS")
		)
		(fp_line
			(start -1.700022 0.899922)
			(end -1.700022 -0.899922)
			(stroke
				(width 0.1)
				(type default)
			)
			(layer "F.Fab")
		)
		(fp_line
			(start 1.700022 0.899922)
			(end -1.700022 0.899922)
			(stroke
				(width 0.1)
				(type default)
			)
			(layer "F.Fab")
		)
		(fp_line
			(start -1.700022 -0.899922)
			(end 1.700022 -0.899922)
			(stroke
				(width 0.1)
				(type default)
			)
			(layer "F.Fab")
		)
		(fp_line
			(start 1.700022 -0.899922)
			(end 1.700022 0.899922)
			(stroke
				(width 0.1)
				(type default)
			)
			(layer "F.Fab")
		)
		(pad "1" smd rect
			(at -1.4732 0 90)
			(size 1.1684 1.5748)
			(layers "F.Cu" "F.Mask" "F.Paste")
			(net "P52V_HS1_DVCC")
		)
		(pad "2" smd rect
			(at 1.4732 0 90)
			(size 1.1684 1.5748)
			(layers "F.Cu" "F.Mask" "F.Paste")
			(net "GND")
		)
	)
	(footprint ""
		(layer "F.Cu")
		(at 239.395 -95.504 -90)
		(property "Reference" "C43"
			(at 0 0 270)
			(layer "F.SilkS")
			(hide yes)
			(effects
				(font
					(size 1.27 1.27)
				)
			)
		)
		(property "Value" ""
			(at 0 0 270)
			(layer "F.Fab")
			(effects
				(font
					(size 1.27 1.27)
				)
			)
		)
		(duplicate_pad_numbers_are_jumpers no)
		(fp_line
			(start -2.2098 0.9398)
			(end -2.2098 -0.9398)
			(stroke
				(width 0.1524)
				(type default)
			)
			(layer "F.SilkS")
		)
		(fp_line
			(start 2.2098 0.9398)
			(end -2.2098 0.9398)
			(stroke
				(width 0.1524)
				(type default)
			)
			(layer "F.SilkS")
		)
		(fp_line
			(start -2.2098 -0.9398)
			(end 2.2098 -0.9398)
			(stroke
				(width 0.1524)
				(type default)
			)
			(layer "F.SilkS")
		)
		(fp_line
			(start 2.2098 -0.9398)
			(end 2.2098 0.9398)
			(stroke
				(width 0.1524)
				(type default)
			)
			(layer "F.SilkS")
		)
		(fp_line
			(start -1.700022 0.899922)
			(end -1.700022 -0.899922)
			(stroke
				(width 0.1)
				(type default)
			)
			(layer "F.Fab")
		)
		(fp_line
			(start 1.700022 0.899922)
			(end -1.700022 0.899922)
			(stroke
				(width 0.1)
				(type default)
			)
			(layer "F.Fab")
		)
		(fp_line
			(start -1.700022 -0.899922)
			(end 1.700022 -0.899922)
			(stroke
				(width 0.1)
				(type default)
			)
			(layer "F.Fab")
		)
		(fp_line
			(start 1.700022 -0.899922)
			(end 1.700022 0.899922)
			(stroke
				(width 0.1)
				(type default)
			)
			(layer "F.Fab")
		)
		(pad "1" smd rect
			(at -1.4732 0 90)
			(size 1.1684 1.5748)
			(layers "F.Cu" "F.Mask" "F.Paste")
			(net "P52V_HS")
		)
		(pad "2" smd rect
			(at 1.4732 0 90)
			(size 1.1684 1.5748)
			(layers "F.Cu" "F.Mask" "F.Paste")
			(net "GND")
		)
	)
	(footprint ""
		(layer "F.Cu")
		(at 270.383 -117.688868 -90)
		(property "Reference" "PR12"
			(at 0 0 270)
			(layer "F.SilkS")
			(hide yes)
			(effects
				(font
					(size 1.27 1.27)
				)
			)
		)
		(property "Value" ""
			(at 0 0 270)
			(layer "F.Fab")
			(effects
				(font
					(size 1.27 1.27)
				)
			)
		)
		(duplicate_pad_numbers_are_jumpers no)
		(fp_line
			(start -1.2954 0.5842)
			(end -1.2954 -0.5842)
			(stroke
				(width 0.1524)
				(type default)
			)
			(layer "F.SilkS")
		)
		(fp_line
			(start 1.2954 0.5842)
			(end -1.2954 0.5842)
			(stroke
				(width 0.1524)
				(type default)
			)
			(layer "F.SilkS")
		)
		(fp_line
			(start -1.2954 -0.5842)
			(end 1.2954 -0.5842)
			(stroke
				(width 0.1524)
				(type default)
			)
			(layer "F.SilkS")
		)
		(fp_line
			(start 1.2954 -0.5842)
			(end 1.2954 0.5842)
			(stroke
				(width 0.1524)
				(type default)
			)
			(layer "F.SilkS")
		)
		(fp_line
			(start -0.8636 0.4572)
			(end -0.8636 0.4318)
			(stroke
				(width 0.1)
				(type default)
			)
			(layer "F.Fab")
		)
		(fp_line
			(start 0.8636 0.4572)
			(end -0.8636 0.4572)
			(stroke
				(width 0.1)
				(type default)
			)
			(layer "F.Fab")
		)
		(fp_line
			(start -0.8636 0.4318)
			(end -0.8636 0.4064)
			(stroke
				(width 0.1)
				(type default)
			)
			(layer "F.Fab")
		)
		(fp_line
			(start -1.1938 0.4064)
			(end -1.1938 -0.406654)
			(stroke
				(width 0.1)
				(type default)
			)
			(layer "F.Fab")
		)
		(fp_line
			(start -0.8636 0.4064)
			(end -1.1938 0.4064)
			(stroke
				(width 0.1)
				(type default)
			)
			(layer "F.Fab")
		)
		(fp_line
			(start 0.8636 0.4064)
			(end 0.8636 0.4572)
			(stroke
				(width 0.1)
				(type default)
			)
			(layer "F.Fab")
		)
		(fp_line
			(start 1.1938 0.4064)
			(end 0.8636 0.4064)
			(stroke
				(width 0.1)
				(type default)
			)
			(layer "F.Fab")
		)
		(fp_line
			(start -1.1938 -0.406654)
			(end -0.8636 -0.406654)
			(stroke
				(width 0.1)
				(type default)
			)
			(layer "F.Fab")
		)
		(fp_line
			(start -0.8636 -0.406654)
			(end -0.8636 -0.4572)
			(stroke
				(width 0.1)
				(type default)
			)
			(layer "F.Fab")
		)
		(fp_line
			(start 0.8636 -0.406654)
			(end 1.1938 -0.406654)
			(stroke
				(width 0.1)
				(type default)
			)
			(layer "F.Fab")
		)
		(fp_line
			(start 1.1938 -0.406654)
			(end 1.1938 0.4064)
			(stroke
				(width 0.1)
				(type default)
			)
			(layer "F.Fab")
		)
		(fp_line
			(start -0.8636 -0.4572)
			(end 0.8636 -0.4572)
			(stroke
				(width 0.1)
				(type default)
			)
			(layer "F.Fab")
		)
		(fp_line
			(start 0.8636 -0.4572)
			(end 0.8636 -0.406654)
			(stroke
				(width 0.1)
				(type default)
			)
			(layer "F.Fab")
		)
		(pad "1" smd rect
			(at -0.7366 0 180)
			(size 0.7112 0.8128)
			(layers "F.Cu" "F.Mask" "F.Paste")
			(net "P52V_HS1_GATE1_R")
		)
		(pad "2" smd rect
			(at 0.7366 0 180)
			(size 0.7112 0.8128)
			(layers "F.Cu" "F.Mask" "F.Paste")
			(net "P52V_HS1_GATE2")
		)
	)
	(footprint ""
		(layer "F.Cu")
		(at 157.226 -49.911)
		(property "Reference" "PC36"
			(at 0 0 0)
			(layer "F.SilkS")
			(hide yes)
			(effects
				(font
					(size 1.27 1.27)
				)
			)
		)
		(property "Value" ""
			(at 0 0 0)
			(layer "F.Fab")
			(effects
				(font
					(size 1.27 1.27)
				)
			)
		)
		(duplicate_pad_numbers_are_jumpers no)
		(fp_line
			(start -1.524 -0.762)
			(end 1.524 -0.762)
			(stroke
				(width 0.1524)
				(type default)
			)
			(layer "F.SilkS")
		)
		(fp_line
			(start -1.524 0.762)
			(end -1.524 -0.762)
			(stroke
				(width 0.1524)
				(type default)
			)
			(layer "F.SilkS")
		)
		(fp_line
			(start 1.524 -0.762)
			(end 1.524 0.762)
			(stroke
				(width 0.1524)
				(type default)
			)
			(layer "F.SilkS")
		)
		(fp_line
			(start 1.524 0.762)
			(end -1.524 0.762)
			(stroke
				(width 0.1524)
				(type default)
			)
			(layer "F.SilkS")
		)
		(fp_line
			(start -1.1049 -0.724916)
			(end -1.1049 0.724916)
			(stroke
				(width 0.1)
				(type default)
			)
			(layer "F.Fab")
		)
		(fp_line
			(start -1.1049 0.724916)
			(end 1.1049 0.724916)
			(stroke
				(width 0.1)
				(type default)
			)
			(layer "F.Fab")
		)
		(fp_line
			(start 1.1049 -0.724916)
			(end -1.1049 -0.724916)
			(stroke
				(width 0.1)
				(type default)
			)
			(layer "F.Fab")
		)
		(fp_line
			(start 1.1049 0.724916)
			(end 1.1049 -0.724916)
			(stroke
				(width 0.1)
				(type default)
			)
			(layer "F.Fab")
		)
		(pad "1" smd rect
			(at -0.889 0 180)
			(size 1.016 1.27)
			(layers "F.Cu" "F.Mask" "F.Paste")
			(net "P12V_BRICK")
		)
		(pad "2" smd rect
			(at 0.889 0 180)
			(size 1.016 1.27)
			(layers "F.Cu" "F.Mask" "F.Paste")
			(net "GND")
		)
	)
	(footprint ""
		(layer "F.Cu")
		(at 96.012 -8.763)
		(property "Reference" "ME2"
			(at 0 0 0)
			(layer "F.SilkS")
			(hide yes)
			(effects
				(font
					(size 1.27 1.27)
				)
			)
		)
		(property "Value" ""
			(at 0 0 0)
			(layer "F.Fab")
			(effects
				(font
					(size 1.27 1.27)
				)
			)
		)
		(duplicate_pad_numbers_are_jumpers no)
		(fp_poly
			(pts
				(xy 0 -0.5842) (xy 3.3401 -0.5842) (xy 3.3401 0) (xy 0 0)
			)
			(stroke
				(width 0)
				(type default)
			)
			(fill yes)
			(layer "F.SilkS")
		)
		(fp_poly
			(pts
				(xy 1.32715 -3.4417) (xy 2.01295 -3.4417) (xy 2.01295 -3.2512) (xy 1.32715 -3.2512)
			)
			(stroke
				(width 0)
				(type default)
			)
			(fill yes)
			(layer "F.SilkS")
		)
		(fp_poly
			(pts
				(xy -0.070612 -0.681228) (xy -0.197612 -0.820928) (xy 0.852678 -1.91262) (xy 0.728472 -3.29184)
				(xy -0.248412 -4.300728) (xy -0.184912 -4.478528) (xy -0.007112 -4.503928) (xy 0.684022 -3.785616)
				(xy 0.65659 -4.0894) (xy 0.97155 -4.3434) (xy 1.22555 -4.3561) (xy 1.46685 -4.4704) (xy 2.01295 -4.4704)
				(xy 2.15265 -4.4069) (xy 2.44475 -4.191) (xy 2.49555 -4.191) (xy 2.59715 -4.2926) (xy 2.80035 -4.2672)
				(xy 2.88925 -4.1656) (xy 2.88925 -4.029456) (xy 3.345688 -4.503928) (xy 3.523488 -4.478528) (xy 3.586988 -4.300728)
				(xy 2.88925 -3.58013) (xy 2.88925 -3.3147) (xy 2.82575 -3.2385) (xy 2.67335 -3.2385) (xy 2.521966 -1.875282)
				(xy 2.545842 -1.85039)
				(arc
					(start 2.55905 -1.8415)
					(mid 2.648099 -1.766068)
					(end 2.717292 -1.672082)
				)
				(xy 3.536188 -0.820928) (xy 3.409188 -0.681228) (xy 3.244088 -0.693928)
				(arc
					(start 2.737612 -1.216914)
					(mid 2.31728 -0.925553)
					(end 1.86055 -1.1557)
				)
				(xy 0.92075 -1.1557) (xy 0.888492 -1.51384) (xy 0.094488 -0.693928)
			)
			(stroke
				(width 0)
				(type default)
			)
			(fill yes)
			(layer "F.SilkS")
		)
	)
	(footprint ""
		(layer "F.Cu")
		(at 38.90772 -55.20944 -90)
		(property "Reference" "C93"
			(at 0 0 270)
			(layer "F.SilkS")
			(hide yes)
			(effects
				(font
					(size 1.27 1.27)
				)
			)
		)
		(property "Value" ""
			(at 0 0 270)
			(layer "F.Fab")
			(effects
				(font
					(size 1.27 1.27)
				)
			)
		)
		(duplicate_pad_numbers_are_jumpers no)
		(fp_line
			(start -0.7874 0.4064)
			(end -0.7874 -0.4064)
			(stroke
				(width 0.1524)
				(type default)
			)
			(layer "F.SilkS")
		)
		(fp_line
			(start 0.7874 0.4064)
			(end -0.7874 0.4064)
			(stroke
				(width 0.1524)
				(type default)
			)
			(layer "F.SilkS")
		)
		(fp_line
			(start -0.7874 -0.4064)
			(end 0.7874 -0.4064)
			(stroke
				(width 0.1524)
				(type default)
			)
			(layer "F.SilkS")
		)
		(fp_line
			(start 0.7874 -0.4064)
			(end 0.7874 0.4064)
			(stroke
				(width 0.1524)
				(type default)
			)
			(layer "F.SilkS")
		)
		(fp_line
			(start -0.6858 0.3048)
			(end -0.6858 -0.3048)
			(stroke
				(width 0.1)
				(type default)
			)
			(layer "F.Fab")
		)
		(fp_line
			(start -0.1016 0.3048)
			(end -0.6858 0.3048)
			(stroke
				(width 0.1)
				(type default)
			)
			(layer "F.Fab")
		)
		(fp_line
			(start 0.1016 0.3048)
			(end 0.1016 0.2794)
			(stroke
				(width 0.1)
				(type default)
			)
			(layer "F.Fab")
		)
		(fp_line
			(start 0.6858 0.3048)
			(end 0.1016 0.3048)
			(stroke
				(width 0.1)
				(type default)
			)
			(layer "F.Fab")
		)
		(fp_line
			(start -0.1016 0.2794)
			(end -0.1016 0.3048)
			(stroke
				(width 0.1)
				(type default)
			)
			(layer "F.Fab")
		)
		(fp_line
			(start 0.1016 0.2794)
			(end -0.1016 0.2794)
			(stroke
				(width 0.1)
				(type default)
			)
			(layer "F.Fab")
		)
		(fp_line
			(start -0.1016 -0.2794)
			(end 0.1016 -0.2794)
			(stroke
				(width 0.1)
				(type default)
			)
			(layer "F.Fab")
		)
		(fp_line
			(start 0.1016 -0.2794)
			(end 0.1016 -0.3048)
			(stroke
				(width 0.1)
				(type default)
			)
			(layer "F.Fab")
		)
		(fp_line
			(start -0.6858 -0.3048)
			(end -0.1016 -0.3048)
			(stroke
				(width 0.1)
				(type default)
			)
			(layer "F.Fab")
		)
		(fp_line
			(start -0.1016 -0.3048)
			(end -0.1016 -0.2794)
			(stroke
				(width 0.1)
				(type default)
			)
			(layer "F.Fab")
		)
		(fp_line
			(start 0.1016 -0.3048)
			(end 0.6858 -0.3048)
			(stroke
				(width 0.1)
				(type default)
			)
			(layer "F.Fab")
		)
		(fp_line
			(start 0.6858 -0.3048)
			(end 0.6858 0.3048)
			(stroke
				(width 0.1)
				(type default)
			)
			(layer "F.Fab")
		)
		(pad "1" smd rect
			(at -0.40005 0 90)
			(size 0.4572 0.508)
			(layers "F.Cu" "F.Mask" "F.Paste")
			(net "P12V_HPDB")
		)
		(pad "2" smd rect
			(at 0.40005 0 90)
			(size 0.4572 0.508)
			(layers "F.Cu" "F.Mask" "F.Paste")
			(net "GND")
		)
	)
	(footprint ""
		(layer "F.Cu")
		(at 278.883872 -46.634146 180)
		(property "Reference" "PC561"
			(at 0 0 180)
			(layer "F.SilkS")
			(hide yes)
			(effects
				(font
					(size 1.27 1.27)
				)
			)
		)
		(property "Value" ""
			(at 0 0 180)
			(layer "F.Fab")
			(effects
				(font
					(size 1.27 1.27)
				)
			)
		)
		(duplicate_pad_numbers_are_jumpers no)
		(fp_line
			(start 0.7874 0.4064)
			(end -0.7874 0.4064)
			(stroke
				(width 0.1524)
				(type default)
			)
			(layer "F.SilkS")
		)
		(fp_line
			(start 0.7874 -0.4064)
			(end 0.7874 0.4064)
			(stroke
				(width 0.1524)
				(type default)
			)
			(layer "F.SilkS")
		)
		(fp_line
			(start -0.7874 0.4064)
			(end -0.7874 -0.4064)
			(stroke
				(width 0.1524)
				(type default)
			)
			(layer "F.SilkS")
		)
		(fp_line
			(start -0.7874 -0.4064)
			(end 0.7874 -0.4064)
			(stroke
				(width 0.1524)
				(type default)
			)
			(layer "F.SilkS")
		)
		(fp_line
			(start 0.67945 0.3048)
			(end 0.120396 0.3048)
			(stroke
				(width 0.1)
				(type default)
			)
			(layer "F.Fab")
		)
		(fp_line
			(start 0.67945 -0.3048)
			(end 0.67945 0.3048)
			(stroke
				(width 0.1)
				(type default)
			)
			(layer "F.Fab")
		)
		(fp_line
			(start 0.12065 -0.2794)
			(end 0.12065 -0.3048)
			(stroke
				(width 0.1)
				(type default)
			)
			(layer "F.Fab")
		)
		(fp_line
			(start 0.12065 -0.3048)
			(end 0.67945 -0.3048)
			(stroke
				(width 0.1)
				(type default)
			)
			(layer "F.Fab")
		)
		(fp_line
			(start 0.120396 0.3048)
			(end 0.120396 0.2794)
			(stroke
				(width 0.1)
				(type default)
			)
			(layer "F.Fab")
		)
		(fp_line
			(start 0.120396 0.2794)
			(end -0.12065 0.2794)
			(stroke
				(width 0.1)
				(type default)
			)
			(layer "F.Fab")
		)
		(fp_line
			(start -0.12065 0.3048)
			(end -0.67945 0.3048)
			(stroke
				(width 0.1)
				(type default)
			)
			(layer "F.Fab")
		)
		(fp_line
			(start -0.12065 0.2794)
			(end -0.12065 0.3048)
			(stroke
				(width 0.1)
				(type default)
			)
			(layer "F.Fab")
		)
		(fp_line
			(start -0.12065 -0.2794)
			(end 0.12065 -0.2794)
			(stroke
				(width 0.1)
				(type default)
			)
			(layer "F.Fab")
		)
		(fp_line
			(start -0.12065 -0.305054)
			(end -0.12065 -0.2794)
			(stroke
				(width 0.1)
				(type default)
			)
			(layer "F.Fab")
		)
		(fp_line
			(start -0.67945 0.3048)
			(end -0.67945 -0.305054)
			(stroke
				(width 0.1)
				(type default)
			)
			(layer "F.Fab")
		)
		(fp_line
			(start -0.67945 -0.305054)
			(end -0.12065 -0.305054)
			(stroke
				(width 0.1)
				(type default)
			)
			(layer "F.Fab")
		)
		(pad "1" smd circle
			(at -0.40005 0 180)
			(size 0 0)
			(layers "F.Cu" "F.Mask" "F.Paste")
			(net "P52V_HS1_ISET")
		)
		(pad "2" smd circle
			(at 0.40005 0 180)
			(size 0 0)
			(layers "F.Cu" "F.Mask" "F.Paste")
			(net "GND_FIELD_SIGNAL")
		)
	)
	(footprint ""
		(layer "F.Cu")
		(at 287.767014 -32.577024 90)
		(property "Reference" "PR17"
			(at 0 0 90)
			(layer "F.SilkS")
			(hide yes)
			(effects
				(font
					(size 1.27 1.27)
				)
			)
		)
		(property "Value" ""
			(at 0 0 90)
			(layer "F.Fab")
			(effects
				(font
					(size 1.27 1.27)
				)
			)
		)
		(duplicate_pad_numbers_are_jumpers no)
		(fp_line
			(start 1.651 -0.8382)
			(end 1.651 0.8382)
			(stroke
				(width 0.1524)
				(type default)
			)
			(layer "F.SilkS")
		)
		(fp_line
			(start -1.651 -0.8382)
			(end 1.651 -0.8382)
			(stroke
				(width 0.1524)
				(type default)
			)
			(layer "F.SilkS")
		)
		(fp_line
			(start 1.651 0.8382)
			(end -1.651 0.8382)
			(stroke
				(width 0.1524)
				(type default)
			)
			(layer "F.SilkS")
		)
		(fp_line
			(start -1.651 0.8382)
			(end -1.651 -0.8382)
			(stroke
				(width 0.1524)
				(type default)
			)
			(layer "F.SilkS")
		)
		(fp_line
			(start 1.560576 -0.7366)
			(end 1.524 -0.7366)
			(stroke
				(width 0.1)
				(type default)
			)
			(layer "F.Fab")
		)
		(fp_line
			(start 1.524 -0.7366)
			(end -1.524 -0.7366)
			(stroke
				(width 0.1)
				(type default)
			)
			(layer "F.Fab")
		)
		(fp_line
			(start -1.524 -0.7366)
			(end -1.559814 -0.7366)
			(stroke
				(width 0.1)
				(type default)
			)
			(layer "F.Fab")
		)
		(fp_line
			(start -1.559814 -0.7366)
			(end -1.559814 0.7366)
			(stroke
				(width 0.1)
				(type default)
			)
			(layer "F.Fab")
		)
		(fp_line
			(start 1.560576 0.7366)
			(end 1.560576 -0.7366)
			(stroke
				(width 0.1)
				(type default)
			)
			(layer "F.Fab")
		)
		(fp_line
			(start 1.524 0.7366)
			(end 1.560576 0.7366)
			(stroke
				(width 0.1)
				(type default)
			)
			(layer "F.Fab")
		)
		(fp_line
			(start -1.524 0.7366)
			(end 1.524 0.7366)
			(stroke
				(width 0.1)
				(type default)
			)
			(layer "F.Fab")
		)
		(fp_line
			(start -1.559814 0.7366)
			(end -1.524 0.7366)
			(stroke
				(width 0.1)
				(type default)
			)
			(layer "F.Fab")
		)
		(pad "1" smd rect
			(at -0.94996 0 270)
			(size 1.1176 1.3716)
			(layers "F.Cu" "F.Mask" "F.Paste")
			(net "P52V_HS")
		)
		(pad "2" smd rect
			(at 0.94996 0 270)
			(size 1.1176 1.3716)
			(layers "F.Cu" "F.Mask" "F.Paste")
			(net "P52V_HS1_PWRGIN")
		)
	)
	(footprint ""
		(layer "F.Cu")
		(at 286.554672 -36.209224)
		(property "Reference" "PR6935"
			(at 0 0 0)
			(layer "F.SilkS")
			(hide yes)
			(effects
				(font
					(size 1.27 1.27)
				)
			)
		)
		(property "Value" ""
			(at 0 0 0)
			(layer "F.Fab")
			(effects
				(font
					(size 1.27 1.27)
				)
			)
		)
		(duplicate_pad_numbers_are_jumpers no)
		(fp_line
			(start -0.7874 -0.4064)
			(end 0.7874 -0.4064)
			(stroke
				(width 0.1524)
				(type default)
			)
			(layer "F.SilkS")
		)
		(fp_line
			(start -0.7874 0.4064)
			(end -0.7874 -0.4064)
			(stroke
				(width 0.1524)
				(type default)
			)
			(layer "F.SilkS")
		)
		(fp_line
			(start 0.7874 -0.4064)
			(end 0.7874 0.4064)
			(stroke
				(width 0.1524)
				(type default)
			)
			(layer "F.SilkS")
		)
		(fp_line
			(start 0.7874 0.4064)
			(end -0.7874 0.4064)
			(stroke
				(width 0.1524)
				(type default)
			)
			(layer "F.SilkS")
		)
		(fp_line
			(start -0.67945 -0.305054)
			(end -0.12065 -0.305054)
			(stroke
				(width 0.1)
				(type default)
			)
			(layer "F.Fab")
		)
		(fp_line
			(start -0.67945 0.3048)
			(end -0.67945 -0.305054)
			(stroke
				(width 0.1)
				(type default)
			)
			(layer "F.Fab")
		)
		(fp_line
			(start -0.12065 -0.305054)
			(end -0.12065 -0.2794)
			(stroke
				(width 0.1)
				(type default)
			)
			(layer "F.Fab")
		)
		(fp_line
			(start -0.12065 -0.2794)
			(end 0.12065 -0.2794)
			(stroke
				(width 0.1)
				(type default)
			)
			(layer "F.Fab")
		)
		(fp_line
			(start -0.12065 0.2794)
			(end -0.12065 0.3048)
			(stroke
				(width 0.1)
				(type default)
			)
			(layer "F.Fab")
		)
		(fp_line
			(start -0.12065 0.3048)
			(end -0.67945 0.3048)
			(stroke
				(width 0.1)
				(type default)
			)
			(layer "F.Fab")
		)
		(fp_line
			(start 0.120396 0.2794)
			(end -0.12065 0.2794)
			(stroke
				(width 0.1)
				(type default)
			)
			(layer "F.Fab")
		)
		(fp_line
			(start 0.120396 0.3048)
			(end 0.120396 0.2794)
			(stroke
				(width 0.1)
				(type default)
			)
			(layer "F.Fab")
		)
		(fp_line
			(start 0.12065 -0.3048)
			(end 0.67945 -0.3048)
			(stroke
				(width 0.1)
				(type default)
			)
			(layer "F.Fab")
		)
		(fp_line
			(start 0.12065 -0.2794)
			(end 0.12065 -0.3048)
			(stroke
				(width 0.1)
				(type default)
			)
			(layer "F.Fab")
		)
		(fp_line
			(start 0.67945 -0.3048)
			(end 0.67945 0.3048)
			(stroke
				(width 0.1)
				(type default)
			)
			(layer "F.Fab")
		)
		(fp_line
			(start 0.67945 0.3048)
			(end 0.120396 0.3048)
			(stroke
				(width 0.1)
				(type default)
			)
			(layer "F.Fab")
		)
		(pad "1" smd circle
			(at -0.40005 0)
			(size 0 0)
			(layers "F.Cu" "F.Mask" "F.Paste")
			(net "PWRGD_P52V_HS1_PG")
		)
		(pad "2" smd circle
			(at 0.40005 0)
			(size 0 0)
			(layers "F.Cu" "F.Mask" "F.Paste")
			(net "P52V_HS1_PWRGIN")
		)
	)
	(footprint ""
		(layer "F.Cu")
		(at 244.97284 -4.3053)
		(property "Reference" "H22"
			(at -1.143 -3.40233 0)
			(unlocked yes)
			(layer "F.SilkS")
			(effects
				(font
					(size 0.7874 0.5842)
					(thickness 0.1524)
				)
				(justify left)
			)
		)
		(property "Value" ""
			(at 0 0 0)
			(layer "F.Fab")
			(effects
				(font
					(size 1.27 1.27)
				)
			)
		)
		(duplicate_pad_numbers_are_jumpers no)
		(fp_circle
			(center 0 0)
			(end 2.4003 0)
			(stroke
				(width 0.1524)
				(type default)
			)
			(fill no)
			(layer "F.SilkS")
		)
		(fp_circle
			(center 0 0)
			(end 6.5913 0)
			(stroke
				(width 0.1524)
				(type default)
			)
			(fill no)
			(layer "B.SilkS")
		)
		(fp_circle
			(center 0 0)
			(end 6.5913 0)
			(stroke
				(width 0.1)
				(type default)
			)
			(fill no)
			(layer "B.Fab")
		)
		(fp_circle
			(center 0 0)
			(end 2.4003 0)
			(stroke
				(width 0.1)
				(type default)
			)
			(fill no)
			(layer "F.Fab")
		)
		(pad "" np_thru_hole circle
			(at 0 0)
			(size 3.175 3.175)
			(drill 3.175)
			(layers "*.Cu" "*.Mask")
			(clearance 0.381)
			(thermal_gap 0.381)
		)
		(zone
			(layers "F.Cu" "B.Cu" "In1.Cu" "In2.Cu" "In3.Cu" "In4.Cu" "In5.Cu" "In6.Cu"
				"In7.Cu" "In8.Cu"
			)
			(hatch none 0.5)
			(connect_pads
				(clearance 0)
			)
			(min_thickness 0.25)
			(keepout
				(tracks not_allowed)
				(vias allowed)
				(pads allowed)
				(copperpour not_allowed)
				(footprints allowed)
			)
			(placement
				(enabled no)
				(sheetname "")
			)
			(fill
				(thermal_gap 0.5)
				(thermal_bridge_width 0.5)
				(island_removal_mode 0)
			)
			(polygon
				(pts
					(arc
						(start 247.06834 -4.3053)
						(mid 242.87734 -4.3053)
						(end 247.06834 -4.3053)
					)
				)
			)
		)
	)
	(footprint ""
		(layer "F.Cu")
		(at 287.782 -49.276 90)
		(property "Reference" "PC10"
			(at 0 0 90)
			(layer "F.SilkS")
			(hide yes)
			(effects
				(font
					(size 1.27 1.27)
				)
			)
		)
		(property "Value" ""
			(at 0 0 90)
			(layer "F.Fab")
			(effects
				(font
					(size 1.27 1.27)
				)
			)
		)
		(duplicate_pad_numbers_are_jumpers no)
		(fp_line
			(start 0.7874 -0.4064)
			(end 0.7874 0.4064)
			(stroke
				(width 0.1524)
				(type default)
			)
			(layer "F.SilkS")
		)
		(fp_line
			(start -0.7874 -0.4064)
			(end 0.7874 -0.4064)
			(stroke
				(width 0.1524)
				(type default)
			)
			(layer "F.SilkS")
		)
		(fp_line
			(start 0.7874 0.4064)
			(end -0.7874 0.4064)
			(stroke
				(width 0.1524)
				(type default)
			)
			(layer "F.SilkS")
		)
		(fp_line
			(start -0.7874 0.4064)
			(end -0.7874 -0.4064)
			(stroke
				(width 0.1524)
				(type default)
			)
			(layer "F.SilkS")
		)
		(fp_line
			(start -0.12065 -0.305054)
			(end -0.12065 -0.2794)
			(stroke
				(width 0.1)
				(type default)
			)
			(layer "F.Fab")
		)
		(fp_line
			(start -0.67945 -0.305054)
			(end -0.12065 -0.305054)
			(stroke
				(width 0.1)
				(type default)
			)
			(layer "F.Fab")
		)
		(fp_line
			(start 0.67945 -0.3048)
			(end 0.67945 0.3048)
			(stroke
				(width 0.1)
				(type default)
			)
			(layer "F.Fab")
		)
		(fp_line
			(start 0.12065 -0.3048)
			(end 0.67945 -0.3048)
			(stroke
				(width 0.1)
				(type default)
			)
			(layer "F.Fab")
		)
		(fp_line
			(start 0.12065 -0.2794)
			(end 0.12065 -0.3048)
			(stroke
				(width 0.1)
				(type default)
			)
			(layer "F.Fab")
		)
		(fp_line
			(start -0.12065 -0.2794)
			(end 0.12065 -0.2794)
			(stroke
				(width 0.1)
				(type default)
			)
			(layer "F.Fab")
		)
		(fp_line
			(start 0.120396 0.2794)
			(end -0.12065 0.2794)
			(stroke
				(width 0.1)
				(type default)
			)
			(layer "F.Fab")
		)
		(fp_line
			(start -0.12065 0.2794)
			(end -0.12065 0.3048)
			(stroke
				(width 0.1)
				(type default)
			)
			(layer "F.Fab")
		)
		(fp_line
			(start 0.67945 0.3048)
			(end 0.120396 0.3048)
			(stroke
				(width 0.1)
				(type default)
			)
			(layer "F.Fab")
		)
		(fp_line
			(start 0.120396 0.3048)
			(end 0.120396 0.2794)
			(stroke
				(width 0.1)
				(type default)
			)
			(layer "F.Fab")
		)
		(fp_line
			(start -0.12065 0.3048)
			(end -0.67945 0.3048)
			(stroke
				(width 0.1)
				(type default)
			)
			(layer "F.Fab")
		)
		(fp_line
			(start -0.67945 0.3048)
			(end -0.67945 -0.305054)
			(stroke
				(width 0.1)
				(type default)
			)
			(layer "F.Fab")
		)
		(pad "1" smd circle
			(at -0.40005 0 90)
			(size 0 0)
			(layers "F.Cu" "F.Mask" "F.Paste")
			(net "P52V_HS1_VREG")
		)
		(pad "2" smd circle
			(at 0.40005 0 90)
			(size 0 0)
			(layers "F.Cu" "F.Mask" "F.Paste")
			(net "GND_FIELD_SIGNAL")
		)
	)
	(footprint ""
		(layer "F.Cu")
		(at 163.576 -9.398)
		(property "Reference" "PC99"
			(at 0 0 0)
			(layer "F.SilkS")
			(hide yes)
			(effects
				(font
					(size 1.27 1.27)
				)
			)
		)
		(property "Value" ""
			(at 0 0 0)
			(layer "F.Fab")
			(effects
				(font
					(size 1.27 1.27)
				)
			)
		)
		(duplicate_pad_numbers_are_jumpers no)
		(fp_line
			(start -0.7874 -0.4064)
			(end 0.7874 -0.4064)
			(stroke
				(width 0.1524)
				(type default)
			)
			(layer "F.SilkS")
		)
		(fp_line
			(start -0.7874 0.4064)
			(end -0.7874 -0.4064)
			(stroke
				(width 0.1524)
				(type default)
			)
			(layer "F.SilkS")
		)
		(fp_line
			(start 0.7874 -0.4064)
			(end 0.7874 0.4064)
			(stroke
				(width 0.1524)
				(type default)
			)
			(layer "F.SilkS")
		)
		(fp_line
			(start 0.7874 0.4064)
			(end -0.7874 0.4064)
			(stroke
				(width 0.1524)
				(type default)
			)
			(layer "F.SilkS")
		)
		(fp_line
			(start -0.6858 -0.3048)
			(end -0.1016 -0.3048)
			(stroke
				(width 0.1)
				(type default)
			)
			(layer "F.Fab")
		)
		(fp_line
			(start -0.6858 0.3048)
			(end -0.6858 -0.3048)
			(stroke
				(width 0.1)
				(type default)
			)
			(layer "F.Fab")
		)
		(fp_line
			(start -0.1016 -0.3048)
			(end -0.1016 -0.2794)
			(stroke
				(width 0.1)
				(type default)
			)
			(layer "F.Fab")
		)
		(fp_line
			(start -0.1016 -0.2794)
			(end 0.1016 -0.2794)
			(stroke
				(width 0.1)
				(type default)
			)
			(layer "F.Fab")
		)
		(fp_line
			(start -0.1016 0.2794)
			(end -0.1016 0.3048)
			(stroke
				(width 0.1)
				(type default)
			)
			(layer "F.Fab")
		)
		(fp_line
			(start -0.1016 0.3048)
			(end -0.6858 0.3048)
			(stroke
				(width 0.1)
				(type default)
			)
			(layer "F.Fab")
		)
		(fp_line
			(start 0.1016 -0.3048)
			(end 0.6858 -0.3048)
			(stroke
				(width 0.1)
				(type default)
			)
			(layer "F.Fab")
		)
		(fp_line
			(start 0.1016 -0.2794)
			(end 0.1016 -0.3048)
			(stroke
				(width 0.1)
				(type default)
			)
			(layer "F.Fab")
		)
		(fp_line
			(start 0.1016 0.2794)
			(end -0.1016 0.2794)
			(stroke
				(width 0.1)
				(type default)
			)
			(layer "F.Fab")
		)
		(fp_line
			(start 0.1016 0.3048)
			(end 0.1016 0.2794)
			(stroke
				(width 0.1)
				(type default)
			)
			(layer "F.Fab")
		)
		(fp_line
			(start 0.6858 -0.3048)
			(end 0.6858 0.3048)
			(stroke
				(width 0.1)
				(type default)
			)
			(layer "F.Fab")
		)
		(fp_line
			(start 0.6858 0.3048)
			(end 0.1016 0.3048)
			(stroke
				(width 0.1)
				(type default)
			)
			(layer "F.Fab")
		)
		(pad "1" smd rect
			(at -0.40005 0 180)
			(size 0.4572 0.508)
			(layers "F.Cu" "F.Mask" "F.Paste")
			(net "P12V_BRICK")
		)
		(pad "2" smd rect
			(at 0.40005 0 180)
			(size 0.4572 0.508)
			(layers "F.Cu" "F.Mask" "F.Paste")
			(net "GND")
		)
	)
	(footprint ""
		(layer "F.Cu")
		(at 62.23 -8.509)
		(property "Reference" "DM1"
			(at 0 0 0)
			(layer "F.SilkS")
			(hide yes)
			(effects
				(font
					(size 1.27 1.27)
				)
			)
		)
		(property "Value" ""
			(at 0 0 0)
			(layer "F.Fab")
			(effects
				(font
					(size 1.27 1.27)
				)
			)
		)
		(duplicate_pad_numbers_are_jumpers no)
		(fp_line
			(start 0 -4.99999)
			(end 0 -3.47599)
			(stroke
				(width 0.1524)
				(type default)
			)
			(layer "F.SilkS")
		)
		(fp_line
			(start 1.524 -4.99999)
			(end 0 -4.99999)
			(stroke
				(width 0.1524)
				(type default)
			)
			(layer "F.SilkS")
		)
		(fp_text user "P/N"
			(at 0.361188 -3.449828 0)
			(unlocked yes)
			(layer "F.SilkS")
			(effects
				(font
					(size 1.905 1.4224)
					(thickness 0.1524)
				)
				(justify left)
			)
		)
	)
	(footprint ""
		(layer "F.Cu")
		(at 300.5074 -49.403 90)
		(property "Reference" "FS1"
			(at -0.889 -2.51333 90)
			(unlocked yes)
			(layer "F.SilkS")
			(effects
				(font
					(size 0.7874 0.5842)
					(thickness 0.1524)
				)
				(justify left)
			)
		)
		(property "Value" ""
			(at 0 0 90)
			(layer "F.Fab")
			(effects
				(font
					(size 1.27 1.27)
				)
			)
		)
		(duplicate_pad_numbers_are_jumpers no)
		(fp_line
			(start 6.427724 -1.8415)
			(end -6.427724 -1.8415)
			(stroke
				(width 0.1524)
				(type default)
			)
			(layer "F.SilkS")
		)
		(fp_line
			(start -6.427724 -1.8415)
			(end -6.427724 1.8415)
			(stroke
				(width 0.1524)
				(type default)
			)
			(layer "F.SilkS")
		)
		(fp_line
			(start 6.427724 1.8415)
			(end 6.427724 -1.8415)
			(stroke
				(width 0.1524)
				(type default)
			)
			(layer "F.SilkS")
		)
		(fp_line
			(start -6.427724 1.8415)
			(end 6.427724 1.8415)
			(stroke
				(width 0.1524)
				(type default)
			)
			(layer "F.SilkS")
		)
		(fp_line
			(start 5.050028 -1.560068)
			(end -5.050028 -1.560068)
			(stroke
				(width 0.1)
				(type default)
			)
			(layer "F.Fab")
		)
		(fp_line
			(start -5.050028 -1.560068)
			(end -5.050028 1.560068)
			(stroke
				(width 0.1)
				(type default)
			)
			(layer "F.Fab")
		)
		(fp_line
			(start 5.050028 1.560068)
			(end 5.050028 -1.560068)
			(stroke
				(width 0.1)
				(type default)
			)
			(layer "F.Fab")
		)
		(fp_line
			(start -5.050028 1.560068)
			(end 5.050028 1.560068)
			(stroke
				(width 0.1)
				(type default)
			)
			(layer "F.Fab")
		)
		(pad "1" smd rect
			(at -4.675124 0 90)
			(size 3.2512 3.429)
			(layers "F.Cu" "F.Mask" "F.Paste")
			(net "P52V_1_FUSE_1")
		)
		(pad "2" smd rect
			(at 4.675124 0 90)
			(size 3.2512 3.429)
			(layers "F.Cu" "F.Mask" "F.Paste")
			(net "P52V_1")
		)
	)
	(footprint ""
		(layer "B.Cu")
		(at 272.288 -28.956)
		(property "Reference" "C102"
			(at 0 0 0)
			(layer "B.SilkS")
			(hide yes)
			(effects
				(font
					(size 1.27 1.27)
				)
				(justify mirror)
			)
		)
		(property "Value" ""
			(at 0 0 0)
			(layer "B.Fab")
			(effects
				(font
					(size 1.27 1.27)
				)
				(justify mirror)
			)
		)
		(duplicate_pad_numbers_are_jumpers no)
		(fp_line
			(start -0.7874 -0.4064)
			(end -0.7874 0.4064)
			(stroke
				(width 0.1524)
				(type default)
			)
			(layer "B.SilkS")
		)
		(fp_line
			(start -0.7874 0.4064)
			(end 0.7874 0.4064)
			(stroke
				(width 0.1524)
				(type default)
			)
			(layer "B.SilkS")
		)
		(fp_line
			(start 0.7874 -0.4064)
			(end -0.7874 -0.4064)
			(stroke
				(width 0.1524)
				(type default)
			)
			(layer "B.SilkS")
		)
		(fp_line
			(start 0.7874 0.4064)
			(end 0.7874 -0.4064)
			(stroke
				(width 0.1524)
				(type default)
			)
			(layer "B.SilkS")
		)
		(fp_line
			(start -0.67945 -0.3048)
			(end -0.67945 0.3048)
			(stroke
				(width 0.1)
				(type default)
			)
			(layer "B.Fab")
		)
		(fp_line
			(start -0.67945 0.3048)
			(end -0.120396 0.3048)
			(stroke
				(width 0.1)
				(type default)
			)
			(layer "B.Fab")
		)
		(fp_line
			(start -0.12065 -0.3048)
			(end -0.67945 -0.3048)
			(stroke
				(width 0.1)
				(type default)
			)
			(layer "B.Fab")
		)
		(fp_line
			(start -0.12065 -0.2794)
			(end -0.12065 -0.3048)
			(stroke
				(width 0.1)
				(type default)
			)
			(layer "B.Fab")
		)
		(fp_line
			(start -0.120396 0.2794)
			(end 0.12065 0.2794)
			(stroke
				(width 0.1)
				(type default)
			)
			(layer "B.Fab")
		)
		(fp_line
			(start -0.120396 0.3048)
			(end -0.120396 0.2794)
			(stroke
				(width 0.1)
				(type default)
			)
			(layer "B.Fab")
		)
		(fp_line
			(start 0.12065 -0.305054)
			(end 0.12065 -0.2794)
			(stroke
				(width 0.1)
				(type default)
			)
			(layer "B.Fab")
		)
		(fp_line
			(start 0.12065 -0.2794)
			(end -0.12065 -0.2794)
			(stroke
				(width 0.1)
				(type default)
			)
			(layer "B.Fab")
		)
		(fp_line
			(start 0.12065 0.2794)
			(end 0.12065 0.3048)
			(stroke
				(width 0.1)
				(type default)
			)
			(layer "B.Fab")
		)
		(fp_line
			(start 0.12065 0.3048)
			(end 0.67945 0.3048)
			(stroke
				(width 0.1)
				(type default)
			)
			(layer "B.Fab")
		)
		(fp_line
			(start 0.67945 -0.305054)
			(end 0.12065 -0.305054)
			(stroke
				(width 0.1)
				(type default)
			)
			(layer "B.Fab")
		)
		(fp_line
			(start 0.67945 0.3048)
			(end 0.67945 -0.305054)
			(stroke
				(width 0.1)
				(type default)
			)
			(layer "B.Fab")
		)
		(pad "1" smd circle
			(at 0.40005 0 180)
			(size 0 0)
			(layers "B.Cu" "B.Mask" "B.Paste")
			(net "FM_AC_PWR_CYCLE_R_BUF")
		)
		(pad "2" smd circle
			(at -0.40005 0 180)
			(size 0 0)
			(layers "B.Cu" "B.Mask" "B.Paste")
			(net "GND")
		)
	)
	(footprint ""
		(layer "B.Cu")
		(at 103.886 -76.708 90)
		(property "Reference" "PR324"
			(at 0 0 90)
			(layer "B.SilkS")
			(hide yes)
			(effects
				(font
					(size 1.27 1.27)
				)
				(justify mirror)
			)
		)
		(property "Value" ""
			(at 0 0 90)
			(layer "B.Fab")
			(effects
				(font
					(size 1.27 1.27)
				)
				(justify mirror)
			)
		)
		(duplicate_pad_numbers_are_jumpers no)
		(fp_line
			(start 0.7874 -0.4064)
			(end -0.7874 -0.4064)
			(stroke
				(width 0.1524)
				(type default)
			)
			(layer "B.SilkS")
		)
		(fp_line
			(start -0.7874 -0.4064)
			(end -0.7874 0.4064)
			(stroke
				(width 0.1524)
				(type default)
			)
			(layer "B.SilkS")
		)
		(fp_line
			(start 0.7874 0.4064)
			(end 0.7874 -0.4064)
			(stroke
				(width 0.1524)
				(type default)
			)
			(layer "B.SilkS")
		)
		(fp_line
			(start -0.7874 0.4064)
			(end 0.7874 0.4064)
			(stroke
				(width 0.1524)
				(type default)
			)
			(layer "B.SilkS")
		)
		(fp_line
			(start 0.67945 -0.305054)
			(end 0.12065 -0.305054)
			(stroke
				(width 0.1)
				(type default)
			)
			(layer "B.Fab")
		)
		(fp_line
			(start 0.12065 -0.305054)
			(end 0.12065 -0.2794)
			(stroke
				(width 0.1)
				(type default)
			)
			(layer "B.Fab")
		)
		(fp_line
			(start -0.12065 -0.3048)
			(end -0.67945 -0.3048)
			(stroke
				(width 0.1)
				(type default)
			)
			(layer "B.Fab")
		)
		(fp_line
			(start -0.67945 -0.3048)
			(end -0.67945 0.3048)
			(stroke
				(width 0.1)
				(type default)
			)
			(layer "B.Fab")
		)
		(fp_line
			(start 0.12065 -0.2794)
			(end -0.12065 -0.2794)
			(stroke
				(width 0.1)
				(type default)
			)
			(layer "B.Fab")
		)
		(fp_line
			(start -0.12065 -0.2794)
			(end -0.12065 -0.3048)
			(stroke
				(width 0.1)
				(type default)
			)
			(layer "B.Fab")
		)
		(fp_line
			(start 0.12065 0.2794)
			(end 0.12065 0.3048)
			(stroke
				(width 0.1)
				(type default)
			)
			(layer "B.Fab")
		)
		(fp_line
			(start -0.120396 0.2794)
			(end 0.12065 0.2794)
			(stroke
				(width 0.1)
				(type default)
			)
			(layer "B.Fab")
		)
		(fp_line
			(start 0.67945 0.3048)
			(end 0.67945 -0.305054)
			(stroke
				(width 0.1)
				(type default)
			)
			(layer "B.Fab")
		)
		(fp_line
			(start 0.12065 0.3048)
			(end 0.67945 0.3048)
			(stroke
				(width 0.1)
				(type default)
			)
			(layer "B.Fab")
		)
		(fp_line
			(start -0.120396 0.3048)
			(end -0.120396 0.2794)
			(stroke
				(width 0.1)
				(type default)
			)
			(layer "B.Fab")
		)
		(fp_line
			(start -0.67945 0.3048)
			(end -0.120396 0.3048)
			(stroke
				(width 0.1)
				(type default)
			)
			(layer "B.Fab")
		)
		(pad "1" smd circle
			(at 0.40005 0 270)
			(size 0 0)
			(layers "B.Cu" "B.Mask" "B.Paste")
			(net "P12V_MB1_SENSE+")
		)
		(pad "2" smd circle
			(at -0.40005 0 270)
			(size 0 0)
			(layers "B.Cu" "B.Mask" "B.Paste")
			(net "P12V_MB0_SENSE+")
		)
	)
	(footprint ""
		(layer "B.Cu")
		(at 292.608 -39.116 180)
		(property "Reference" "C100"
			(at 0 0 0)
			(layer "B.SilkS")
			(hide yes)
			(effects
				(font
					(size 1.27 1.27)
				)
				(justify mirror)
			)
		)
		(property "Value" ""
			(at 0 0 0)
			(layer "B.Fab")
			(effects
				(font
					(size 1.27 1.27)
				)
				(justify mirror)
			)
		)
		(duplicate_pad_numbers_are_jumpers no)
		(fp_line
			(start 0.7874 0.4064)
			(end 0.7874 -0.4064)
			(stroke
				(width 0.1524)
				(type default)
			)
			(layer "B.SilkS")
		)
		(fp_line
			(start 0.7874 -0.4064)
			(end -0.7874 -0.4064)
			(stroke
				(width 0.1524)
				(type default)
			)
			(layer "B.SilkS")
		)
		(fp_line
			(start -0.7874 0.4064)
			(end 0.7874 0.4064)
			(stroke
				(width 0.1524)
				(type default)
			)
			(layer "B.SilkS")
		)
		(fp_line
			(start -0.7874 -0.4064)
			(end -0.7874 0.4064)
			(stroke
				(width 0.1524)
				(type default)
			)
			(layer "B.SilkS")
		)
		(fp_line
			(start 0.67945 0.3048)
			(end 0.67945 -0.305054)
			(stroke
				(width 0.1)
				(type default)
			)
			(layer "B.Fab")
		)
		(fp_line
			(start 0.67945 -0.305054)
			(end 0.12065 -0.305054)
			(stroke
				(width 0.1)
				(type default)
			)
			(layer "B.Fab")
		)
		(fp_line
			(start 0.12065 0.3048)
			(end 0.67945 0.3048)
			(stroke
				(width 0.1)
				(type default)
			)
			(layer "B.Fab")
		)
		(fp_line
			(start 0.12065 0.2794)
			(end 0.12065 0.3048)
			(stroke
				(width 0.1)
				(type default)
			)
			(layer "B.Fab")
		)
		(fp_line
			(start 0.12065 -0.2794)
			(end -0.12065 -0.2794)
			(stroke
				(width 0.1)
				(type default)
			)
			(layer "B.Fab")
		)
		(fp_line
			(start 0.12065 -0.305054)
			(end 0.12065 -0.2794)
			(stroke
				(width 0.1)
				(type default)
			)
			(layer "B.Fab")
		)
		(fp_line
			(start -0.120396 0.3048)
			(end -0.120396 0.2794)
			(stroke
				(width 0.1)
				(type default)
			)
			(layer "B.Fab")
		)
		(fp_line
			(start -0.120396 0.2794)
			(end 0.12065 0.2794)
			(stroke
				(width 0.1)
				(type default)
			)
			(layer "B.Fab")
		)
		(fp_line
			(start -0.12065 -0.2794)
			(end -0.12065 -0.3048)
			(stroke
				(width 0.1)
				(type default)
			)
			(layer "B.Fab")
		)
		(fp_line
			(start -0.12065 -0.3048)
			(end -0.67945 -0.3048)
			(stroke
				(width 0.1)
				(type default)
			)
			(layer "B.Fab")
		)
		(fp_line
			(start -0.67945 0.3048)
			(end -0.120396 0.3048)
			(stroke
				(width 0.1)
				(type default)
			)
			(layer "B.Fab")
		)
		(fp_line
			(start -0.67945 -0.3048)
			(end -0.67945 0.3048)
			(stroke
				(width 0.1)
				(type default)
			)
			(layer "B.Fab")
		)
		(pad "1" smd circle
			(at 0.40005 0)
			(size 0 0)
			(layers "B.Cu" "B.Mask" "B.Paste")
			(net "FM_AC_PWR_CYCLE_R1_N")
		)
		(pad "2" smd circle
			(at -0.40005 0)
			(size 0 0)
			(layers "B.Cu" "B.Mask" "B.Paste")
			(net "GND")
		)
	)
	(footprint ""
		(layer "B.Cu")
		(at 236.982 -95.504 90)
		(property "Reference" "C32"
			(at 0 0 90)
			(layer "B.SilkS")
			(hide yes)
			(effects
				(font
					(size 1.27 1.27)
				)
				(justify mirror)
			)
		)
		(property "Value" ""
			(at 0 0 90)
			(layer "B.Fab")
			(effects
				(font
					(size 1.27 1.27)
				)
				(justify mirror)
			)
		)
		(duplicate_pad_numbers_are_jumpers no)
		(fp_line
			(start 2.2098 -0.9398)
			(end -2.2098 -0.9398)
			(stroke
				(width 0.1524)
				(type default)
			)
			(layer "B.SilkS")
		)
		(fp_line
			(start -2.2098 -0.9398)
			(end -2.2098 0.9398)
			(stroke
				(width 0.1524)
				(type default)
			)
			(layer "B.SilkS")
		)
		(fp_line
			(start 2.2098 0.9398)
			(end 2.2098 -0.9398)
			(stroke
				(width 0.1524)
				(type default)
			)
			(layer "B.SilkS")
		)
		(fp_line
			(start -2.2098 0.9398)
			(end 2.2098 0.9398)
			(stroke
				(width 0.1524)
				(type default)
			)
			(layer "B.SilkS")
		)
		(fp_line
			(start 1.700022 -0.899922)
			(end -1.700022 -0.899922)
			(stroke
				(width 0.1)
				(type default)
			)
			(layer "B.Fab")
		)
		(fp_line
			(start -1.700022 -0.899922)
			(end -1.700022 0.899922)
			(stroke
				(width 0.1)
				(type default)
			)
			(layer "B.Fab")
		)
		(fp_line
			(start 1.700022 0.899922)
			(end 1.700022 -0.899922)
			(stroke
				(width 0.1)
				(type default)
			)
			(layer "B.Fab")
		)
		(fp_line
			(start -1.700022 0.899922)
			(end 1.700022 0.899922)
			(stroke
				(width 0.1)
				(type default)
			)
			(layer "B.Fab")
		)
		(pad "1" smd rect
			(at 1.4732 0 90)
			(size 1.1684 1.5748)
			(layers "B.Cu" "B.Mask" "B.Paste")
			(net "P52V_HS")
		)
		(pad "2" smd rect
			(at -1.4732 0 90)
			(size 1.1684 1.5748)
			(layers "B.Cu" "B.Mask" "B.Paste")
			(net "GND")
		)
	)
	(footprint ""
		(layer "B.Cu")
		(at 277.709122 -93.203522 90)
		(property "Reference" "PC563"
			(at 0 0 90)
			(layer "B.SilkS")
			(hide yes)
			(effects
				(font
					(size 1.27 1.27)
				)
				(justify mirror)
			)
		)
		(property "Value" ""
			(at 0 0 90)
			(layer "B.Fab")
			(effects
				(font
					(size 1.27 1.27)
				)
				(justify mirror)
			)
		)
		(duplicate_pad_numbers_are_jumpers no)
		(fp_line
			(start 1.2954 -0.5842)
			(end -1.2954 -0.5842)
			(stroke
				(width 0.1524)
				(type default)
			)
			(layer "B.SilkS")
		)
		(fp_line
			(start -1.2954 -0.5842)
			(end -1.2954 0.5842)
			(stroke
				(width 0.1524)
				(type default)
			)
			(layer "B.SilkS")
		)
		(fp_line
			(start 1.2954 0.5842)
			(end 1.2954 -0.5842)
			(stroke
				(width 0.1524)
				(type default)
			)
			(layer "B.SilkS")
		)
		(fp_line
			(start -1.2954 0.5842)
			(end 1.2954 0.5842)
			(stroke
				(width 0.1524)
				(type default)
			)
			(layer "B.SilkS")
		)
		(fp_line
			(start 0.8636 -0.4572)
			(end -0.8636 -0.4572)
			(stroke
				(width 0.1)
				(type default)
			)
			(layer "B.Fab")
		)
		(fp_line
			(start -0.8636 -0.4572)
			(end -0.8636 -0.4064)
			(stroke
				(width 0.1)
				(type default)
			)
			(layer "B.Fab")
		)
		(fp_line
			(start 1.1938 -0.4064)
			(end 0.8636 -0.4064)
			(stroke
				(width 0.1)
				(type default)
			)
			(layer "B.Fab")
		)
		(fp_line
			(start 0.8636 -0.4064)
			(end 0.8636 -0.4572)
			(stroke
				(width 0.1)
				(type default)
			)
			(layer "B.Fab")
		)
		(fp_line
			(start -0.8636 -0.4064)
			(end -1.1938 -0.4064)
			(stroke
				(width 0.1)
				(type default)
			)
			(layer "B.Fab")
		)
		(fp_line
			(start -1.1938 -0.4064)
			(end -1.1938 0.4064)
			(stroke
				(width 0.1)
				(type default)
			)
			(layer "B.Fab")
		)
		(fp_line
			(start 1.1938 0.4064)
			(end 1.1938 -0.4064)
			(stroke
				(width 0.1)
				(type default)
			)
			(layer "B.Fab")
		)
		(fp_line
			(start 0.8636 0.4064)
			(end 1.1938 0.4064)
			(stroke
				(width 0.1)
				(type default)
			)
			(layer "B.Fab")
		)
		(fp_line
			(start -0.8636 0.4064)
			(end -0.8636 0.4572)
			(stroke
				(width 0.1)
				(type default)
			)
			(layer "B.Fab")
		)
		(fp_line
			(start -1.1938 0.4064)
			(end -0.8636 0.4064)
			(stroke
				(width 0.1)
				(type default)
			)
			(layer "B.Fab")
		)
		(fp_line
			(start 0.8636 0.4572)
			(end 0.8636 0.4064)
			(stroke
				(width 0.1)
				(type default)
			)
			(layer "B.Fab")
		)
		(fp_line
			(start -0.8636 0.4572)
			(end 0.8636 0.4572)
			(stroke
				(width 0.1)
				(type default)
			)
			(layer "B.Fab")
		)
		(pad "1" smd rect
			(at 0.7366 0)
			(size 0.7112 0.8128)
			(layers "B.Cu" "B.Mask" "B.Paste")
			(net "GND")
		)
		(pad "2" smd rect
			(at -0.7366 0)
			(size 0.7112 0.8128)
			(layers "B.Cu" "B.Mask" "B.Paste")
			(net "P52V_HS1_GATE2_R1")
		)
	)
	(footprint ""
		(layer "B.Cu")
		(at 189.611 -82.423)
		(property "Reference" "R105"
			(at 0 0 0)
			(layer "B.SilkS")
			(hide yes)
			(effects
				(font
					(size 1.27 1.27)
				)
				(justify mirror)
			)
		)
		(property "Value" ""
			(at 0 0 0)
			(layer "B.Fab")
			(effects
				(font
					(size 1.27 1.27)
				)
				(justify mirror)
			)
		)
		(duplicate_pad_numbers_are_jumpers no)
		(fp_line
			(start -0.7874 -0.4064)
			(end -0.7874 0.4064)
			(stroke
				(width 0.1524)
				(type default)
			)
			(layer "B.SilkS")
		)
		(fp_line
			(start -0.7874 0.4064)
			(end 0.7874 0.4064)
			(stroke
				(width 0.1524)
				(type default)
			)
			(layer "B.SilkS")
		)
		(fp_line
			(start 0.7874 -0.4064)
			(end -0.7874 -0.4064)
			(stroke
				(width 0.1524)
				(type default)
			)
			(layer "B.SilkS")
		)
		(fp_line
			(start 0.7874 0.4064)
			(end 0.7874 -0.4064)
			(stroke
				(width 0.1524)
				(type default)
			)
			(layer "B.SilkS")
		)
		(fp_line
			(start -0.67945 -0.3048)
			(end -0.67945 0.3048)
			(stroke
				(width 0.1)
				(type default)
			)
			(layer "B.Fab")
		)
		(fp_line
			(start -0.67945 0.3048)
			(end -0.120396 0.3048)
			(stroke
				(width 0.1)
				(type default)
			)
			(layer "B.Fab")
		)
		(fp_line
			(start -0.12065 -0.3048)
			(end -0.67945 -0.3048)
			(stroke
				(width 0.1)
				(type default)
			)
			(layer "B.Fab")
		)
		(fp_line
			(start -0.12065 -0.2794)
			(end -0.12065 -0.3048)
			(stroke
				(width 0.1)
				(type default)
			)
			(layer "B.Fab")
		)
		(fp_line
			(start -0.120396 0.2794)
			(end 0.12065 0.2794)
			(stroke
				(width 0.1)
				(type default)
			)
			(layer "B.Fab")
		)
		(fp_line
			(start -0.120396 0.3048)
			(end -0.120396 0.2794)
			(stroke
				(width 0.1)
				(type default)
			)
			(layer "B.Fab")
		)
		(fp_line
			(start 0.12065 -0.305054)
			(end 0.12065 -0.2794)
			(stroke
				(width 0.1)
				(type default)
			)
			(layer "B.Fab")
		)
		(fp_line
			(start 0.12065 -0.2794)
			(end -0.12065 -0.2794)
			(stroke
				(width 0.1)
				(type default)
			)
			(layer "B.Fab")
		)
		(fp_line
			(start 0.12065 0.2794)
			(end 0.12065 0.3048)
			(stroke
				(width 0.1)
				(type default)
			)
			(layer "B.Fab")
		)
		(fp_line
			(start 0.12065 0.3048)
			(end 0.67945 0.3048)
			(stroke
				(width 0.1)
				(type default)
			)
			(layer "B.Fab")
		)
		(fp_line
			(start 0.67945 -0.305054)
			(end 0.12065 -0.305054)
			(stroke
				(width 0.1)
				(type default)
			)
			(layer "B.Fab")
		)
		(fp_line
			(start 0.67945 0.3048)
			(end 0.67945 -0.305054)
			(stroke
				(width 0.1)
				(type default)
			)
			(layer "B.Fab")
		)
		(pad "1" smd circle
			(at 0.40005 0 180)
			(size 0 0)
			(layers "B.Cu" "B.Mask" "B.Paste")
			(net "PU_9543_1_INT0")
		)
		(pad "2" smd circle
			(at -0.40005 0 180)
			(size 0 0)
			(layers "B.Cu" "B.Mask" "B.Paste")
			(net "P3V3_AUX")
		)
	)
	(footprint ""
		(layer "B.Cu")
		(at 210.185 -82.55 -90)
		(property "Reference" "R23"
			(at 0 0 90)
			(layer "B.SilkS")
			(hide yes)
			(effects
				(font
					(size 1.27 1.27)
				)
				(justify mirror)
			)
		)
		(property "Value" ""
			(at 0 0 90)
			(layer "B.Fab")
			(effects
				(font
					(size 1.27 1.27)
				)
				(justify mirror)
			)
		)
		(duplicate_pad_numbers_are_jumpers no)
		(fp_line
			(start -0.7874 0.4064)
			(end 0.7874 0.4064)
			(stroke
				(width 0.1524)
				(type default)
			)
			(layer "B.SilkS")
		)
		(fp_line
			(start 0.7874 0.4064)
			(end 0.7874 -0.4064)
			(stroke
				(width 0.1524)
				(type default)
			)
			(layer "B.SilkS")
		)
		(fp_line
			(start -0.7874 -0.4064)
			(end -0.7874 0.4064)
			(stroke
				(width 0.1524)
				(type default)
			)
			(layer "B.SilkS")
		)
		(fp_line
			(start 0.7874 -0.4064)
			(end -0.7874 -0.4064)
			(stroke
				(width 0.1524)
				(type default)
			)
			(layer "B.SilkS")
		)
		(fp_line
			(start -0.67945 0.3048)
			(end -0.120396 0.3048)
			(stroke
				(width 0.1)
				(type default)
			)
			(layer "B.Fab")
		)
		(fp_line
			(start -0.120396 0.3048)
			(end -0.120396 0.2794)
			(stroke
				(width 0.1)
				(type default)
			)
			(layer "B.Fab")
		)
		(fp_line
			(start 0.12065 0.3048)
			(end 0.67945 0.3048)
			(stroke
				(width 0.1)
				(type default)
			)
			(layer "B.Fab")
		)
		(fp_line
			(start 0.67945 0.3048)
			(end 0.67945 -0.305054)
			(stroke
				(width 0.1)
				(type default)
			)
			(layer "B.Fab")
		)
		(fp_line
			(start -0.120396 0.2794)
			(end 0.12065 0.2794)
			(stroke
				(width 0.1)
				(type default)
			)
			(layer "B.Fab")
		)
		(fp_line
			(start 0.12065 0.2794)
			(end 0.12065 0.3048)
			(stroke
				(width 0.1)
				(type default)
			)
			(layer "B.Fab")
		)
		(fp_line
			(start -0.12065 -0.2794)
			(end -0.12065 -0.3048)
			(stroke
				(width 0.1)
				(type default)
			)
			(layer "B.Fab")
		)
		(fp_line
			(start 0.12065 -0.2794)
			(end -0.12065 -0.2794)
			(stroke
				(width 0.1)
				(type default)
			)
			(layer "B.Fab")
		)
		(fp_line
			(start -0.67945 -0.3048)
			(end -0.67945 0.3048)
			(stroke
				(width 0.1)
				(type default)
			)
			(layer "B.Fab")
		)
		(fp_line
			(start -0.12065 -0.3048)
			(end -0.67945 -0.3048)
			(stroke
				(width 0.1)
				(type default)
			)
			(layer "B.Fab")
		)
		(fp_line
			(start 0.12065 -0.305054)
			(end 0.12065 -0.2794)
			(stroke
				(width 0.1)
				(type default)
			)
			(layer "B.Fab")
		)
		(fp_line
			(start 0.67945 -0.305054)
			(end 0.12065 -0.305054)
			(stroke
				(width 0.1)
				(type default)
			)
			(layer "B.Fab")
		)
		(pad "1" smd circle
			(at 0.40005 0 90)
			(size 0 0)
			(layers "B.Cu" "B.Mask" "B.Paste")
			(net "PCA9555_A2")
		)
		(pad "2" smd circle
			(at -0.40005 0 90)
			(size 0 0)
			(layers "B.Cu" "B.Mask" "B.Paste")
			(net "GND")
		)
	)
	(footprint ""
		(layer "B.Cu")
		(at 38.989 -85.217)
		(property "Reference" "R78"
			(at 0 0 0)
			(layer "B.SilkS")
			(hide yes)
			(effects
				(font
					(size 1.27 1.27)
				)
				(justify mirror)
			)
		)
		(property "Value" ""
			(at 0 0 0)
			(layer "B.Fab")
			(effects
				(font
					(size 1.27 1.27)
				)
				(justify mirror)
			)
		)
		(duplicate_pad_numbers_are_jumpers no)
		(fp_line
			(start -0.7874 -0.4064)
			(end -0.7874 0.4064)
			(stroke
				(width 0.1524)
				(type default)
			)
			(layer "B.SilkS")
		)
		(fp_line
			(start -0.7874 0.4064)
			(end 0.7874 0.4064)
			(stroke
				(width 0.1524)
				(type default)
			)
			(layer "B.SilkS")
		)
		(fp_line
			(start 0.7874 -0.4064)
			(end -0.7874 -0.4064)
			(stroke
				(width 0.1524)
				(type default)
			)
			(layer "B.SilkS")
		)
		(fp_line
			(start 0.7874 0.4064)
			(end 0.7874 -0.4064)
			(stroke
				(width 0.1524)
				(type default)
			)
			(layer "B.SilkS")
		)
		(fp_line
			(start -0.67945 -0.3048)
			(end -0.67945 0.3048)
			(stroke
				(width 0.1)
				(type default)
			)
			(layer "B.Fab")
		)
		(fp_line
			(start -0.67945 0.3048)
			(end -0.120396 0.3048)
			(stroke
				(width 0.1)
				(type default)
			)
			(layer "B.Fab")
		)
		(fp_line
			(start -0.12065 -0.3048)
			(end -0.67945 -0.3048)
			(stroke
				(width 0.1)
				(type default)
			)
			(layer "B.Fab")
		)
		(fp_line
			(start -0.12065 -0.2794)
			(end -0.12065 -0.3048)
			(stroke
				(width 0.1)
				(type default)
			)
			(layer "B.Fab")
		)
		(fp_line
			(start -0.120396 0.2794)
			(end 0.12065 0.2794)
			(stroke
				(width 0.1)
				(type default)
			)
			(layer "B.Fab")
		)
		(fp_line
			(start -0.120396 0.3048)
			(end -0.120396 0.2794)
			(stroke
				(width 0.1)
				(type default)
			)
			(layer "B.Fab")
		)
		(fp_line
			(start 0.12065 -0.305054)
			(end 0.12065 -0.2794)
			(stroke
				(width 0.1)
				(type default)
			)
			(layer "B.Fab")
		)
		(fp_line
			(start 0.12065 -0.2794)
			(end -0.12065 -0.2794)
			(stroke
				(width 0.1)
				(type default)
			)
			(layer "B.Fab")
		)
		(fp_line
			(start 0.12065 0.2794)
			(end 0.12065 0.3048)
			(stroke
				(width 0.1)
				(type default)
			)
			(layer "B.Fab")
		)
		(fp_line
			(start 0.12065 0.3048)
			(end 0.67945 0.3048)
			(stroke
				(width 0.1)
				(type default)
			)
			(layer "B.Fab")
		)
		(fp_line
			(start 0.67945 -0.305054)
			(end 0.12065 -0.305054)
			(stroke
				(width 0.1)
				(type default)
			)
			(layer "B.Fab")
		)
		(fp_line
			(start 0.67945 0.3048)
			(end 0.67945 -0.305054)
			(stroke
				(width 0.1)
				(type default)
			)
			(layer "B.Fab")
		)
		(pad "1" smd circle
			(at 0.40005 0 180)
			(size 0 0)
			(layers "B.Cu" "B.Mask" "B.Paste")
			(net "SMB_P52V_HPDB_SCL")
		)
		(pad "2" smd circle
			(at -0.40005 0 180)
			(size 0 0)
			(layers "B.Cu" "B.Mask" "B.Paste")
			(net "SMB_P52V_HPDB_R_SCL")
		)
	)
	(footprint ""
		(layer "B.Cu")
		(at 275.169122 -89.520522)
		(property "Reference" "PC564"
			(at 0 0 0)
			(layer "B.SilkS")
			(hide yes)
			(effects
				(font
					(size 1.27 1.27)
				)
				(justify mirror)
			)
		)
		(property "Value" ""
			(at 0 0 0)
			(layer "B.Fab")
			(effects
				(font
					(size 1.27 1.27)
				)
				(justify mirror)
			)
		)
		(duplicate_pad_numbers_are_jumpers no)
		(fp_line
			(start -1.2954 -0.5842)
			(end -1.2954 0.5842)
			(stroke
				(width 0.1524)
				(type default)
			)
			(layer "B.SilkS")
		)
		(fp_line
			(start -1.2954 0.5842)
			(end 1.2954 0.5842)
			(stroke
				(width 0.1524)
				(type default)
			)
			(layer "B.SilkS")
		)
		(fp_line
			(start 1.2954 -0.5842)
			(end -1.2954 -0.5842)
			(stroke
				(width 0.1524)
				(type default)
			)
			(layer "B.SilkS")
		)
		(fp_line
			(start 1.2954 0.5842)
			(end 1.2954 -0.5842)
			(stroke
				(width 0.1524)
				(type default)
			)
			(layer "B.SilkS")
		)
		(fp_line
			(start -1.1938 -0.4064)
			(end -1.1938 0.4064)
			(stroke
				(width 0.1)
				(type default)
			)
			(layer "B.Fab")
		)
		(fp_line
			(start -1.1938 0.4064)
			(end -0.8636 0.4064)
			(stroke
				(width 0.1)
				(type default)
			)
			(layer "B.Fab")
		)
		(fp_line
			(start -0.8636 -0.4572)
			(end -0.8636 -0.4064)
			(stroke
				(width 0.1)
				(type default)
			)
			(layer "B.Fab")
		)
		(fp_line
			(start -0.8636 -0.4064)
			(end -1.1938 -0.4064)
			(stroke
				(width 0.1)
				(type default)
			)
			(layer "B.Fab")
		)
		(fp_line
			(start -0.8636 0.4064)
			(end -0.8636 0.4572)
			(stroke
				(width 0.1)
				(type default)
			)
			(layer "B.Fab")
		)
		(fp_line
			(start -0.8636 0.4572)
			(end 0.8636 0.4572)
			(stroke
				(width 0.1)
				(type default)
			)
			(layer "B.Fab")
		)
		(fp_line
			(start 0.8636 -0.4572)
			(end -0.8636 -0.4572)
			(stroke
				(width 0.1)
				(type default)
			)
			(layer "B.Fab")
		)
		(fp_line
			(start 0.8636 -0.4064)
			(end 0.8636 -0.4572)
			(stroke
				(width 0.1)
				(type default)
			)
			(layer "B.Fab")
		)
		(fp_line
			(start 0.8636 0.4064)
			(end 1.1938 0.4064)
			(stroke
				(width 0.1)
				(type default)
			)
			(layer "B.Fab")
		)
		(fp_line
			(start 0.8636 0.4572)
			(end 0.8636 0.4064)
			(stroke
				(width 0.1)
				(type default)
			)
			(layer "B.Fab")
		)
		(fp_line
			(start 1.1938 -0.4064)
			(end 0.8636 -0.4064)
			(stroke
				(width 0.1)
				(type default)
			)
			(layer "B.Fab")
		)
		(fp_line
			(start 1.1938 0.4064)
			(end 1.1938 -0.4064)
			(stroke
				(width 0.1)
				(type default)
			)
			(layer "B.Fab")
		)
		(pad "1" smd rect
			(at 0.7366 0 270)
			(size 0.7112 0.8128)
			(layers "B.Cu" "B.Mask" "B.Paste")
			(net "P52V_HS1_4287_GATE2_R")
		)
		(pad "2" smd rect
			(at -0.7366 0 270)
			(size 0.7112 0.8128)
			(layers "B.Cu" "B.Mask" "B.Paste")
			(net "P52V_HS")
		)
	)
	(footprint ""
		(layer "B.Cu")
		(at 224.79 -95.504 90)
		(property "Reference" "C22"
			(at 0 0 90)
			(layer "B.SilkS")
			(hide yes)
			(effects
				(font
					(size 1.27 1.27)
				)
				(justify mirror)
			)
		)
		(property "Value" ""
			(at 0 0 90)
			(layer "B.Fab")
			(effects
				(font
					(size 1.27 1.27)
				)
				(justify mirror)
			)
		)
		(duplicate_pad_numbers_are_jumpers no)
		(fp_line
			(start 2.2098 -0.9398)
			(end -2.2098 -0.9398)
			(stroke
				(width 0.1524)
				(type default)
			)
			(layer "B.SilkS")
		)
		(fp_line
			(start -2.2098 -0.9398)
			(end -2.2098 0.9398)
			(stroke
				(width 0.1524)
				(type default)
			)
			(layer "B.SilkS")
		)
		(fp_line
			(start 2.2098 0.9398)
			(end 2.2098 -0.9398)
			(stroke
				(width 0.1524)
				(type default)
			)
			(layer "B.SilkS")
		)
		(fp_line
			(start -2.2098 0.9398)
			(end 2.2098 0.9398)
			(stroke
				(width 0.1524)
				(type default)
			)
			(layer "B.SilkS")
		)
		(fp_line
			(start 1.700022 -0.899922)
			(end -1.700022 -0.899922)
			(stroke
				(width 0.1)
				(type default)
			)
			(layer "B.Fab")
		)
		(fp_line
			(start -1.700022 -0.899922)
			(end -1.700022 0.899922)
			(stroke
				(width 0.1)
				(type default)
			)
			(layer "B.Fab")
		)
		(fp_line
			(start 1.700022 0.899922)
			(end 1.700022 -0.899922)
			(stroke
				(width 0.1)
				(type default)
			)
			(layer "B.Fab")
		)
		(fp_line
			(start -1.700022 0.899922)
			(end 1.700022 0.899922)
			(stroke
				(width 0.1)
				(type default)
			)
			(layer "B.Fab")
		)
		(pad "1" smd rect
			(at 1.4732 0 90)
			(size 1.1684 1.5748)
			(layers "B.Cu" "B.Mask" "B.Paste")
			(net "P52V_HS")
		)
		(pad "2" smd rect
			(at -1.4732 0 90)
			(size 1.1684 1.5748)
			(layers "B.Cu" "B.Mask" "B.Paste")
			(net "GND")
		)
	)
	(footprint ""
		(layer "B.Cu")
		(at 182.850282 -76.708 -90)
		(property "Reference" "PR318"
			(at 0 0 90)
			(layer "B.SilkS")
			(hide yes)
			(effects
				(font
					(size 1.27 1.27)
				)
				(justify mirror)
			)
		)
		(property "Value" ""
			(at 0 0 90)
			(layer "B.Fab")
			(effects
				(font
					(size 1.27 1.27)
				)
				(justify mirror)
			)
		)
		(duplicate_pad_numbers_are_jumpers no)
		(fp_line
			(start -0.7874 0.4064)
			(end 0.7874 0.4064)
			(stroke
				(width 0.1524)
				(type default)
			)
			(layer "B.SilkS")
		)
		(fp_line
			(start 0.7874 0.4064)
			(end 0.7874 -0.4064)
			(stroke
				(width 0.1524)
				(type default)
			)
			(layer "B.SilkS")
		)
		(fp_line
			(start -0.7874 -0.4064)
			(end -0.7874 0.4064)
			(stroke
				(width 0.1524)
				(type default)
			)
			(layer "B.SilkS")
		)
		(fp_line
			(start 0.7874 -0.4064)
			(end -0.7874 -0.4064)
			(stroke
				(width 0.1524)
				(type default)
			)
			(layer "B.SilkS")
		)
		(fp_line
			(start -0.67945 0.3048)
			(end -0.120396 0.3048)
			(stroke
				(width 0.1)
				(type default)
			)
			(layer "B.Fab")
		)
		(fp_line
			(start -0.120396 0.3048)
			(end -0.120396 0.2794)
			(stroke
				(width 0.1)
				(type default)
			)
			(layer "B.Fab")
		)
		(fp_line
			(start 0.12065 0.3048)
			(end 0.67945 0.3048)
			(stroke
				(width 0.1)
				(type default)
			)
			(layer "B.Fab")
		)
		(fp_line
			(start 0.67945 0.3048)
			(end 0.67945 -0.305054)
			(stroke
				(width 0.1)
				(type default)
			)
			(layer "B.Fab")
		)
		(fp_line
			(start -0.120396 0.2794)
			(end 0.12065 0.2794)
			(stroke
				(width 0.1)
				(type default)
			)
			(layer "B.Fab")
		)
		(fp_line
			(start 0.12065 0.2794)
			(end 0.12065 0.3048)
			(stroke
				(width 0.1)
				(type default)
			)
			(layer "B.Fab")
		)
		(fp_line
			(start -0.12065 -0.2794)
			(end -0.12065 -0.3048)
			(stroke
				(width 0.1)
				(type default)
			)
			(layer "B.Fab")
		)
		(fp_line
			(start 0.12065 -0.2794)
			(end -0.12065 -0.2794)
			(stroke
				(width 0.1)
				(type default)
			)
			(layer "B.Fab")
		)
		(fp_line
			(start -0.67945 -0.3048)
			(end -0.67945 0.3048)
			(stroke
				(width 0.1)
				(type default)
			)
			(layer "B.Fab")
		)
		(fp_line
			(start -0.12065 -0.3048)
			(end -0.67945 -0.3048)
			(stroke
				(width 0.1)
				(type default)
			)
			(layer "B.Fab")
		)
		(fp_line
			(start 0.12065 -0.305054)
			(end 0.12065 -0.2794)
			(stroke
				(width 0.1)
				(type default)
			)
			(layer "B.Fab")
		)
		(fp_line
			(start 0.67945 -0.305054)
			(end 0.12065 -0.305054)
			(stroke
				(width 0.1)
				(type default)
			)
			(layer "B.Fab")
		)
		(pad "1" smd rect
			(at 0.40005 0 270)
			(size 0.4572 0.508)
			(layers "B.Cu" "B.Mask" "B.Paste")
			(net "P12V_MB2_SENSE+")
		)
		(pad "2" smd rect
			(at -0.40005 0 270)
			(size 0.4572 0.508)
			(layers "B.Cu" "B.Mask" "B.Paste")
			(net "P12V_BRICK")
		)
	)
	(footprint ""
		(layer "B.Cu")
		(at 238.047784 -84.17179 90)
		(property "Reference" "U1"
			(at -0.47879 -2.235454 270)
			(unlocked yes)
			(layer "B.SilkS")
			(effects
				(font
					(size 0.7874 0.5842)
					(thickness 0.1524)
				)
				(justify left mirror)
			)
		)
		(property "Value" ""
			(at 0 0 90)
			(layer "B.Fab")
			(effects
				(font
					(size 1.27 1.27)
				)
				(justify mirror)
			)
		)
		(duplicate_pad_numbers_are_jumpers no)
		(fp_line
			(start 1.3716 -1.524)
			(end 0.508 -1.524)
			(stroke
				(width 0.1524)
				(type default)
			)
			(layer "B.SilkS")
		)
		(fp_line
			(start 0.508 -1.524)
			(end 0 -1.016)
			(stroke
				(width 0.1524)
				(type default)
			)
			(layer "B.SilkS")
		)
		(fp_line
			(start -0.508 -1.524)
			(end -1.3716 -1.524)
			(stroke
				(width 0.1524)
				(type default)
			)
			(layer "B.SilkS")
		)
		(fp_line
			(start -1.3716 -1.524)
			(end -1.3716 1.524)
			(stroke
				(width 0.1524)
				(type default)
			)
			(layer "B.SilkS")
		)
		(fp_line
			(start 0 -1.016)
			(end -0.508 -1.524)
			(stroke
				(width 0.1524)
				(type default)
			)
			(layer "B.SilkS")
		)
		(fp_line
			(start 1.3716 1.524)
			(end 1.3716 -1.524)
			(stroke
				(width 0.1524)
				(type default)
			)
			(layer "B.SilkS")
		)
		(fp_line
			(start -1.3716 1.524)
			(end 1.3716 1.524)
			(stroke
				(width 0.1524)
				(type default)
			)
			(layer "B.SilkS")
		)
		(fp_poly
			(pts
				(xy 2.661666 -2.352294) (xy 2.036826 -2.352294) (xy 2.364994 -1.798574)
			)
			(stroke
				(width 0)
				(type default)
			)
			(fill yes)
			(layer "B.SilkS")
		)
		(fp_line
			(start 1.5494 -1.524)
			(end -1.5494 -1.524)
			(stroke
				(width 0.1)
				(type default)
			)
			(layer "B.Fab")
		)
		(fp_line
			(start -1.5494 -1.524)
			(end -1.5494 -1.0668)
			(stroke
				(width 0.1)
				(type default)
			)
			(layer "B.Fab")
		)
		(fp_line
			(start 2.54 -1.0668)
			(end 1.5494 -1.0668)
			(stroke
				(width 0.1)
				(type default)
			)
			(layer "B.Fab")
		)
		(fp_line
			(start 1.5494 -1.0668)
			(end 1.5494 -1.524)
			(stroke
				(width 0.1)
				(type default)
			)
			(layer "B.Fab")
		)
		(fp_line
			(start -1.5494 -1.0668)
			(end -2.54 -1.0668)
			(stroke
				(width 0.1)
				(type default)
			)
			(layer "B.Fab")
		)
		(fp_line
			(start -1.5494 -1.0668)
			(end -1.5494 1.0668)
			(stroke
				(width 0.1)
				(type default)
			)
			(layer "B.Fab")
		)
		(fp_line
			(start -2.54 -1.0668)
			(end -2.54 1.0668)
			(stroke
				(width 0.1)
				(type default)
			)
			(layer "B.Fab")
		)
		(fp_line
			(start 2.54 1.0668)
			(end 2.54 -1.0668)
			(stroke
				(width 0.1)
				(type default)
			)
			(layer "B.Fab")
		)
		(fp_line
			(start 1.5494 1.0668)
			(end 1.5494 -1.0668)
			(stroke
				(width 0.1)
				(type default)
			)
			(layer "B.Fab")
		)
		(fp_line
			(start 1.5494 1.0668)
			(end 2.54 1.0668)
			(stroke
				(width 0.1)
				(type default)
			)
			(layer "B.Fab")
		)
		(fp_line
			(start -1.5494 1.0668)
			(end -1.5494 1.524)
			(stroke
				(width 0.1)
				(type default)
			)
			(layer "B.Fab")
		)
		(fp_line
			(start -2.54 1.0668)
			(end -1.5494 1.0668)
			(stroke
				(width 0.1)
				(type default)
			)
			(layer "B.Fab")
		)
		(fp_line
			(start 1.5494 1.524)
			(end 1.5494 1.0668)
			(stroke
				(width 0.1)
				(type default)
			)
			(layer "B.Fab")
		)
		(fp_line
			(start -1.5494 1.524)
			(end 1.5494 1.524)
			(stroke
				(width 0.1)
				(type default)
			)
			(layer "B.Fab")
		)
		(fp_poly
			(pts
				(xy 3.60172 -0.719328) (xy 3.60172 -1.344168) (xy 3.048 -1.016)
			)
			(stroke
				(width 0)
				(type default)
			)
			(fill yes)
			(layer "B.Fab")
		)
		(pad "1" smd rect
			(at 2.232406 -0.975106)
			(size 0.3556 1.4224)
			(layers "B.Cu" "B.Mask" "B.Paste")
			(net "MB_MISC_I2C_EN")
		)
		(pad "2" smd rect
			(at 2.232406 -0.32512)
			(size 0.3556 1.4224)
			(layers "B.Cu" "B.Mask" "B.Paste")
			(net "SMB_PDB_MISC_SCL_R")
		)
		(pad "3" smd rect
			(at 2.232406 0.32512)
			(size 0.3556 1.4224)
			(layers "B.Cu" "B.Mask" "B.Paste")
			(net "SMB_MB_PDB_SCL")
		)
		(pad "4" smd rect
			(at 2.232406 0.975106)
			(size 0.3556 1.4224)
			(layers "B.Cu" "B.Mask" "B.Paste")
			(net "GND")
		)
		(pad "5" smd rect
			(at -2.232406 0.975106)
			(size 0.3556 1.4224)
			(layers "B.Cu" "B.Mask" "B.Paste")
			(net "NC_U1_READY")
		)
		(pad "6" smd rect
			(at -2.232406 0.32512)
			(size 0.3556 1.4224)
			(layers "B.Cu" "B.Mask" "B.Paste")
			(net "SMB_MB_PDB_SDA")
		)
		(pad "7" smd rect
			(at -2.232406 -0.32512)
			(size 0.3556 1.4224)
			(layers "B.Cu" "B.Mask" "B.Paste")
			(net "SMB_PDB_MISC_SDA_R")
		)
		(pad "8" smd rect
			(at -2.232406 -0.975106)
			(size 0.3556 1.4224)
			(layers "B.Cu" "B.Mask" "B.Paste")
			(net "P3V3_AUX")
		)
	)
	(footprint ""
		(layer "B.Cu")
		(at 195.961 -88.392)
		(property "Reference" "U25"
			(at 4.699 -4.67233 0)
			(unlocked yes)
			(layer "B.SilkS")
			(effects
				(font
					(size 0.7874 0.5842)
					(thickness 0.1524)
				)
				(justify left mirror)
			)
		)
		(property "Value" ""
			(at 0 0 0)
			(layer "B.Fab")
			(effects
				(font
					(size 1.27 1.27)
				)
				(justify mirror)
			)
		)
		(duplicate_pad_numbers_are_jumpers no)
		(fp_line
			(start -2.161032 -3.299968)
			(end -2.161032 3.299968)
			(stroke
				(width 0.1524)
				(type default)
			)
			(layer "B.SilkS")
		)
		(fp_line
			(start -2.161032 3.299968)
			(end 2.161032 3.299968)
			(stroke
				(width 0.1524)
				(type default)
			)
			(layer "B.SilkS")
		)
		(fp_line
			(start -1.013968 -3.299968)
			(end -2.161032 -3.299968)
			(stroke
				(width 0.1524)
				(type default)
			)
			(layer "B.SilkS")
		)
		(fp_line
			(start 0 -2.54)
			(end -1.013968 -3.299968)
			(stroke
				(width 0.1524)
				(type default)
			)
			(layer "B.SilkS")
		)
		(fp_line
			(start 1.013968 -3.299968)
			(end 0 -2.54)
			(stroke
				(width 0.1524)
				(type default)
			)
			(layer "B.SilkS")
		)
		(fp_line
			(start 2.161032 -3.299968)
			(end 1.013968 -3.299968)
			(stroke
				(width 0.1524)
				(type default)
			)
			(layer "B.SilkS")
		)
		(fp_line
			(start 2.161032 3.299968)
			(end 2.161032 -3.299968)
			(stroke
				(width 0.1524)
				(type default)
			)
			(layer "B.SilkS")
		)
		(fp_poly
			(pts
				(xy 4.572 -3.433064) (xy 4.572 -2.417064) (xy 3.556 -2.925064)
			)
			(stroke
				(width 0)
				(type default)
			)
			(fill yes)
			(layer "B.SilkS")
		)
		(fp_line
			(start -2.249932 -3.299968)
			(end 2.249932 -3.299968)
			(stroke
				(width 0.1)
				(type default)
			)
			(layer "B.Fab")
		)
		(fp_line
			(start -2.249932 3.299968)
			(end -2.249932 -3.299968)
			(stroke
				(width 0.1)
				(type default)
			)
			(layer "B.Fab")
		)
		(fp_line
			(start 2.249932 -3.299968)
			(end 2.249932 3.299968)
			(stroke
				(width 0.1)
				(type default)
			)
			(layer "B.Fab")
		)
		(fp_line
			(start 2.249932 3.299968)
			(end -2.249932 3.299968)
			(stroke
				(width 0.1)
				(type default)
			)
			(layer "B.Fab")
		)
		(fp_poly
			(pts
				(xy 4.572 -3.433064) (xy 4.572 -2.417064) (xy 3.556 -2.925064)
			)
			(stroke
				(width 0)
				(type default)
			)
			(fill yes)
			(layer "B.Fab")
		)
		(pad "1" smd rect
			(at 2.84988 -2.925064 270)
			(size 0.4064 1.1176)
			(layers "B.Cu" "B.Mask" "B.Paste")
			(net "PCA9543_MISC_A0")
		)
		(pad "2" smd rect
			(at 2.84988 -2.275078 270)
			(size 0.4064 1.1176)
			(layers "B.Cu" "B.Mask" "B.Paste")
			(net "PCA9543_MISC_A1")
		)
		(pad "3" smd rect
			(at 2.84988 -1.625092 270)
			(size 0.4064 1.1176)
			(layers "B.Cu" "B.Mask" "B.Paste")
			(net "RST_SMB_PDB_BUF_R1_N")
		)
		(pad "4" smd rect
			(at 2.84988 -0.975106 270)
			(size 0.4064 1.1176)
			(layers "B.Cu" "B.Mask" "B.Paste")
			(net "PU_9543_0_INT0")
		)
		(pad "5" smd rect
			(at 2.84988 -0.32512 270)
			(size 0.4064 1.1176)
			(layers "B.Cu" "B.Mask" "B.Paste")
			(net "SMB_VPDB_MISC_SDA")
		)
		(pad "6" smd rect
			(at 2.84988 0.32512 270)
			(size 0.4064 1.1176)
			(layers "B.Cu" "B.Mask" "B.Paste")
			(net "SMB_VPDB_MISC_SCL")
		)
		(pad "7" smd rect
			(at 2.84988 0.975106 270)
			(size 0.4064 1.1176)
			(layers "B.Cu" "B.Mask" "B.Paste")
			(net "PU_9543_0_INT1")
		)
		(pad "8" smd rect
			(at 2.84988 1.625092 270)
			(size 0.4064 1.1176)
			(layers "B.Cu" "B.Mask" "B.Paste")
			(net "SMB_HPDB_MISC_SDA")
		)
		(pad "9" smd rect
			(at 2.84988 2.275078 270)
			(size 0.4064 1.1176)
			(layers "B.Cu" "B.Mask" "B.Paste")
			(net "SMB_HPDB_MISC_SCL")
		)
		(pad "10" smd rect
			(at 2.84988 2.925064 270)
			(size 0.4064 1.1176)
			(layers "B.Cu" "B.Mask" "B.Paste")
			(net "GND")
		)
		(pad "11" smd rect
			(at -2.84988 2.925064 270)
			(size 0.4064 1.1176)
			(layers "B.Cu" "B.Mask" "B.Paste")
			(net "PU_9543_1_INT0")
		)
		(pad "12" smd rect
			(at -2.84988 2.275078 270)
			(size 0.4064 1.1176)
			(layers "B.Cu" "B.Mask" "B.Paste")
			(net "SMB_P52V_VPDB_SDA")
		)
		(pad "13" smd rect
			(at -2.84988 1.625092 270)
			(size 0.4064 1.1176)
			(layers "B.Cu" "B.Mask" "B.Paste")
			(net "SMB_P52V_VPDB_SCL_R")
		)
		(pad "14" smd rect
			(at -2.84988 0.975106 270)
			(size 0.4064 1.1176)
			(layers "B.Cu" "B.Mask" "B.Paste")
			(net "PU_9543_1_INT1")
		)
		(pad "15" smd rect
			(at -2.84988 0.32512 270)
			(size 0.4064 1.1176)
			(layers "B.Cu" "B.Mask" "B.Paste")
			(net "SMB_P52V_HPDB_SDA")
		)
		(pad "16" smd rect
			(at -2.84988 -0.32512 270)
			(size 0.4064 1.1176)
			(layers "B.Cu" "B.Mask" "B.Paste")
			(net "SMB_P52V_HPDB_SCL")
		)
		(pad "17" smd rect
			(at -2.84988 -0.975106 270)
			(size 0.4064 1.1176)
			(layers "B.Cu" "B.Mask" "B.Paste")
			(net "TP_9543_MISC_INT_N")
		)
		(pad "18" smd rect
			(at -2.84988 -1.625092 270)
			(size 0.4064 1.1176)
			(layers "B.Cu" "B.Mask" "B.Paste")
			(net "SMB_PDB_MISC_SCL")
		)
		(pad "19" smd rect
			(at -2.84988 -2.275078 270)
			(size 0.4064 1.1176)
			(layers "B.Cu" "B.Mask" "B.Paste")
			(net "SMB_PDB_MISC_SDA")
		)
		(pad "20" smd rect
			(at -2.84988 -2.925064 270)
			(size 0.4064 1.1176)
			(layers "B.Cu" "B.Mask" "B.Paste")
			(net "P3V3_AUX")
		)
	)
	(footprint ""
		(layer "B.Cu")
		(at 289.38093 -38.032436 180)
		(property "Reference" "D6"
			(at -2.0828 1.28143 0)
			(unlocked yes)
			(layer "B.SilkS")
			(effects
				(font
					(size 0.7874 0.5842)
					(thickness 0.1524)
				)
				(justify left mirror)
			)
		)
		(property "Value" ""
			(at 0 0 0)
			(layer "B.Fab")
			(effects
				(font
					(size 1.27 1.27)
				)
				(justify mirror)
			)
		)
		(duplicate_pad_numbers_are_jumpers no)
		(fp_line
			(start 2.050796 0.700024)
			(end 2.050796 -0.700024)
			(stroke
				(width 0.1524)
				(type default)
			)
			(layer "B.SilkS")
		)
		(fp_line
			(start 2.050796 -0.700024)
			(end -2.050796 -0.700024)
			(stroke
				(width 0.1524)
				(type default)
			)
			(layer "B.SilkS")
		)
		(fp_line
			(start 0.30607 0.500126)
			(end -0.193802 0)
			(stroke
				(width 0.1524)
				(type default)
			)
			(layer "B.SilkS")
		)
		(fp_line
			(start 0.30607 -0.500126)
			(end 0.30607 0.500126)
			(stroke
				(width 0.1524)
				(type default)
			)
			(layer "B.SilkS")
		)
		(fp_line
			(start -0.193802 0)
			(end 0.30607 -0.500126)
			(stroke
				(width 0.1524)
				(type default)
			)
			(layer "B.SilkS")
		)
		(fp_line
			(start -0.293878 -0.500126)
			(end -0.293878 0.500126)
			(stroke
				(width 0.1524)
				(type default)
			)
			(layer "B.SilkS")
		)
		(fp_line
			(start -2.050796 0.700024)
			(end 2.050796 0.700024)
			(stroke
				(width 0.1524)
				(type default)
			)
			(layer "B.SilkS")
		)
		(fp_line
			(start -2.050796 -0.700024)
			(end -2.050796 0.700024)
			(stroke
				(width 0.1524)
				(type default)
			)
			(layer "B.SilkS")
		)
		(fp_line
			(start -2.051304 0.6985)
			(end -2.051304 0.635)
			(stroke
				(width 0.1524)
				(type default)
			)
			(layer "B.SilkS")
		)
		(fp_line
			(start -2.051304 0.635)
			(end -2.152904 0.635)
			(stroke
				(width 0.1524)
				(type default)
			)
			(layer "B.SilkS")
		)
		(fp_line
			(start -2.064004 -0.6731)
			(end -2.064004 -0.6985)
			(stroke
				(width 0.1524)
				(type default)
			)
			(layer "B.SilkS")
		)
		(fp_line
			(start -2.064004 -0.6985)
			(end -2.229104 -0.6985)
			(stroke
				(width 0.1524)
				(type default)
			)
			(layer "B.SilkS")
		)
		(fp_line
			(start -2.152904 0.635)
			(end -2.152904 -0.6985)
			(stroke
				(width 0.1524)
				(type default)
			)
			(layer "B.SilkS")
		)
		(fp_line
			(start -2.152904 -0.6985)
			(end -2.343404 -0.6985)
			(stroke
				(width 0.1524)
				(type default)
			)
			(layer "B.SilkS")
		)
		(fp_line
			(start -2.229104 0.6985)
			(end -2.051304 0.6985)
			(stroke
				(width 0.1524)
				(type default)
			)
			(layer "B.SilkS")
		)
		(fp_line
			(start -2.229104 -0.6985)
			(end -2.229104 0.6985)
			(stroke
				(width 0.1524)
				(type default)
			)
			(layer "B.SilkS")
		)
		(fp_line
			(start -2.343404 0.6985)
			(end -2.216404 0.6985)
			(stroke
				(width 0.1524)
				(type default)
			)
			(layer "B.SilkS")
		)
		(fp_line
			(start -2.343404 -0.6985)
			(end -2.343404 0.6985)
			(stroke
				(width 0.1524)
				(type default)
			)
			(layer "B.SilkS")
		)
		(fp_line
			(start 0.899922 0.700024)
			(end 0.899922 -0.700024)
			(stroke
				(width 0.1)
				(type default)
			)
			(layer "B.Fab")
		)
		(fp_line
			(start 0.899922 -0.700024)
			(end -0.899922 -0.700024)
			(stroke
				(width 0.1)
				(type default)
			)
			(layer "B.Fab")
		)
		(fp_line
			(start -0.899922 0.700024)
			(end 0.899922 0.700024)
			(stroke
				(width 0.1)
				(type default)
			)
			(layer "B.Fab")
		)
		(fp_line
			(start -0.899922 -0.700024)
			(end -0.899922 0.700024)
			(stroke
				(width 0.1)
				(type default)
			)
			(layer "B.Fab")
		)
		(fp_text user "+"
			(at 3.05435 1.2446 90)
			(unlocked yes)
			(layer "B.SilkS")
			(effects
				(font
					(size 1.905 1.4224)
					(thickness 0.1524)
				)
				(justify left mirror)
			)
		)
		(fp_text user "-"
			(at -3.880104 0.23495 0)
			(unlocked yes)
			(layer "B.SilkS")
			(effects
				(font
					(size 1.905 1.4224)
					(thickness 0.1524)
				)
				(justify left mirror)
			)
		)
		(fp_text user "+"
			(at 3.123946 0.762 90)
			(unlocked yes)
			(layer "B.Fab")
			(effects
				(font
					(size 1.905 1.4224)
					(thickness 0.1524)
				)
				(justify left mirror)
			)
		)
		(fp_text user "-"
			(at -3.880104 0.23495 0)
			(unlocked yes)
			(layer "B.Fab")
			(effects
				(font
					(size 1.905 1.4224)
					(thickness 0.1524)
				)
				(justify left mirror)
			)
		)
		(pad "1" smd rect
			(at 1.199896 0 90)
			(size 0.6604 1.3716)
			(layers "B.Cu" "B.Mask" "B.Paste")
			(net "FM_AC_PWR_CYCLE_N")
		)
		(pad "2" smd rect
			(at -1.199896 0 270)
			(size 0.6604 1.3716)
			(layers "B.Cu" "B.Mask" "B.Paste")
			(net "FM_AC_PWR_CYCLE_R1_N")
		)
	)
	(footprint ""
		(layer "B.Cu")
		(at 104.652826 -114.046 -90)
		(property "Reference" "R202"
			(at 0 0 90)
			(layer "B.SilkS")
			(hide yes)
			(effects
				(font
					(size 1.27 1.27)
				)
				(justify mirror)
			)
		)
		(property "Value" ""
			(at 0 0 90)
			(layer "B.Fab")
			(effects
				(font
					(size 1.27 1.27)
				)
				(justify mirror)
			)
		)
		(duplicate_pad_numbers_are_jumpers no)
		(fp_line
			(start -0.7874 0.4064)
			(end 0.7874 0.4064)
			(stroke
				(width 0.1524)
				(type default)
			)
			(layer "B.SilkS")
		)
		(fp_line
			(start 0.7874 0.4064)
			(end 0.7874 -0.4064)
			(stroke
				(width 0.1524)
				(type default)
			)
			(layer "B.SilkS")
		)
		(fp_line
			(start -0.7874 -0.4064)
			(end -0.7874 0.4064)
			(stroke
				(width 0.1524)
				(type default)
			)
			(layer "B.SilkS")
		)
		(fp_line
			(start 0.7874 -0.4064)
			(end -0.7874 -0.4064)
			(stroke
				(width 0.1524)
				(type default)
			)
			(layer "B.SilkS")
		)
		(fp_line
			(start -0.67945 0.3048)
			(end -0.120396 0.3048)
			(stroke
				(width 0.1)
				(type default)
			)
			(layer "B.Fab")
		)
		(fp_line
			(start -0.120396 0.3048)
			(end -0.120396 0.2794)
			(stroke
				(width 0.1)
				(type default)
			)
			(layer "B.Fab")
		)
		(fp_line
			(start 0.12065 0.3048)
			(end 0.67945 0.3048)
			(stroke
				(width 0.1)
				(type default)
			)
			(layer "B.Fab")
		)
		(fp_line
			(start 0.67945 0.3048)
			(end 0.67945 -0.305054)
			(stroke
				(width 0.1)
				(type default)
			)
			(layer "B.Fab")
		)
		(fp_line
			(start -0.120396 0.2794)
			(end 0.12065 0.2794)
			(stroke
				(width 0.1)
				(type default)
			)
			(layer "B.Fab")
		)
		(fp_line
			(start 0.12065 0.2794)
			(end 0.12065 0.3048)
			(stroke
				(width 0.1)
				(type default)
			)
			(layer "B.Fab")
		)
		(fp_line
			(start -0.12065 -0.2794)
			(end -0.12065 -0.3048)
			(stroke
				(width 0.1)
				(type default)
			)
			(layer "B.Fab")
		)
		(fp_line
			(start 0.12065 -0.2794)
			(end -0.12065 -0.2794)
			(stroke
				(width 0.1)
				(type default)
			)
			(layer "B.Fab")
		)
		(fp_line
			(start -0.67945 -0.3048)
			(end -0.67945 0.3048)
			(stroke
				(width 0.1)
				(type default)
			)
			(layer "B.Fab")
		)
		(fp_line
			(start -0.12065 -0.3048)
			(end -0.67945 -0.3048)
			(stroke
				(width 0.1)
				(type default)
			)
			(layer "B.Fab")
		)
		(fp_line
			(start 0.12065 -0.305054)
			(end 0.12065 -0.2794)
			(stroke
				(width 0.1)
				(type default)
			)
			(layer "B.Fab")
		)
		(fp_line
			(start 0.67945 -0.305054)
			(end 0.12065 -0.305054)
			(stroke
				(width 0.1)
				(type default)
			)
			(layer "B.Fab")
		)
		(pad "1" smd circle
			(at 0.40005 0 90)
			(size 0 0)
			(layers "B.Cu" "B.Mask" "B.Paste")
			(net "BRICK_P12V_EN_R_N")
		)
		(pad "2" smd circle
			(at -0.40005 0 90)
			(size 0 0)
			(layers "B.Cu" "B.Mask" "B.Paste")
			(net "BRICK_P12V_1_EN_N")
		)
	)
	(footprint ""
		(layer "B.Cu")
		(at 180.850286 -76.708 90)
		(property "Reference" "PR320"
			(at 0 0 90)
			(layer "B.SilkS")
			(hide yes)
			(effects
				(font
					(size 1.27 1.27)
				)
				(justify mirror)
			)
		)
		(property "Value" ""
			(at 0 0 90)
			(layer "B.Fab")
			(effects
				(font
					(size 1.27 1.27)
				)
				(justify mirror)
			)
		)
		(duplicate_pad_numbers_are_jumpers no)
		(fp_line
			(start 0.7874 -0.4064)
			(end -0.7874 -0.4064)
			(stroke
				(width 0.1524)
				(type default)
			)
			(layer "B.SilkS")
		)
		(fp_line
			(start -0.7874 -0.4064)
			(end -0.7874 0.4064)
			(stroke
				(width 0.1524)
				(type default)
			)
			(layer "B.SilkS")
		)
		(fp_line
			(start 0.7874 0.4064)
			(end 0.7874 -0.4064)
			(stroke
				(width 0.1524)
				(type default)
			)
			(layer "B.SilkS")
		)
		(fp_line
			(start -0.7874 0.4064)
			(end 0.7874 0.4064)
			(stroke
				(width 0.1524)
				(type default)
			)
			(layer "B.SilkS")
		)
		(fp_line
			(start 0.67945 -0.305054)
			(end 0.12065 -0.305054)
			(stroke
				(width 0.1)
				(type default)
			)
			(layer "B.Fab")
		)
		(fp_line
			(start 0.12065 -0.305054)
			(end 0.12065 -0.2794)
			(stroke
				(width 0.1)
				(type default)
			)
			(layer "B.Fab")
		)
		(fp_line
			(start -0.12065 -0.3048)
			(end -0.67945 -0.3048)
			(stroke
				(width 0.1)
				(type default)
			)
			(layer "B.Fab")
		)
		(fp_line
			(start -0.67945 -0.3048)
			(end -0.67945 0.3048)
			(stroke
				(width 0.1)
				(type default)
			)
			(layer "B.Fab")
		)
		(fp_line
			(start 0.12065 -0.2794)
			(end -0.12065 -0.2794)
			(stroke
				(width 0.1)
				(type default)
			)
			(layer "B.Fab")
		)
		(fp_line
			(start -0.12065 -0.2794)
			(end -0.12065 -0.3048)
			(stroke
				(width 0.1)
				(type default)
			)
			(layer "B.Fab")
		)
		(fp_line
			(start 0.12065 0.2794)
			(end 0.12065 0.3048)
			(stroke
				(width 0.1)
				(type default)
			)
			(layer "B.Fab")
		)
		(fp_line
			(start -0.120396 0.2794)
			(end 0.12065 0.2794)
			(stroke
				(width 0.1)
				(type default)
			)
			(layer "B.Fab")
		)
		(fp_line
			(start 0.67945 0.3048)
			(end 0.67945 -0.305054)
			(stroke
				(width 0.1)
				(type default)
			)
			(layer "B.Fab")
		)
		(fp_line
			(start 0.12065 0.3048)
			(end 0.67945 0.3048)
			(stroke
				(width 0.1)
				(type default)
			)
			(layer "B.Fab")
		)
		(fp_line
			(start -0.120396 0.3048)
			(end -0.120396 0.2794)
			(stroke
				(width 0.1)
				(type default)
			)
			(layer "B.Fab")
		)
		(fp_line
			(start -0.67945 0.3048)
			(end -0.120396 0.3048)
			(stroke
				(width 0.1)
				(type default)
			)
			(layer "B.Fab")
		)
		(pad "1" smd circle
			(at 0.40005 0 270)
			(size 0 0)
			(layers "B.Cu" "B.Mask" "B.Paste")
			(net "GND")
		)
		(pad "2" smd circle
			(at -0.40005 0 270)
			(size 0 0)
			(layers "B.Cu" "B.Mask" "B.Paste")
			(net "BRICK2_PMBADD")
		)
	)
	(footprint ""
		(layer "B.Cu")
		(at 275.169122 -101.585522)
		(property "Reference" "PC82"
			(at 0 0 0)
			(layer "B.SilkS")
			(hide yes)
			(effects
				(font
					(size 1.27 1.27)
				)
				(justify mirror)
			)
		)
		(property "Value" ""
			(at 0 0 0)
			(layer "B.Fab")
			(effects
				(font
					(size 1.27 1.27)
				)
				(justify mirror)
			)
		)
		(duplicate_pad_numbers_are_jumpers no)
		(fp_line
			(start -1.2954 -0.5842)
			(end -1.2954 0.5842)
			(stroke
				(width 0.1524)
				(type default)
			)
			(layer "B.SilkS")
		)
		(fp_line
			(start -1.2954 0.5842)
			(end 1.2954 0.5842)
			(stroke
				(width 0.1524)
				(type default)
			)
			(layer "B.SilkS")
		)
		(fp_line
			(start 1.2954 -0.5842)
			(end -1.2954 -0.5842)
			(stroke
				(width 0.1524)
				(type default)
			)
			(layer "B.SilkS")
		)
		(fp_line
			(start 1.2954 0.5842)
			(end 1.2954 -0.5842)
			(stroke
				(width 0.1524)
				(type default)
			)
			(layer "B.SilkS")
		)
		(fp_line
			(start -1.1938 -0.4064)
			(end -1.1938 0.4064)
			(stroke
				(width 0.1)
				(type default)
			)
			(layer "B.Fab")
		)
		(fp_line
			(start -1.1938 0.4064)
			(end -0.8636 0.4064)
			(stroke
				(width 0.1)
				(type default)
			)
			(layer "B.Fab")
		)
		(fp_line
			(start -0.8636 -0.4572)
			(end -0.8636 -0.4064)
			(stroke
				(width 0.1)
				(type default)
			)
			(layer "B.Fab")
		)
		(fp_line
			(start -0.8636 -0.4064)
			(end -1.1938 -0.4064)
			(stroke
				(width 0.1)
				(type default)
			)
			(layer "B.Fab")
		)
		(fp_line
			(start -0.8636 0.4064)
			(end -0.8636 0.4572)
			(stroke
				(width 0.1)
				(type default)
			)
			(layer "B.Fab")
		)
		(fp_line
			(start -0.8636 0.4572)
			(end 0.8636 0.4572)
			(stroke
				(width 0.1)
				(type default)
			)
			(layer "B.Fab")
		)
		(fp_line
			(start 0.8636 -0.4572)
			(end -0.8636 -0.4572)
			(stroke
				(width 0.1)
				(type default)
			)
			(layer "B.Fab")
		)
		(fp_line
			(start 0.8636 -0.4064)
			(end 0.8636 -0.4572)
			(stroke
				(width 0.1)
				(type default)
			)
			(layer "B.Fab")
		)
		(fp_line
			(start 0.8636 0.4064)
			(end 1.1938 0.4064)
			(stroke
				(width 0.1)
				(type default)
			)
			(layer "B.Fab")
		)
		(fp_line
			(start 0.8636 0.4572)
			(end 0.8636 0.4064)
			(stroke
				(width 0.1)
				(type default)
			)
			(layer "B.Fab")
		)
		(fp_line
			(start 1.1938 -0.4064)
			(end 0.8636 -0.4064)
			(stroke
				(width 0.1)
				(type default)
			)
			(layer "B.Fab")
		)
		(fp_line
			(start 1.1938 0.4064)
			(end 1.1938 -0.4064)
			(stroke
				(width 0.1)
				(type default)
			)
			(layer "B.Fab")
		)
		(pad "1" smd rect
			(at 0.7366 0 270)
			(size 0.7112 0.8128)
			(layers "B.Cu" "B.Mask" "B.Paste")
			(net "P52V_HS1_4287_GATE_R")
		)
		(pad "2" smd rect
			(at -0.7366 0 270)
			(size 0.7112 0.8128)
			(layers "B.Cu" "B.Mask" "B.Paste")
			(net "P52V_HS")
		)
	)
	(footprint ""
		(layer "B.Cu")
		(at 54.483 -78.613)
		(property "Reference" "R181"
			(at 0 0 0)
			(layer "B.SilkS")
			(hide yes)
			(effects
				(font
					(size 1.27 1.27)
				)
				(justify mirror)
			)
		)
		(property "Value" ""
			(at 0 0 0)
			(layer "B.Fab")
			(effects
				(font
					(size 1.27 1.27)
				)
				(justify mirror)
			)
		)
		(duplicate_pad_numbers_are_jumpers no)
		(fp_line
			(start -0.7874 -0.4064)
			(end -0.7874 0.4064)
			(stroke
				(width 0.1524)
				(type default)
			)
			(layer "B.SilkS")
		)
		(fp_line
			(start -0.7874 0.4064)
			(end 0.7874 0.4064)
			(stroke
				(width 0.1524)
				(type default)
			)
			(layer "B.SilkS")
		)
		(fp_line
			(start 0.7874 -0.4064)
			(end -0.7874 -0.4064)
			(stroke
				(width 0.1524)
				(type default)
			)
			(layer "B.SilkS")
		)
		(fp_line
			(start 0.7874 0.4064)
			(end 0.7874 -0.4064)
			(stroke
				(width 0.1524)
				(type default)
			)
			(layer "B.SilkS")
		)
		(fp_line
			(start -0.67945 -0.3048)
			(end -0.67945 0.3048)
			(stroke
				(width 0.1)
				(type default)
			)
			(layer "B.Fab")
		)
		(fp_line
			(start -0.67945 0.3048)
			(end -0.120396 0.3048)
			(stroke
				(width 0.1)
				(type default)
			)
			(layer "B.Fab")
		)
		(fp_line
			(start -0.12065 -0.3048)
			(end -0.67945 -0.3048)
			(stroke
				(width 0.1)
				(type default)
			)
			(layer "B.Fab")
		)
		(fp_line
			(start -0.12065 -0.2794)
			(end -0.12065 -0.3048)
			(stroke
				(width 0.1)
				(type default)
			)
			(layer "B.Fab")
		)
		(fp_line
			(start -0.120396 0.2794)
			(end 0.12065 0.2794)
			(stroke
				(width 0.1)
				(type default)
			)
			(layer "B.Fab")
		)
		(fp_line
			(start -0.120396 0.3048)
			(end -0.120396 0.2794)
			(stroke
				(width 0.1)
				(type default)
			)
			(layer "B.Fab")
		)
		(fp_line
			(start 0.12065 -0.305054)
			(end 0.12065 -0.2794)
			(stroke
				(width 0.1)
				(type default)
			)
			(layer "B.Fab")
		)
		(fp_line
			(start 0.12065 -0.2794)
			(end -0.12065 -0.2794)
			(stroke
				(width 0.1)
				(type default)
			)
			(layer "B.Fab")
		)
		(fp_line
			(start 0.12065 0.2794)
			(end 0.12065 0.3048)
			(stroke
				(width 0.1)
				(type default)
			)
			(layer "B.Fab")
		)
		(fp_line
			(start 0.12065 0.3048)
			(end 0.67945 0.3048)
			(stroke
				(width 0.1)
				(type default)
			)
			(layer "B.Fab")
		)
		(fp_line
			(start 0.67945 -0.305054)
			(end 0.12065 -0.305054)
			(stroke
				(width 0.1)
				(type default)
			)
			(layer "B.Fab")
		)
		(fp_line
			(start 0.67945 0.3048)
			(end 0.67945 -0.305054)
			(stroke
				(width 0.1)
				(type default)
			)
			(layer "B.Fab")
		)
		(pad "1" smd circle
			(at 0.40005 0 180)
			(size 0 0)
			(layers "B.Cu" "B.Mask" "B.Paste")
			(net "P3V3_AUX")
		)
		(pad "2" smd circle
			(at -0.40005 0 180)
			(size 0 0)
			(layers "B.Cu" "B.Mask" "B.Paste")
			(net "SMB_P52V_VPDB_SDA")
		)
	)
	(footprint ""
		(layer "B.Cu")
		(at 229.87 -87.757 180)
		(property "Reference" "U20"
			(at 2.43967 -1.016 270)
			(unlocked yes)
			(layer "B.SilkS")
			(effects
				(font
					(size 0.7874 0.5842)
					(thickness 0.1524)
				)
				(justify left mirror)
			)
		)
		(property "Value" ""
			(at 0 0 0)
			(layer "B.Fab")
			(effects
				(font
					(size 1.27 1.27)
				)
				(justify mirror)
			)
		)
		(duplicate_pad_numbers_are_jumpers no)
		(fp_line
			(start 1.603248 1.500124)
			(end 1.603248 -1.500124)
			(stroke
				(width 0.1524)
				(type default)
			)
			(layer "B.SilkS")
		)
		(fp_line
			(start 1.603248 -1.500124)
			(end -1.603248 -1.500124)
			(stroke
				(width 0.1524)
				(type default)
			)
			(layer "B.SilkS")
		)
		(fp_line
			(start -1.603248 1.500124)
			(end 1.603248 1.500124)
			(stroke
				(width 0.1524)
				(type default)
			)
			(layer "B.SilkS")
		)
		(fp_line
			(start -1.603248 -1.500124)
			(end -1.603248 1.500124)
			(stroke
				(width 0.1524)
				(type default)
			)
			(layer "B.SilkS")
		)
		(fp_line
			(start 1.249934 1.169924)
			(end 0.700024 1.169924)
			(stroke
				(width 0.1)
				(type default)
			)
			(layer "B.Fab")
		)
		(fp_line
			(start 1.249934 0.729996)
			(end 1.249934 1.169924)
			(stroke
				(width 0.1)
				(type default)
			)
			(layer "B.Fab")
		)
		(fp_line
			(start 1.249934 -0.729996)
			(end 0.6985 -0.729996)
			(stroke
				(width 0.1)
				(type default)
			)
			(layer "B.Fab")
		)
		(fp_line
			(start 1.249934 -1.169924)
			(end 1.249934 -0.729996)
			(stroke
				(width 0.1)
				(type default)
			)
			(layer "B.Fab")
		)
		(fp_line
			(start 0.700024 1.500124)
			(end -0.700024 1.500124)
			(stroke
				(width 0.1)
				(type default)
			)
			(layer "B.Fab")
		)
		(fp_line
			(start 0.700024 1.169924)
			(end 0.700024 1.500124)
			(stroke
				(width 0.1)
				(type default)
			)
			(layer "B.Fab")
		)
		(fp_line
			(start 0.700024 -1.169924)
			(end 1.249934 -1.169924)
			(stroke
				(width 0.1)
				(type default)
			)
			(layer "B.Fab")
		)
		(fp_line
			(start 0.700024 -1.500124)
			(end 0.700024 -1.169924)
			(stroke
				(width 0.1)
				(type default)
			)
			(layer "B.Fab")
		)
		(fp_line
			(start 0.6985 0.729996)
			(end 1.249934 0.729996)
			(stroke
				(width 0.1)
				(type default)
			)
			(layer "B.Fab")
		)
		(fp_line
			(start 0.6985 -0.729996)
			(end 0.6985 0.729996)
			(stroke
				(width 0.1)
				(type default)
			)
			(layer "B.Fab")
		)
		(fp_line
			(start -0.700024 1.500124)
			(end -0.700024 0.219964)
			(stroke
				(width 0.1)
				(type default)
			)
			(layer "B.Fab")
		)
		(fp_line
			(start -0.700024 0.219964)
			(end -1.249934 0.219964)
			(stroke
				(width 0.1)
				(type default)
			)
			(layer "B.Fab")
		)
		(fp_line
			(start -0.700024 -0.219964)
			(end -0.700024 -1.500124)
			(stroke
				(width 0.1)
				(type default)
			)
			(layer "B.Fab")
		)
		(fp_line
			(start -0.700024 -1.500124)
			(end 0.700024 -1.500124)
			(stroke
				(width 0.1)
				(type default)
			)
			(layer "B.Fab")
		)
		(fp_line
			(start -1.249934 0.219964)
			(end -1.249934 -0.219964)
			(stroke
				(width 0.1)
				(type default)
			)
			(layer "B.Fab")
		)
		(fp_line
			(start -1.249934 -0.219964)
			(end -0.700024 -0.219964)
			(stroke
				(width 0.1)
				(type default)
			)
			(layer "B.Fab")
		)
		(fp_rect
			(start 0.700024 -1.500124)
			(end -0.700024 1.500124)
			(stroke
				(width 0)
				(type default)
			)
			(fill no)
			(layer "B.Fab")
		)
		(pad "D" smd rect
			(at -0.999998 0 90)
			(size 0.8128 0.9144)
			(layers "B.Cu" "B.Mask" "B.Paste")
			(net "PWRGD_P3V3_AUX_MB_BUF_N")
		)
		(pad "G" smd rect
			(at 0.999998 -0.94996 90)
			(size 0.8128 0.9144)
			(layers "B.Cu" "B.Mask" "B.Paste")
			(net "PWRGD_P3V3_AUX_MB_BUF")
		)
		(pad "S" smd rect
			(at 0.999998 0.94996 90)
			(size 0.8128 0.9144)
			(layers "B.Cu" "B.Mask" "B.Paste")
			(net "GND")
		)
	)
	(footprint ""
		(layer "B.Cu")
		(at 38.989 -88.011)
		(property "Reference" "R76"
			(at 0 0 0)
			(layer "B.SilkS")
			(hide yes)
			(effects
				(font
					(size 1.27 1.27)
				)
				(justify mirror)
			)
		)
		(property "Value" ""
			(at 0 0 0)
			(layer "B.Fab")
			(effects
				(font
					(size 1.27 1.27)
				)
				(justify mirror)
			)
		)
		(duplicate_pad_numbers_are_jumpers no)
		(fp_line
			(start -0.7874 -0.4064)
			(end -0.7874 0.4064)
			(stroke
				(width 0.1524)
				(type default)
			)
			(layer "B.SilkS")
		)
		(fp_line
			(start -0.7874 0.4064)
			(end 0.7874 0.4064)
			(stroke
				(width 0.1524)
				(type default)
			)
			(layer "B.SilkS")
		)
		(fp_line
			(start 0.7874 -0.4064)
			(end -0.7874 -0.4064)
			(stroke
				(width 0.1524)
				(type default)
			)
			(layer "B.SilkS")
		)
		(fp_line
			(start 0.7874 0.4064)
			(end 0.7874 -0.4064)
			(stroke
				(width 0.1524)
				(type default)
			)
			(layer "B.SilkS")
		)
		(fp_line
			(start -0.67945 -0.3048)
			(end -0.67945 0.3048)
			(stroke
				(width 0.1)
				(type default)
			)
			(layer "B.Fab")
		)
		(fp_line
			(start -0.67945 0.3048)
			(end -0.120396 0.3048)
			(stroke
				(width 0.1)
				(type default)
			)
			(layer "B.Fab")
		)
		(fp_line
			(start -0.12065 -0.3048)
			(end -0.67945 -0.3048)
			(stroke
				(width 0.1)
				(type default)
			)
			(layer "B.Fab")
		)
		(fp_line
			(start -0.12065 -0.2794)
			(end -0.12065 -0.3048)
			(stroke
				(width 0.1)
				(type default)
			)
			(layer "B.Fab")
		)
		(fp_line
			(start -0.120396 0.2794)
			(end 0.12065 0.2794)
			(stroke
				(width 0.1)
				(type default)
			)
			(layer "B.Fab")
		)
		(fp_line
			(start -0.120396 0.3048)
			(end -0.120396 0.2794)
			(stroke
				(width 0.1)
				(type default)
			)
			(layer "B.Fab")
		)
		(fp_line
			(start 0.12065 -0.305054)
			(end 0.12065 -0.2794)
			(stroke
				(width 0.1)
				(type default)
			)
			(layer "B.Fab")
		)
		(fp_line
			(start 0.12065 -0.2794)
			(end -0.12065 -0.2794)
			(stroke
				(width 0.1)
				(type default)
			)
			(layer "B.Fab")
		)
		(fp_line
			(start 0.12065 0.2794)
			(end 0.12065 0.3048)
			(stroke
				(width 0.1)
				(type default)
			)
			(layer "B.Fab")
		)
		(fp_line
			(start 0.12065 0.3048)
			(end 0.67945 0.3048)
			(stroke
				(width 0.1)
				(type default)
			)
			(layer "B.Fab")
		)
		(fp_line
			(start 0.67945 -0.305054)
			(end 0.12065 -0.305054)
			(stroke
				(width 0.1)
				(type default)
			)
			(layer "B.Fab")
		)
		(fp_line
			(start 0.67945 0.3048)
			(end 0.67945 -0.305054)
			(stroke
				(width 0.1)
				(type default)
			)
			(layer "B.Fab")
		)
		(pad "1" smd circle
			(at 0.40005 0 180)
			(size 0 0)
			(layers "B.Cu" "B.Mask" "B.Paste")
			(net "SMB_HPDB_MISC_SCL")
		)
		(pad "2" smd circle
			(at -0.40005 0 180)
			(size 0 0)
			(layers "B.Cu" "B.Mask" "B.Paste")
			(net "SMB_HPDB_MISC_R_SCL")
		)
	)
	(footprint ""
		(layer "B.Cu")
		(at 205.74 -90.678 180)
		(property "Reference" "R103"
			(at 0 0 0)
			(layer "B.SilkS")
			(hide yes)
			(effects
				(font
					(size 1.27 1.27)
				)
				(justify mirror)
			)
		)
		(property "Value" ""
			(at 0 0 0)
			(layer "B.Fab")
			(effects
				(font
					(size 1.27 1.27)
				)
				(justify mirror)
			)
		)
		(duplicate_pad_numbers_are_jumpers no)
		(fp_line
			(start 0.7874 0.4064)
			(end 0.7874 -0.4064)
			(stroke
				(width 0.1524)
				(type default)
			)
			(layer "B.SilkS")
		)
		(fp_line
			(start 0.7874 -0.4064)
			(end -0.7874 -0.4064)
			(stroke
				(width 0.1524)
				(type default)
			)
			(layer "B.SilkS")
		)
		(fp_line
			(start -0.7874 0.4064)
			(end 0.7874 0.4064)
			(stroke
				(width 0.1524)
				(type default)
			)
			(layer "B.SilkS")
		)
		(fp_line
			(start -0.7874 -0.4064)
			(end -0.7874 0.4064)
			(stroke
				(width 0.1524)
				(type default)
			)
			(layer "B.SilkS")
		)
		(fp_line
			(start 0.67945 0.3048)
			(end 0.67945 -0.305054)
			(stroke
				(width 0.1)
				(type default)
			)
			(layer "B.Fab")
		)
		(fp_line
			(start 0.67945 -0.305054)
			(end 0.12065 -0.305054)
			(stroke
				(width 0.1)
				(type default)
			)
			(layer "B.Fab")
		)
		(fp_line
			(start 0.12065 0.3048)
			(end 0.67945 0.3048)
			(stroke
				(width 0.1)
				(type default)
			)
			(layer "B.Fab")
		)
		(fp_line
			(start 0.12065 0.2794)
			(end 0.12065 0.3048)
			(stroke
				(width 0.1)
				(type default)
			)
			(layer "B.Fab")
		)
		(fp_line
			(start 0.12065 -0.2794)
			(end -0.12065 -0.2794)
			(stroke
				(width 0.1)
				(type default)
			)
			(layer "B.Fab")
		)
		(fp_line
			(start 0.12065 -0.305054)
			(end 0.12065 -0.2794)
			(stroke
				(width 0.1)
				(type default)
			)
			(layer "B.Fab")
		)
		(fp_line
			(start -0.120396 0.3048)
			(end -0.120396 0.2794)
			(stroke
				(width 0.1)
				(type default)
			)
			(layer "B.Fab")
		)
		(fp_line
			(start -0.120396 0.2794)
			(end 0.12065 0.2794)
			(stroke
				(width 0.1)
				(type default)
			)
			(layer "B.Fab")
		)
		(fp_line
			(start -0.12065 -0.2794)
			(end -0.12065 -0.3048)
			(stroke
				(width 0.1)
				(type default)
			)
			(layer "B.Fab")
		)
		(fp_line
			(start -0.12065 -0.3048)
			(end -0.67945 -0.3048)
			(stroke
				(width 0.1)
				(type default)
			)
			(layer "B.Fab")
		)
		(fp_line
			(start -0.67945 0.3048)
			(end -0.120396 0.3048)
			(stroke
				(width 0.1)
				(type default)
			)
			(layer "B.Fab")
		)
		(fp_line
			(start -0.67945 -0.3048)
			(end -0.67945 0.3048)
			(stroke
				(width 0.1)
				(type default)
			)
			(layer "B.Fab")
		)
		(pad "1" smd circle
			(at 0.40005 0)
			(size 0 0)
			(layers "B.Cu" "B.Mask" "B.Paste")
			(net "PCA9543_MISC_A1")
		)
		(pad "2" smd circle
			(at -0.40005 0)
			(size 0 0)
			(layers "B.Cu" "B.Mask" "B.Paste")
			(net "GND")
		)
	)
	(footprint ""
		(layer "B.Cu")
		(at 281.94 -36.449 -90)
		(property "Reference" "R152"
			(at 0 0 90)
			(layer "B.SilkS")
			(hide yes)
			(effects
				(font
					(size 1.27 1.27)
				)
				(justify mirror)
			)
		)
		(property "Value" ""
			(at 0 0 90)
			(layer "B.Fab")
			(effects
				(font
					(size 1.27 1.27)
				)
				(justify mirror)
			)
		)
		(duplicate_pad_numbers_are_jumpers no)
		(fp_line
			(start -0.7874 0.4064)
			(end 0.7874 0.4064)
			(stroke
				(width 0.1524)
				(type default)
			)
			(layer "B.SilkS")
		)
		(fp_line
			(start 0.7874 0.4064)
			(end 0.7874 -0.4064)
			(stroke
				(width 0.1524)
				(type default)
			)
			(layer "B.SilkS")
		)
		(fp_line
			(start -0.7874 -0.4064)
			(end -0.7874 0.4064)
			(stroke
				(width 0.1524)
				(type default)
			)
			(layer "B.SilkS")
		)
		(fp_line
			(start 0.7874 -0.4064)
			(end -0.7874 -0.4064)
			(stroke
				(width 0.1524)
				(type default)
			)
			(layer "B.SilkS")
		)
		(fp_line
			(start -0.67945 0.3048)
			(end -0.120396 0.3048)
			(stroke
				(width 0.1)
				(type default)
			)
			(layer "B.Fab")
		)
		(fp_line
			(start -0.120396 0.3048)
			(end -0.120396 0.2794)
			(stroke
				(width 0.1)
				(type default)
			)
			(layer "B.Fab")
		)
		(fp_line
			(start 0.12065 0.3048)
			(end 0.67945 0.3048)
			(stroke
				(width 0.1)
				(type default)
			)
			(layer "B.Fab")
		)
		(fp_line
			(start 0.67945 0.3048)
			(end 0.67945 -0.305054)
			(stroke
				(width 0.1)
				(type default)
			)
			(layer "B.Fab")
		)
		(fp_line
			(start -0.120396 0.2794)
			(end 0.12065 0.2794)
			(stroke
				(width 0.1)
				(type default)
			)
			(layer "B.Fab")
		)
		(fp_line
			(start 0.12065 0.2794)
			(end 0.12065 0.3048)
			(stroke
				(width 0.1)
				(type default)
			)
			(layer "B.Fab")
		)
		(fp_line
			(start -0.12065 -0.2794)
			(end -0.12065 -0.3048)
			(stroke
				(width 0.1)
				(type default)
			)
			(layer "B.Fab")
		)
		(fp_line
			(start 0.12065 -0.2794)
			(end -0.12065 -0.2794)
			(stroke
				(width 0.1)
				(type default)
			)
			(layer "B.Fab")
		)
		(fp_line
			(start -0.67945 -0.3048)
			(end -0.67945 0.3048)
			(stroke
				(width 0.1)
				(type default)
			)
			(layer "B.Fab")
		)
		(fp_line
			(start -0.12065 -0.3048)
			(end -0.67945 -0.3048)
			(stroke
				(width 0.1)
				(type default)
			)
			(layer "B.Fab")
		)
		(fp_line
			(start 0.12065 -0.305054)
			(end 0.12065 -0.2794)
			(stroke
				(width 0.1)
				(type default)
			)
			(layer "B.Fab")
		)
		(fp_line
			(start 0.67945 -0.305054)
			(end 0.12065 -0.305054)
			(stroke
				(width 0.1)
				(type default)
			)
			(layer "B.Fab")
		)
		(pad "1" smd circle
			(at 0.40005 0 90)
			(size 0 0)
			(layers "B.Cu" "B.Mask" "B.Paste")
			(net "P3V3_AUX")
		)
		(pad "2" smd circle
			(at -0.40005 0 90)
			(size 0 0)
			(layers "B.Cu" "B.Mask" "B.Paste")
			(net "P52V_HS1_GPO1")
		)
	)
	(footprint ""
		(layer "B.Cu")
		(at 231.013 -75.184 -90)
		(property "Reference" "R141"
			(at 0 0 90)
			(layer "B.SilkS")
			(hide yes)
			(effects
				(font
					(size 1.27 1.27)
				)
				(justify mirror)
			)
		)
		(property "Value" ""
			(at 0 0 90)
			(layer "B.Fab")
			(effects
				(font
					(size 1.27 1.27)
				)
				(justify mirror)
			)
		)
		(duplicate_pad_numbers_are_jumpers no)
		(fp_line
			(start -0.7874 0.4064)
			(end 0.7874 0.4064)
			(stroke
				(width 0.1524)
				(type default)
			)
			(layer "B.SilkS")
		)
		(fp_line
			(start 0.7874 0.4064)
			(end 0.7874 -0.4064)
			(stroke
				(width 0.1524)
				(type default)
			)
			(layer "B.SilkS")
		)
		(fp_line
			(start -0.7874 -0.4064)
			(end -0.7874 0.4064)
			(stroke
				(width 0.1524)
				(type default)
			)
			(layer "B.SilkS")
		)
		(fp_line
			(start 0.7874 -0.4064)
			(end -0.7874 -0.4064)
			(stroke
				(width 0.1524)
				(type default)
			)
			(layer "B.SilkS")
		)
		(fp_line
			(start -0.67945 0.3048)
			(end -0.120396 0.3048)
			(stroke
				(width 0.1)
				(type default)
			)
			(layer "B.Fab")
		)
		(fp_line
			(start -0.120396 0.3048)
			(end -0.120396 0.2794)
			(stroke
				(width 0.1)
				(type default)
			)
			(layer "B.Fab")
		)
		(fp_line
			(start 0.12065 0.3048)
			(end 0.67945 0.3048)
			(stroke
				(width 0.1)
				(type default)
			)
			(layer "B.Fab")
		)
		(fp_line
			(start 0.67945 0.3048)
			(end 0.67945 -0.305054)
			(stroke
				(width 0.1)
				(type default)
			)
			(layer "B.Fab")
		)
		(fp_line
			(start -0.120396 0.2794)
			(end 0.12065 0.2794)
			(stroke
				(width 0.1)
				(type default)
			)
			(layer "B.Fab")
		)
		(fp_line
			(start 0.12065 0.2794)
			(end 0.12065 0.3048)
			(stroke
				(width 0.1)
				(type default)
			)
			(layer "B.Fab")
		)
		(fp_line
			(start -0.12065 -0.2794)
			(end -0.12065 -0.3048)
			(stroke
				(width 0.1)
				(type default)
			)
			(layer "B.Fab")
		)
		(fp_line
			(start 0.12065 -0.2794)
			(end -0.12065 -0.2794)
			(stroke
				(width 0.1)
				(type default)
			)
			(layer "B.Fab")
		)
		(fp_line
			(start -0.67945 -0.3048)
			(end -0.67945 0.3048)
			(stroke
				(width 0.1)
				(type default)
			)
			(layer "B.Fab")
		)
		(fp_line
			(start -0.12065 -0.3048)
			(end -0.67945 -0.3048)
			(stroke
				(width 0.1)
				(type default)
			)
			(layer "B.Fab")
		)
		(fp_line
			(start 0.12065 -0.305054)
			(end 0.12065 -0.2794)
			(stroke
				(width 0.1)
				(type default)
			)
			(layer "B.Fab")
		)
		(fp_line
			(start 0.67945 -0.305054)
			(end 0.12065 -0.305054)
			(stroke
				(width 0.1)
				(type default)
			)
			(layer "B.Fab")
		)
		(pad "1" smd circle
			(at 0.40005 0 90)
			(size 0 0)
			(layers "B.Cu" "B.Mask" "B.Paste")
			(net "PWRGD_P3V3_AUX_MB")
		)
		(pad "2" smd circle
			(at -0.40005 0 90)
			(size 0 0)
			(layers "B.Cu" "B.Mask" "B.Paste")
			(net "PWRGD_P3V3_AUX_MB_R1")
		)
	)
	(footprint ""
		(layer "B.Cu")
		(at 92.849954 -76.708 -90)
		(property "Reference" "PR67"
			(at 0 0 90)
			(layer "B.SilkS")
			(hide yes)
			(effects
				(font
					(size 1.27 1.27)
				)
				(justify mirror)
			)
		)
		(property "Value" ""
			(at 0 0 90)
			(layer "B.Fab")
			(effects
				(font
					(size 1.27 1.27)
				)
				(justify mirror)
			)
		)
		(duplicate_pad_numbers_are_jumpers no)
		(fp_line
			(start -0.7874 0.4064)
			(end 0.7874 0.4064)
			(stroke
				(width 0.1524)
				(type default)
			)
			(layer "B.SilkS")
		)
		(fp_line
			(start 0.7874 0.4064)
			(end 0.7874 -0.4064)
			(stroke
				(width 0.1524)
				(type default)
			)
			(layer "B.SilkS")
		)
		(fp_line
			(start -0.7874 -0.4064)
			(end -0.7874 0.4064)
			(stroke
				(width 0.1524)
				(type default)
			)
			(layer "B.SilkS")
		)
		(fp_line
			(start 0.7874 -0.4064)
			(end -0.7874 -0.4064)
			(stroke
				(width 0.1524)
				(type default)
			)
			(layer "B.SilkS")
		)
		(fp_line
			(start -0.67945 0.3048)
			(end -0.120396 0.3048)
			(stroke
				(width 0.1)
				(type default)
			)
			(layer "B.Fab")
		)
		(fp_line
			(start -0.120396 0.3048)
			(end -0.120396 0.2794)
			(stroke
				(width 0.1)
				(type default)
			)
			(layer "B.Fab")
		)
		(fp_line
			(start 0.12065 0.3048)
			(end 0.67945 0.3048)
			(stroke
				(width 0.1)
				(type default)
			)
			(layer "B.Fab")
		)
		(fp_line
			(start 0.67945 0.3048)
			(end 0.67945 -0.305054)
			(stroke
				(width 0.1)
				(type default)
			)
			(layer "B.Fab")
		)
		(fp_line
			(start -0.120396 0.2794)
			(end 0.12065 0.2794)
			(stroke
				(width 0.1)
				(type default)
			)
			(layer "B.Fab")
		)
		(fp_line
			(start 0.12065 0.2794)
			(end 0.12065 0.3048)
			(stroke
				(width 0.1)
				(type default)
			)
			(layer "B.Fab")
		)
		(fp_line
			(start -0.12065 -0.2794)
			(end -0.12065 -0.3048)
			(stroke
				(width 0.1)
				(type default)
			)
			(layer "B.Fab")
		)
		(fp_line
			(start 0.12065 -0.2794)
			(end -0.12065 -0.2794)
			(stroke
				(width 0.1)
				(type default)
			)
			(layer "B.Fab")
		)
		(fp_line
			(start -0.67945 -0.3048)
			(end -0.67945 0.3048)
			(stroke
				(width 0.1)
				(type default)
			)
			(layer "B.Fab")
		)
		(fp_line
			(start -0.12065 -0.3048)
			(end -0.67945 -0.3048)
			(stroke
				(width 0.1)
				(type default)
			)
			(layer "B.Fab")
		)
		(fp_line
			(start 0.12065 -0.305054)
			(end 0.12065 -0.2794)
			(stroke
				(width 0.1)
				(type default)
			)
			(layer "B.Fab")
		)
		(fp_line
			(start 0.67945 -0.305054)
			(end 0.12065 -0.305054)
			(stroke
				(width 0.1)
				(type default)
			)
			(layer "B.Fab")
		)
		(pad "1" smd circle
			(at 0.40005 0 90)
			(size 0 0)
			(layers "B.Cu" "B.Mask" "B.Paste")
			(net "P12V_MB1_SENSE-")
		)
		(pad "2" smd circle
			(at -0.40005 0 90)
			(size 0 0)
			(layers "B.Cu" "B.Mask" "B.Paste")
			(net "GND")
		)
	)
	(footprint ""
		(layer "B.Cu")
		(at 189.611 -88.3158)
		(property "Reference" "R132"
			(at 0 0 0)
			(layer "B.SilkS")
			(hide yes)
			(effects
				(font
					(size 1.27 1.27)
				)
				(justify mirror)
			)
		)
		(property "Value" ""
			(at 0 0 0)
			(layer "B.Fab")
			(effects
				(font
					(size 1.27 1.27)
				)
				(justify mirror)
			)
		)
		(duplicate_pad_numbers_are_jumpers no)
		(fp_line
			(start -0.7874 -0.4064)
			(end -0.7874 0.4064)
			(stroke
				(width 0.1524)
				(type default)
			)
			(layer "B.SilkS")
		)
		(fp_line
			(start -0.7874 0.4064)
			(end 0.7874 0.4064)
			(stroke
				(width 0.1524)
				(type default)
			)
			(layer "B.SilkS")
		)
		(fp_line
			(start 0.7874 -0.4064)
			(end -0.7874 -0.4064)
			(stroke
				(width 0.1524)
				(type default)
			)
			(layer "B.SilkS")
		)
		(fp_line
			(start 0.7874 0.4064)
			(end 0.7874 -0.4064)
			(stroke
				(width 0.1524)
				(type default)
			)
			(layer "B.SilkS")
		)
		(fp_line
			(start -0.67945 -0.3048)
			(end -0.67945 0.3048)
			(stroke
				(width 0.1)
				(type default)
			)
			(layer "B.Fab")
		)
		(fp_line
			(start -0.67945 0.3048)
			(end -0.120396 0.3048)
			(stroke
				(width 0.1)
				(type default)
			)
			(layer "B.Fab")
		)
		(fp_line
			(start -0.12065 -0.3048)
			(end -0.67945 -0.3048)
			(stroke
				(width 0.1)
				(type default)
			)
			(layer "B.Fab")
		)
		(fp_line
			(start -0.12065 -0.2794)
			(end -0.12065 -0.3048)
			(stroke
				(width 0.1)
				(type default)
			)
			(layer "B.Fab")
		)
		(fp_line
			(start -0.120396 0.2794)
			(end 0.12065 0.2794)
			(stroke
				(width 0.1)
				(type default)
			)
			(layer "B.Fab")
		)
		(fp_line
			(start -0.120396 0.3048)
			(end -0.120396 0.2794)
			(stroke
				(width 0.1)
				(type default)
			)
			(layer "B.Fab")
		)
		(fp_line
			(start 0.12065 -0.305054)
			(end 0.12065 -0.2794)
			(stroke
				(width 0.1)
				(type default)
			)
			(layer "B.Fab")
		)
		(fp_line
			(start 0.12065 -0.2794)
			(end -0.12065 -0.2794)
			(stroke
				(width 0.1)
				(type default)
			)
			(layer "B.Fab")
		)
		(fp_line
			(start 0.12065 0.2794)
			(end 0.12065 0.3048)
			(stroke
				(width 0.1)
				(type default)
			)
			(layer "B.Fab")
		)
		(fp_line
			(start 0.12065 0.3048)
			(end 0.67945 0.3048)
			(stroke
				(width 0.1)
				(type default)
			)
			(layer "B.Fab")
		)
		(fp_line
			(start 0.67945 -0.305054)
			(end 0.12065 -0.305054)
			(stroke
				(width 0.1)
				(type default)
			)
			(layer "B.Fab")
		)
		(fp_line
			(start 0.67945 0.3048)
			(end 0.67945 -0.305054)
			(stroke
				(width 0.1)
				(type default)
			)
			(layer "B.Fab")
		)
		(pad "1" smd circle
			(at 0.40005 0 180)
			(size 0 0)
			(layers "B.Cu" "B.Mask" "B.Paste")
			(net "SMB_P52V_HPDB_SDA")
		)
		(pad "2" smd circle
			(at -0.40005 0 180)
			(size 0 0)
			(layers "B.Cu" "B.Mask" "B.Paste")
			(net "P3V3_AUX")
		)
	)
	(footprint ""
		(layer "B.Cu")
		(at 136.85012 -114.046 90)
		(property "Reference" "C51"
			(at 0 0 90)
			(layer "B.SilkS")
			(hide yes)
			(effects
				(font
					(size 1.27 1.27)
				)
				(justify mirror)
			)
		)
		(property "Value" ""
			(at 0 0 90)
			(layer "B.Fab")
			(effects
				(font
					(size 1.27 1.27)
				)
				(justify mirror)
			)
		)
		(duplicate_pad_numbers_are_jumpers no)
		(fp_line
			(start 0.7874 -0.4064)
			(end -0.7874 -0.4064)
			(stroke
				(width 0.1524)
				(type default)
			)
			(layer "B.SilkS")
		)
		(fp_line
			(start -0.7874 -0.4064)
			(end -0.7874 0.4064)
			(stroke
				(width 0.1524)
				(type default)
			)
			(layer "B.SilkS")
		)
		(fp_line
			(start 0.7874 0.4064)
			(end 0.7874 -0.4064)
			(stroke
				(width 0.1524)
				(type default)
			)
			(layer "B.SilkS")
		)
		(fp_line
			(start -0.7874 0.4064)
			(end 0.7874 0.4064)
			(stroke
				(width 0.1524)
				(type default)
			)
			(layer "B.SilkS")
		)
		(fp_line
			(start 0.67945 -0.305054)
			(end 0.12065 -0.305054)
			(stroke
				(width 0.1)
				(type default)
			)
			(layer "B.Fab")
		)
		(fp_line
			(start 0.12065 -0.305054)
			(end 0.12065 -0.2794)
			(stroke
				(width 0.1)
				(type default)
			)
			(layer "B.Fab")
		)
		(fp_line
			(start -0.12065 -0.3048)
			(end -0.67945 -0.3048)
			(stroke
				(width 0.1)
				(type default)
			)
			(layer "B.Fab")
		)
		(fp_line
			(start -0.67945 -0.3048)
			(end -0.67945 0.3048)
			(stroke
				(width 0.1)
				(type default)
			)
			(layer "B.Fab")
		)
		(fp_line
			(start 0.12065 -0.2794)
			(end -0.12065 -0.2794)
			(stroke
				(width 0.1)
				(type default)
			)
			(layer "B.Fab")
		)
		(fp_line
			(start -0.12065 -0.2794)
			(end -0.12065 -0.3048)
			(stroke
				(width 0.1)
				(type default)
			)
			(layer "B.Fab")
		)
		(fp_line
			(start 0.12065 0.2794)
			(end 0.12065 0.3048)
			(stroke
				(width 0.1)
				(type default)
			)
			(layer "B.Fab")
		)
		(fp_line
			(start -0.120396 0.2794)
			(end 0.12065 0.2794)
			(stroke
				(width 0.1)
				(type default)
			)
			(layer "B.Fab")
		)
		(fp_line
			(start 0.67945 0.3048)
			(end 0.67945 -0.305054)
			(stroke
				(width 0.1)
				(type default)
			)
			(layer "B.Fab")
		)
		(fp_line
			(start 0.12065 0.3048)
			(end 0.67945 0.3048)
			(stroke
				(width 0.1)
				(type default)
			)
			(layer "B.Fab")
		)
		(fp_line
			(start -0.120396 0.3048)
			(end -0.120396 0.2794)
			(stroke
				(width 0.1)
				(type default)
			)
			(layer "B.Fab")
		)
		(fp_line
			(start -0.67945 0.3048)
			(end -0.120396 0.3048)
			(stroke
				(width 0.1)
				(type default)
			)
			(layer "B.Fab")
		)
		(pad "1" smd circle
			(at 0.40005 0 270)
			(size 0 0)
			(layers "B.Cu" "B.Mask" "B.Paste")
			(net "BRICK_P12V0_EN_N")
		)
		(pad "2" smd circle
			(at -0.40005 0 270)
			(size 0 0)
			(layers "B.Cu" "B.Mask" "B.Paste")
			(net "GND")
		)
	)
	(footprint ""
		(layer "B.Cu")
		(at 216.408 -84.455 90)
		(property "Reference" "R5903"
			(at 0 0 90)
			(layer "B.SilkS")
			(hide yes)
			(effects
				(font
					(size 1.27 1.27)
				)
				(justify mirror)
			)
		)
		(property "Value" ""
			(at 0 0 90)
			(layer "B.Fab")
			(effects
				(font
					(size 1.27 1.27)
				)
				(justify mirror)
			)
		)
		(duplicate_pad_numbers_are_jumpers no)
		(fp_line
			(start 0.7874 -0.4064)
			(end -0.7874 -0.4064)
			(stroke
				(width 0.1524)
				(type default)
			)
			(layer "B.SilkS")
		)
		(fp_line
			(start -0.7874 -0.4064)
			(end -0.7874 0.4064)
			(stroke
				(width 0.1524)
				(type default)
			)
			(layer "B.SilkS")
		)
		(fp_line
			(start 0.7874 0.4064)
			(end 0.7874 -0.4064)
			(stroke
				(width 0.1524)
				(type default)
			)
			(layer "B.SilkS")
		)
		(fp_line
			(start -0.7874 0.4064)
			(end 0.7874 0.4064)
			(stroke
				(width 0.1524)
				(type default)
			)
			(layer "B.SilkS")
		)
		(fp_line
			(start 0.67945 -0.305054)
			(end 0.12065 -0.305054)
			(stroke
				(width 0.1)
				(type default)
			)
			(layer "B.Fab")
		)
		(fp_line
			(start 0.12065 -0.305054)
			(end 0.12065 -0.2794)
			(stroke
				(width 0.1)
				(type default)
			)
			(layer "B.Fab")
		)
		(fp_line
			(start -0.12065 -0.3048)
			(end -0.67945 -0.3048)
			(stroke
				(width 0.1)
				(type default)
			)
			(layer "B.Fab")
		)
		(fp_line
			(start -0.67945 -0.3048)
			(end -0.67945 0.3048)
			(stroke
				(width 0.1)
				(type default)
			)
			(layer "B.Fab")
		)
		(fp_line
			(start 0.12065 -0.2794)
			(end -0.12065 -0.2794)
			(stroke
				(width 0.1)
				(type default)
			)
			(layer "B.Fab")
		)
		(fp_line
			(start -0.12065 -0.2794)
			(end -0.12065 -0.3048)
			(stroke
				(width 0.1)
				(type default)
			)
			(layer "B.Fab")
		)
		(fp_line
			(start 0.12065 0.2794)
			(end 0.12065 0.3048)
			(stroke
				(width 0.1)
				(type default)
			)
			(layer "B.Fab")
		)
		(fp_line
			(start -0.120396 0.2794)
			(end 0.12065 0.2794)
			(stroke
				(width 0.1)
				(type default)
			)
			(layer "B.Fab")
		)
		(fp_line
			(start 0.67945 0.3048)
			(end 0.67945 -0.305054)
			(stroke
				(width 0.1)
				(type default)
			)
			(layer "B.Fab")
		)
		(fp_line
			(start 0.12065 0.3048)
			(end 0.67945 0.3048)
			(stroke
				(width 0.1)
				(type default)
			)
			(layer "B.Fab")
		)
		(fp_line
			(start -0.120396 0.3048)
			(end -0.120396 0.2794)
			(stroke
				(width 0.1)
				(type default)
			)
			(layer "B.Fab")
		)
		(fp_line
			(start -0.67945 0.3048)
			(end -0.120396 0.3048)
			(stroke
				(width 0.1)
				(type default)
			)
			(layer "B.Fab")
		)
		(pad "1" smd circle
			(at 0.40005 0 270)
			(size 0 0)
			(layers "B.Cu" "B.Mask" "B.Paste")
			(net "FAN_PWR_EN")
		)
		(pad "2" smd circle
			(at -0.40005 0 270)
			(size 0 0)
			(layers "B.Cu" "B.Mask" "B.Paste")
			(net "P3V3_AUX")
		)
	)
	(footprint ""
		(layer "B.Cu")
		(at 179.065174 -76.327 180)
		(property "Reference" "R198"
			(at 0 0 0)
			(layer "B.SilkS")
			(hide yes)
			(effects
				(font
					(size 1.27 1.27)
				)
				(justify mirror)
			)
		)
		(property "Value" ""
			(at 0 0 0)
			(layer "B.Fab")
			(effects
				(font
					(size 1.27 1.27)
				)
				(justify mirror)
			)
		)
		(duplicate_pad_numbers_are_jumpers no)
		(fp_line
			(start 0.7874 0.4064)
			(end 0.7874 -0.4064)
			(stroke
				(width 0.1524)
				(type default)
			)
			(layer "B.SilkS")
		)
		(fp_line
			(start 0.7874 -0.4064)
			(end -0.7874 -0.4064)
			(stroke
				(width 0.1524)
				(type default)
			)
			(layer "B.SilkS")
		)
		(fp_line
			(start -0.7874 0.4064)
			(end 0.7874 0.4064)
			(stroke
				(width 0.1524)
				(type default)
			)
			(layer "B.SilkS")
		)
		(fp_line
			(start -0.7874 -0.4064)
			(end -0.7874 0.4064)
			(stroke
				(width 0.1524)
				(type default)
			)
			(layer "B.SilkS")
		)
		(fp_line
			(start 0.67945 0.3048)
			(end 0.67945 -0.305054)
			(stroke
				(width 0.1)
				(type default)
			)
			(layer "B.Fab")
		)
		(fp_line
			(start 0.67945 -0.305054)
			(end 0.12065 -0.305054)
			(stroke
				(width 0.1)
				(type default)
			)
			(layer "B.Fab")
		)
		(fp_line
			(start 0.12065 0.3048)
			(end 0.67945 0.3048)
			(stroke
				(width 0.1)
				(type default)
			)
			(layer "B.Fab")
		)
		(fp_line
			(start 0.12065 0.2794)
			(end 0.12065 0.3048)
			(stroke
				(width 0.1)
				(type default)
			)
			(layer "B.Fab")
		)
		(fp_line
			(start 0.12065 -0.2794)
			(end -0.12065 -0.2794)
			(stroke
				(width 0.1)
				(type default)
			)
			(layer "B.Fab")
		)
		(fp_line
			(start 0.12065 -0.305054)
			(end 0.12065 -0.2794)
			(stroke
				(width 0.1)
				(type default)
			)
			(layer "B.Fab")
		)
		(fp_line
			(start -0.120396 0.3048)
			(end -0.120396 0.2794)
			(stroke
				(width 0.1)
				(type default)
			)
			(layer "B.Fab")
		)
		(fp_line
			(start -0.120396 0.2794)
			(end 0.12065 0.2794)
			(stroke
				(width 0.1)
				(type default)
			)
			(layer "B.Fab")
		)
		(fp_line
			(start -0.12065 -0.2794)
			(end -0.12065 -0.3048)
			(stroke
				(width 0.1)
				(type default)
			)
			(layer "B.Fab")
		)
		(fp_line
			(start -0.12065 -0.3048)
			(end -0.67945 -0.3048)
			(stroke
				(width 0.1)
				(type default)
			)
			(layer "B.Fab")
		)
		(fp_line
			(start -0.67945 0.3048)
			(end -0.120396 0.3048)
			(stroke
				(width 0.1)
				(type default)
			)
			(layer "B.Fab")
		)
		(fp_line
			(start -0.67945 -0.3048)
			(end -0.67945 0.3048)
			(stroke
				(width 0.1)
				(type default)
			)
			(layer "B.Fab")
		)
		(pad "1" smd circle
			(at 0.40005 0)
			(size 0 0)
			(layers "B.Cu" "B.Mask" "B.Paste")
			(net "SMB_P52V_VPDB_SCL")
		)
		(pad "2" smd circle
			(at -0.40005 0)
			(size 0 0)
			(layers "B.Cu" "B.Mask" "B.Paste")
			(net "SMB_BRICK2_SCL")
		)
	)
	(footprint ""
		(layer "B.Cu")
		(at 217.424 -69.723 -90)
		(property "Reference" "R135"
			(at 0 0 90)
			(layer "B.SilkS")
			(hide yes)
			(effects
				(font
					(size 1.27 1.27)
				)
				(justify mirror)
			)
		)
		(property "Value" ""
			(at 0 0 90)
			(layer "B.Fab")
			(effects
				(font
					(size 1.27 1.27)
				)
				(justify mirror)
			)
		)
		(duplicate_pad_numbers_are_jumpers no)
		(fp_line
			(start -0.7874 0.4064)
			(end 0.7874 0.4064)
			(stroke
				(width 0.1524)
				(type default)
			)
			(layer "B.SilkS")
		)
		(fp_line
			(start 0.7874 0.4064)
			(end 0.7874 -0.4064)
			(stroke
				(width 0.1524)
				(type default)
			)
			(layer "B.SilkS")
		)
		(fp_line
			(start -0.7874 -0.4064)
			(end -0.7874 0.4064)
			(stroke
				(width 0.1524)
				(type default)
			)
			(layer "B.SilkS")
		)
		(fp_line
			(start 0.7874 -0.4064)
			(end -0.7874 -0.4064)
			(stroke
				(width 0.1524)
				(type default)
			)
			(layer "B.SilkS")
		)
		(fp_line
			(start -0.67945 0.3048)
			(end -0.120396 0.3048)
			(stroke
				(width 0.1)
				(type default)
			)
			(layer "B.Fab")
		)
		(fp_line
			(start -0.120396 0.3048)
			(end -0.120396 0.2794)
			(stroke
				(width 0.1)
				(type default)
			)
			(layer "B.Fab")
		)
		(fp_line
			(start 0.12065 0.3048)
			(end 0.67945 0.3048)
			(stroke
				(width 0.1)
				(type default)
			)
			(layer "B.Fab")
		)
		(fp_line
			(start 0.67945 0.3048)
			(end 0.67945 -0.305054)
			(stroke
				(width 0.1)
				(type default)
			)
			(layer "B.Fab")
		)
		(fp_line
			(start -0.120396 0.2794)
			(end 0.12065 0.2794)
			(stroke
				(width 0.1)
				(type default)
			)
			(layer "B.Fab")
		)
		(fp_line
			(start 0.12065 0.2794)
			(end 0.12065 0.3048)
			(stroke
				(width 0.1)
				(type default)
			)
			(layer "B.Fab")
		)
		(fp_line
			(start -0.12065 -0.2794)
			(end -0.12065 -0.3048)
			(stroke
				(width 0.1)
				(type default)
			)
			(layer "B.Fab")
		)
		(fp_line
			(start 0.12065 -0.2794)
			(end -0.12065 -0.2794)
			(stroke
				(width 0.1)
				(type default)
			)
			(layer "B.Fab")
		)
		(fp_line
			(start -0.67945 -0.3048)
			(end -0.67945 0.3048)
			(stroke
				(width 0.1)
				(type default)
			)
			(layer "B.Fab")
		)
		(fp_line
			(start -0.12065 -0.3048)
			(end -0.67945 -0.3048)
			(stroke
				(width 0.1)
				(type default)
			)
			(layer "B.Fab")
		)
		(fp_line
			(start 0.12065 -0.305054)
			(end 0.12065 -0.2794)
			(stroke
				(width 0.1)
				(type default)
			)
			(layer "B.Fab")
		)
		(fp_line
			(start 0.67945 -0.305054)
			(end 0.12065 -0.305054)
			(stroke
				(width 0.1)
				(type default)
			)
			(layer "B.Fab")
		)
		(pad "1" smd circle
			(at 0.40005 0 90)
			(size 0 0)
			(layers "B.Cu" "B.Mask" "B.Paste")
			(net "P3V3_AUX")
		)
		(pad "2" smd circle
			(at -0.40005 0 90)
			(size 0 0)
			(layers "B.Cu" "B.Mask" "B.Paste")
			(net "BOARD_ID_0")
		)
	)
	(footprint ""
		(layer "B.Cu")
		(at 276.733 -43.434)
		(property "Reference" "PC11"
			(at 0 0 0)
			(layer "B.SilkS")
			(hide yes)
			(effects
				(font
					(size 1.27 1.27)
				)
				(justify mirror)
			)
		)
		(property "Value" ""
			(at 0 0 0)
			(layer "B.Fab")
			(effects
				(font
					(size 1.27 1.27)
				)
				(justify mirror)
			)
		)
		(duplicate_pad_numbers_are_jumpers no)
		(fp_line
			(start -0.7874 -0.4064)
			(end -0.7874 0.4064)
			(stroke
				(width 0.1524)
				(type default)
			)
			(layer "B.SilkS")
		)
		(fp_line
			(start -0.7874 0.4064)
			(end 0.7874 0.4064)
			(stroke
				(width 0.1524)
				(type default)
			)
			(layer "B.SilkS")
		)
		(fp_line
			(start 0.7874 -0.4064)
			(end -0.7874 -0.4064)
			(stroke
				(width 0.1524)
				(type default)
			)
			(layer "B.SilkS")
		)
		(fp_line
			(start 0.7874 0.4064)
			(end 0.7874 -0.4064)
			(stroke
				(width 0.1524)
				(type default)
			)
			(layer "B.SilkS")
		)
		(fp_line
			(start -0.67945 -0.3048)
			(end -0.67945 0.3048)
			(stroke
				(width 0.1)
				(type default)
			)
			(layer "B.Fab")
		)
		(fp_line
			(start -0.67945 0.3048)
			(end -0.120396 0.3048)
			(stroke
				(width 0.1)
				(type default)
			)
			(layer "B.Fab")
		)
		(fp_line
			(start -0.12065 -0.3048)
			(end -0.67945 -0.3048)
			(stroke
				(width 0.1)
				(type default)
			)
			(layer "B.Fab")
		)
		(fp_line
			(start -0.12065 -0.2794)
			(end -0.12065 -0.3048)
			(stroke
				(width 0.1)
				(type default)
			)
			(layer "B.Fab")
		)
		(fp_line
			(start -0.120396 0.2794)
			(end 0.12065 0.2794)
			(stroke
				(width 0.1)
				(type default)
			)
			(layer "B.Fab")
		)
		(fp_line
			(start -0.120396 0.3048)
			(end -0.120396 0.2794)
			(stroke
				(width 0.1)
				(type default)
			)
			(layer "B.Fab")
		)
		(fp_line
			(start 0.12065 -0.305054)
			(end 0.12065 -0.2794)
			(stroke
				(width 0.1)
				(type default)
			)
			(layer "B.Fab")
		)
		(fp_line
			(start 0.12065 -0.2794)
			(end -0.12065 -0.2794)
			(stroke
				(width 0.1)
				(type default)
			)
			(layer "B.Fab")
		)
		(fp_line
			(start 0.12065 0.2794)
			(end 0.12065 0.3048)
			(stroke
				(width 0.1)
				(type default)
			)
			(layer "B.Fab")
		)
		(fp_line
			(start 0.12065 0.3048)
			(end 0.67945 0.3048)
			(stroke
				(width 0.1)
				(type default)
			)
			(layer "B.Fab")
		)
		(fp_line
			(start 0.67945 -0.305054)
			(end 0.12065 -0.305054)
			(stroke
				(width 0.1)
				(type default)
			)
			(layer "B.Fab")
		)
		(fp_line
			(start 0.67945 0.3048)
			(end 0.67945 -0.305054)
			(stroke
				(width 0.1)
				(type default)
			)
			(layer "B.Fab")
		)
		(pad "1" smd circle
			(at 0.40005 0 180)
			(size 0 0)
			(layers "B.Cu" "B.Mask" "B.Paste")
			(net "P52V_HS1_ESTART")
		)
		(pad "2" smd circle
			(at -0.40005 0 180)
			(size 0 0)
			(layers "B.Cu" "B.Mask" "B.Paste")
			(net "GND_FIELD_SIGNAL")
		)
	)
	(footprint ""
		(layer "B.Cu")
		(at 232.283 -75.184 -90)
		(property "Reference" "R187"
			(at 0 0 90)
			(layer "B.SilkS")
			(hide yes)
			(effects
				(font
					(size 1.27 1.27)
				)
				(justify mirror)
			)
		)
		(property "Value" ""
			(at 0 0 90)
			(layer "B.Fab")
			(effects
				(font
					(size 1.27 1.27)
				)
				(justify mirror)
			)
		)
		(duplicate_pad_numbers_are_jumpers no)
		(fp_line
			(start -0.7874 0.4064)
			(end 0.7874 0.4064)
			(stroke
				(width 0.1524)
				(type default)
			)
			(layer "B.SilkS")
		)
		(fp_line
			(start 0.7874 0.4064)
			(end 0.7874 -0.4064)
			(stroke
				(width 0.1524)
				(type default)
			)
			(layer "B.SilkS")
		)
		(fp_line
			(start -0.7874 -0.4064)
			(end -0.7874 0.4064)
			(stroke
				(width 0.1524)
				(type default)
			)
			(layer "B.SilkS")
		)
		(fp_line
			(start 0.7874 -0.4064)
			(end -0.7874 -0.4064)
			(stroke
				(width 0.1524)
				(type default)
			)
			(layer "B.SilkS")
		)
		(fp_line
			(start -0.67945 0.3048)
			(end -0.120396 0.3048)
			(stroke
				(width 0.1)
				(type default)
			)
			(layer "B.Fab")
		)
		(fp_line
			(start -0.120396 0.3048)
			(end -0.120396 0.2794)
			(stroke
				(width 0.1)
				(type default)
			)
			(layer "B.Fab")
		)
		(fp_line
			(start 0.12065 0.3048)
			(end 0.67945 0.3048)
			(stroke
				(width 0.1)
				(type default)
			)
			(layer "B.Fab")
		)
		(fp_line
			(start 0.67945 0.3048)
			(end 0.67945 -0.305054)
			(stroke
				(width 0.1)
				(type default)
			)
			(layer "B.Fab")
		)
		(fp_line
			(start -0.120396 0.2794)
			(end 0.12065 0.2794)
			(stroke
				(width 0.1)
				(type default)
			)
			(layer "B.Fab")
		)
		(fp_line
			(start 0.12065 0.2794)
			(end 0.12065 0.3048)
			(stroke
				(width 0.1)
				(type default)
			)
			(layer "B.Fab")
		)
		(fp_line
			(start -0.12065 -0.2794)
			(end -0.12065 -0.3048)
			(stroke
				(width 0.1)
				(type default)
			)
			(layer "B.Fab")
		)
		(fp_line
			(start 0.12065 -0.2794)
			(end -0.12065 -0.2794)
			(stroke
				(width 0.1)
				(type default)
			)
			(layer "B.Fab")
		)
		(fp_line
			(start -0.67945 -0.3048)
			(end -0.67945 0.3048)
			(stroke
				(width 0.1)
				(type default)
			)
			(layer "B.Fab")
		)
		(fp_line
			(start -0.12065 -0.3048)
			(end -0.67945 -0.3048)
			(stroke
				(width 0.1)
				(type default)
			)
			(layer "B.Fab")
		)
		(fp_line
			(start 0.12065 -0.305054)
			(end 0.12065 -0.2794)
			(stroke
				(width 0.1)
				(type default)
			)
			(layer "B.Fab")
		)
		(fp_line
			(start 0.67945 -0.305054)
			(end 0.12065 -0.305054)
			(stroke
				(width 0.1)
				(type default)
			)
			(layer "B.Fab")
		)
		(pad "1" smd circle
			(at 0.40005 0 90)
			(size 0 0)
			(layers "B.Cu" "B.Mask" "B.Paste")
			(net "GND")
		)
		(pad "2" smd circle
			(at -0.40005 0 90)
			(size 0 0)
			(layers "B.Cu" "B.Mask" "B.Paste")
			(net "PWRGD_P3V3_AUX_MB_R1")
		)
	)
	(footprint ""
		(layer "B.Cu")
		(at 221.615 -83.439 -90)
		(property "Reference" "U10"
			(at 1.016 -3.14833 270)
			(unlocked yes)
			(layer "B.SilkS")
			(effects
				(font
					(size 0.7874 0.5842)
					(thickness 0.1524)
				)
				(justify left mirror)
			)
		)
		(property "Value" ""
			(at 0 0 90)
			(layer "B.Fab")
			(effects
				(font
					(size 1.27 1.27)
				)
				(justify mirror)
			)
		)
		(duplicate_pad_numbers_are_jumpers no)
		(fp_line
			(start -1.4224 2.5146)
			(end -1.4224 -2.5146)
			(stroke
				(width 0.1524)
				(type default)
			)
			(layer "B.SilkS")
		)
		(fp_line
			(start 1.4224 2.5146)
			(end -1.4224 2.5146)
			(stroke
				(width 0.1524)
				(type default)
			)
			(layer "B.SilkS")
		)
		(fp_line
			(start 0 -2.0574)
			(end 0.4572 -2.5146)
			(stroke
				(width 0.1524)
				(type default)
			)
			(layer "B.SilkS")
		)
		(fp_line
			(start -1.4224 -2.5146)
			(end -0.4572 -2.5146)
			(stroke
				(width 0.1524)
				(type default)
			)
			(layer "B.SilkS")
		)
		(fp_line
			(start -0.4572 -2.5146)
			(end 0 -2.0574)
			(stroke
				(width 0.1524)
				(type default)
			)
			(layer "B.SilkS")
		)
		(fp_line
			(start 0.4572 -2.5146)
			(end 1.4224 -2.5146)
			(stroke
				(width 0.1524)
				(type default)
			)
			(layer "B.SilkS")
		)
		(fp_line
			(start 1.4224 -2.5146)
			(end 1.4224 2.5146)
			(stroke
				(width 0.1524)
				(type default)
			)
			(layer "B.SilkS")
		)
		(fp_poly
			(pts
				(xy 2.575814 -2.8702) (xy 2.956814 -3.6322) (xy 2.194814 -3.6322)
			)
			(stroke
				(width 0)
				(type default)
			)
			(fill yes)
			(layer "B.SilkS")
		)
		(fp_line
			(start -2.0066 2.5146)
			(end -2.0066 2.112264)
			(stroke
				(width 0.1)
				(type default)
			)
			(layer "B.Fab")
		)
		(fp_line
			(start 2.0066 2.5146)
			(end -2.0066 2.5146)
			(stroke
				(width 0.1)
				(type default)
			)
			(layer "B.Fab")
		)
		(fp_line
			(start -2.642616 2.112264)
			(end -2.642616 -2.112264)
			(stroke
				(width 0.1)
				(type default)
			)
			(layer "B.Fab")
		)
		(fp_line
			(start -2.0066 2.112264)
			(end -2.642616 2.112264)
			(stroke
				(width 0.1)
				(type default)
			)
			(layer "B.Fab")
		)
		(fp_line
			(start 2.0066 2.112264)
			(end 2.0066 2.5146)
			(stroke
				(width 0.1)
				(type default)
			)
			(layer "B.Fab")
		)
		(fp_line
			(start 2.648712 2.112264)
			(end 2.0066 2.112264)
			(stroke
				(width 0.1)
				(type default)
			)
			(layer "B.Fab")
		)
		(fp_line
			(start -2.642616 -2.112264)
			(end -2.0066 -2.112264)
			(stroke
				(width 0.1)
				(type default)
			)
			(layer "B.Fab")
		)
		(fp_line
			(start -2.0066 -2.112264)
			(end -2.0066 -2.5146)
			(stroke
				(width 0.1)
				(type default)
			)
			(layer "B.Fab")
		)
		(fp_line
			(start 2.0066 -2.114804)
			(end 2.648712 -2.114804)
			(stroke
				(width 0.1)
				(type default)
			)
			(layer "B.Fab")
		)
		(fp_line
			(start 2.648712 -2.114804)
			(end 2.648712 2.112264)
			(stroke
				(width 0.1)
				(type default)
			)
			(layer "B.Fab")
		)
		(fp_line
			(start -2.0066 -2.5146)
			(end 2.0066 -2.5146)
			(stroke
				(width 0.1)
				(type default)
			)
			(layer "B.Fab")
		)
		(fp_line
			(start 2.0066 -2.5146)
			(end 2.0066 -2.114804)
			(stroke
				(width 0.1)
				(type default)
			)
			(layer "B.Fab")
		)
		(fp_poly
			(pts
				(xy 3.6322 -1.869186) (xy 4.3942 -1.488186) (xy 4.3942 -2.250186)
			)
			(stroke
				(width 0)
				(type default)
			)
			(fill yes)
			(layer "B.Fab")
		)
		(pad "1" smd rect
			(at 2.6416 -1.905 180)
			(size 0.5588 1.7272)
			(layers "B.Cu" "B.Mask" "B.Paste")
			(net "FRU_ADDR0")
		)
		(pad "2" smd rect
			(at 2.6416 -0.635 180)
			(size 0.5588 1.7272)
			(layers "B.Cu" "B.Mask" "B.Paste")
			(net "FRU_ADDR1")
		)
		(pad "3" smd rect
			(at 2.6416 0.635 180)
			(size 0.5588 1.7272)
			(layers "B.Cu" "B.Mask" "B.Paste")
			(net "FRU_ADDR2")
		)
		(pad "4" smd rect
			(at 2.6416 1.905 180)
			(size 0.5588 1.7272)
			(layers "B.Cu" "B.Mask" "B.Paste")
			(net "GND")
		)
		(pad "5" smd rect
			(at -2.6416 1.905 180)
			(size 0.5588 1.7272)
			(layers "B.Cu" "B.Mask" "B.Paste")
			(net "SMB_FRU_DAT")
		)
		(pad "6" smd rect
			(at -2.6416 0.635 180)
			(size 0.5588 1.7272)
			(layers "B.Cu" "B.Mask" "B.Paste")
			(net "SMB_FRU_CLK")
		)
		(pad "7" smd rect
			(at -2.6416 -0.635 180)
			(size 0.5588 1.7272)
			(layers "B.Cu" "B.Mask" "B.Paste")
			(net "FRU_WP_N")
		)
		(pad "8" smd rect
			(at -2.6416 -1.905 180)
			(size 0.5588 1.7272)
			(layers "B.Cu" "B.Mask" "B.Paste")
			(net "P3V3_AUX")
		)
	)
	(footprint ""
		(layer "B.Cu")
		(at 223.52 -75.057 -90)
		(property "Reference" "R45"
			(at 0 0 90)
			(layer "B.SilkS")
			(hide yes)
			(effects
				(font
					(size 1.27 1.27)
				)
				(justify mirror)
			)
		)
		(property "Value" ""
			(at 0 0 90)
			(layer "B.Fab")
			(effects
				(font
					(size 1.27 1.27)
				)
				(justify mirror)
			)
		)
		(duplicate_pad_numbers_are_jumpers no)
		(fp_line
			(start -0.7874 0.4064)
			(end 0.7874 0.4064)
			(stroke
				(width 0.1524)
				(type default)
			)
			(layer "B.SilkS")
		)
		(fp_line
			(start 0.7874 0.4064)
			(end 0.7874 -0.4064)
			(stroke
				(width 0.1524)
				(type default)
			)
			(layer "B.SilkS")
		)
		(fp_line
			(start -0.7874 -0.4064)
			(end -0.7874 0.4064)
			(stroke
				(width 0.1524)
				(type default)
			)
			(layer "B.SilkS")
		)
		(fp_line
			(start 0.7874 -0.4064)
			(end -0.7874 -0.4064)
			(stroke
				(width 0.1524)
				(type default)
			)
			(layer "B.SilkS")
		)
		(fp_line
			(start -0.67945 0.3048)
			(end -0.120396 0.3048)
			(stroke
				(width 0.1)
				(type default)
			)
			(layer "B.Fab")
		)
		(fp_line
			(start -0.120396 0.3048)
			(end -0.120396 0.2794)
			(stroke
				(width 0.1)
				(type default)
			)
			(layer "B.Fab")
		)
		(fp_line
			(start 0.12065 0.3048)
			(end 0.67945 0.3048)
			(stroke
				(width 0.1)
				(type default)
			)
			(layer "B.Fab")
		)
		(fp_line
			(start 0.67945 0.3048)
			(end 0.67945 -0.305054)
			(stroke
				(width 0.1)
				(type default)
			)
			(layer "B.Fab")
		)
		(fp_line
			(start -0.120396 0.2794)
			(end 0.12065 0.2794)
			(stroke
				(width 0.1)
				(type default)
			)
			(layer "B.Fab")
		)
		(fp_line
			(start 0.12065 0.2794)
			(end 0.12065 0.3048)
			(stroke
				(width 0.1)
				(type default)
			)
			(layer "B.Fab")
		)
		(fp_line
			(start -0.12065 -0.2794)
			(end -0.12065 -0.3048)
			(stroke
				(width 0.1)
				(type default)
			)
			(layer "B.Fab")
		)
		(fp_line
			(start 0.12065 -0.2794)
			(end -0.12065 -0.2794)
			(stroke
				(width 0.1)
				(type default)
			)
			(layer "B.Fab")
		)
		(fp_line
			(start -0.67945 -0.3048)
			(end -0.67945 0.3048)
			(stroke
				(width 0.1)
				(type default)
			)
			(layer "B.Fab")
		)
		(fp_line
			(start -0.12065 -0.3048)
			(end -0.67945 -0.3048)
			(stroke
				(width 0.1)
				(type default)
			)
			(layer "B.Fab")
		)
		(fp_line
			(start 0.12065 -0.305054)
			(end 0.12065 -0.2794)
			(stroke
				(width 0.1)
				(type default)
			)
			(layer "B.Fab")
		)
		(fp_line
			(start 0.67945 -0.305054)
			(end 0.12065 -0.305054)
			(stroke
				(width 0.1)
				(type default)
			)
			(layer "B.Fab")
		)
		(pad "1" smd circle
			(at 0.40005 0 90)
			(size 0 0)
			(layers "B.Cu" "B.Mask" "B.Paste")
			(net "GND")
		)
		(pad "2" smd circle
			(at -0.40005 0 90)
			(size 0 0)
			(layers "B.Cu" "B.Mask" "B.Paste")
			(net "FRU_ADDR0")
		)
	)
	(footprint ""
		(layer "B.Cu")
		(at 211.074 -69.723 -90)
		(property "Reference" "R90"
			(at 0 0 90)
			(layer "B.SilkS")
			(hide yes)
			(effects
				(font
					(size 1.27 1.27)
				)
				(justify mirror)
			)
		)
		(property "Value" ""
			(at 0 0 90)
			(layer "B.Fab")
			(effects
				(font
					(size 1.27 1.27)
				)
				(justify mirror)
			)
		)
		(duplicate_pad_numbers_are_jumpers no)
		(fp_line
			(start -0.7874 0.4064)
			(end 0.7874 0.4064)
			(stroke
				(width 0.1524)
				(type default)
			)
			(layer "B.SilkS")
		)
		(fp_line
			(start 0.7874 0.4064)
			(end 0.7874 -0.4064)
			(stroke
				(width 0.1524)
				(type default)
			)
			(layer "B.SilkS")
		)
		(fp_line
			(start -0.7874 -0.4064)
			(end -0.7874 0.4064)
			(stroke
				(width 0.1524)
				(type default)
			)
			(layer "B.SilkS")
		)
		(fp_line
			(start 0.7874 -0.4064)
			(end -0.7874 -0.4064)
			(stroke
				(width 0.1524)
				(type default)
			)
			(layer "B.SilkS")
		)
		(fp_line
			(start -0.67945 0.3048)
			(end -0.120396 0.3048)
			(stroke
				(width 0.1)
				(type default)
			)
			(layer "B.Fab")
		)
		(fp_line
			(start -0.120396 0.3048)
			(end -0.120396 0.2794)
			(stroke
				(width 0.1)
				(type default)
			)
			(layer "B.Fab")
		)
		(fp_line
			(start 0.12065 0.3048)
			(end 0.67945 0.3048)
			(stroke
				(width 0.1)
				(type default)
			)
			(layer "B.Fab")
		)
		(fp_line
			(start 0.67945 0.3048)
			(end 0.67945 -0.305054)
			(stroke
				(width 0.1)
				(type default)
			)
			(layer "B.Fab")
		)
		(fp_line
			(start -0.120396 0.2794)
			(end 0.12065 0.2794)
			(stroke
				(width 0.1)
				(type default)
			)
			(layer "B.Fab")
		)
		(fp_line
			(start 0.12065 0.2794)
			(end 0.12065 0.3048)
			(stroke
				(width 0.1)
				(type default)
			)
			(layer "B.Fab")
		)
		(fp_line
			(start -0.12065 -0.2794)
			(end -0.12065 -0.3048)
			(stroke
				(width 0.1)
				(type default)
			)
			(layer "B.Fab")
		)
		(fp_line
			(start 0.12065 -0.2794)
			(end -0.12065 -0.2794)
			(stroke
				(width 0.1)
				(type default)
			)
			(layer "B.Fab")
		)
		(fp_line
			(start -0.67945 -0.3048)
			(end -0.67945 0.3048)
			(stroke
				(width 0.1)
				(type default)
			)
			(layer "B.Fab")
		)
		(fp_line
			(start -0.12065 -0.3048)
			(end -0.67945 -0.3048)
			(stroke
				(width 0.1)
				(type default)
			)
			(layer "B.Fab")
		)
		(fp_line
			(start 0.12065 -0.305054)
			(end 0.12065 -0.2794)
			(stroke
				(width 0.1)
				(type default)
			)
			(layer "B.Fab")
		)
		(fp_line
			(start 0.67945 -0.305054)
			(end 0.12065 -0.305054)
			(stroke
				(width 0.1)
				(type default)
			)
			(layer "B.Fab")
		)
		(pad "1" smd circle
			(at 0.40005 0 90)
			(size 0 0)
			(layers "B.Cu" "B.Mask" "B.Paste")
			(net "P3V3_AUX")
		)
		(pad "2" smd circle
			(at -0.40005 0 90)
			(size 0 0)
			(layers "B.Cu" "B.Mask" "B.Paste")
			(net "SKU_ID_2")
		)
	)
	(footprint ""
		(layer "B.Cu")
		(at 273.558 -46.482 -90)
		(property "Reference" "R158"
			(at 0 0 90)
			(layer "B.SilkS")
			(hide yes)
			(effects
				(font
					(size 1.27 1.27)
				)
				(justify mirror)
			)
		)
		(property "Value" ""
			(at 0 0 90)
			(layer "B.Fab")
			(effects
				(font
					(size 1.27 1.27)
				)
				(justify mirror)
			)
		)
		(duplicate_pad_numbers_are_jumpers no)
		(fp_line
			(start -0.7874 0.4064)
			(end 0.7874 0.4064)
			(stroke
				(width 0.1524)
				(type default)
			)
			(layer "B.SilkS")
		)
		(fp_line
			(start 0.7874 0.4064)
			(end 0.7874 -0.4064)
			(stroke
				(width 0.1524)
				(type default)
			)
			(layer "B.SilkS")
		)
		(fp_line
			(start -0.7874 -0.4064)
			(end -0.7874 0.4064)
			(stroke
				(width 0.1524)
				(type default)
			)
			(layer "B.SilkS")
		)
		(fp_line
			(start 0.7874 -0.4064)
			(end -0.7874 -0.4064)
			(stroke
				(width 0.1524)
				(type default)
			)
			(layer "B.SilkS")
		)
		(fp_line
			(start -0.67945 0.3048)
			(end -0.120396 0.3048)
			(stroke
				(width 0.1)
				(type default)
			)
			(layer "B.Fab")
		)
		(fp_line
			(start -0.120396 0.3048)
			(end -0.120396 0.2794)
			(stroke
				(width 0.1)
				(type default)
			)
			(layer "B.Fab")
		)
		(fp_line
			(start 0.12065 0.3048)
			(end 0.67945 0.3048)
			(stroke
				(width 0.1)
				(type default)
			)
			(layer "B.Fab")
		)
		(fp_line
			(start 0.67945 0.3048)
			(end 0.67945 -0.305054)
			(stroke
				(width 0.1)
				(type default)
			)
			(layer "B.Fab")
		)
		(fp_line
			(start -0.120396 0.2794)
			(end 0.12065 0.2794)
			(stroke
				(width 0.1)
				(type default)
			)
			(layer "B.Fab")
		)
		(fp_line
			(start 0.12065 0.2794)
			(end 0.12065 0.3048)
			(stroke
				(width 0.1)
				(type default)
			)
			(layer "B.Fab")
		)
		(fp_line
			(start -0.12065 -0.2794)
			(end -0.12065 -0.3048)
			(stroke
				(width 0.1)
				(type default)
			)
			(layer "B.Fab")
		)
		(fp_line
			(start 0.12065 -0.2794)
			(end -0.12065 -0.2794)
			(stroke
				(width 0.1)
				(type default)
			)
			(layer "B.Fab")
		)
		(fp_line
			(start -0.67945 -0.3048)
			(end -0.67945 0.3048)
			(stroke
				(width 0.1)
				(type default)
			)
			(layer "B.Fab")
		)
		(fp_line
			(start -0.12065 -0.3048)
			(end -0.67945 -0.3048)
			(stroke
				(width 0.1)
				(type default)
			)
			(layer "B.Fab")
		)
		(fp_line
			(start 0.12065 -0.305054)
			(end 0.12065 -0.2794)
			(stroke
				(width 0.1)
				(type default)
			)
			(layer "B.Fab")
		)
		(fp_line
			(start 0.67945 -0.305054)
			(end 0.12065 -0.305054)
			(stroke
				(width 0.1)
				(type default)
			)
			(layer "B.Fab")
		)
		(pad "1" smd circle
			(at 0.40005 0 90)
			(size 0 0)
			(layers "B.Cu" "B.Mask" "B.Paste")
			(net "P52V_HS1_ADR0")
		)
		(pad "2" smd circle
			(at -0.40005 0 90)
			(size 0 0)
			(layers "B.Cu" "B.Mask" "B.Paste")
			(net "GND_FIELD_SIGNAL")
		)
	)
	(footprint ""
		(layer "B.Cu")
		(at 211.836 -76.073 90)
		(property "Reference" "U4"
			(at -0.6858 -4.71297 270)
			(unlocked yes)
			(layer "B.SilkS")
			(effects
				(font
					(size 0.7874 0.5842)
					(thickness 0.1524)
				)
				(justify left mirror)
			)
		)
		(property "Value" ""
			(at 0 0 90)
			(layer "B.Fab")
			(effects
				(font
					(size 1.27 1.27)
				)
				(justify mirror)
			)
		)
		(duplicate_pad_numbers_are_jumpers no)
		(fp_line
			(start 2.0066 -3.9624)
			(end 0.5842 -3.9624)
			(stroke
				(width 0.1524)
				(type default)
			)
			(layer "B.SilkS")
		)
		(fp_line
			(start 0.5842 -3.9624)
			(end 0 -3.3782)
			(stroke
				(width 0.1524)
				(type default)
			)
			(layer "B.SilkS")
		)
		(fp_line
			(start -0.5842 -3.9624)
			(end -2.0066 -3.9624)
			(stroke
				(width 0.1524)
				(type default)
			)
			(layer "B.SilkS")
		)
		(fp_line
			(start -2.0066 -3.9624)
			(end -2.0066 3.9624)
			(stroke
				(width 0.1524)
				(type default)
			)
			(layer "B.SilkS")
		)
		(fp_line
			(start 0 -3.3782)
			(end -0.5842 -3.9624)
			(stroke
				(width 0.1524)
				(type default)
			)
			(layer "B.SilkS")
		)
		(fp_line
			(start 2.0066 3.9624)
			(end 2.0066 -3.9624)
			(stroke
				(width 0.1524)
				(type default)
			)
			(layer "B.SilkS")
		)
		(fp_line
			(start -2.0066 3.9624)
			(end 2.0066 3.9624)
			(stroke
				(width 0.1524)
				(type default)
			)
			(layer "B.SilkS")
		)
		(fp_poly
			(pts
				(xy 2.159 -4.6736) (xy 2.54 -5.4356) (xy 1.778 -5.4356)
			)
			(stroke
				(width 0)
				(type default)
			)
			(fill yes)
			(layer "B.SilkS")
		)
		(fp_line
			(start 2.2479 -3.974846)
			(end 2.2479 -3.80365)
			(stroke
				(width 0.1)
				(type default)
			)
			(layer "B.Fab")
		)
		(fp_line
			(start -2.2479 -3.974846)
			(end 2.2479 -3.974846)
			(stroke
				(width 0.1)
				(type default)
			)
			(layer "B.Fab")
		)
		(fp_line
			(start 3.724402 -3.80365)
			(end 3.724402 3.80365)
			(stroke
				(width 0.1)
				(type default)
			)
			(layer "B.Fab")
		)
		(fp_line
			(start 2.2479 -3.80365)
			(end 3.724402 -3.80365)
			(stroke
				(width 0.1)
				(type default)
			)
			(layer "B.Fab")
		)
		(fp_line
			(start -2.2479 -3.80365)
			(end -2.2479 -3.974846)
			(stroke
				(width 0.1)
				(type default)
			)
			(layer "B.Fab")
		)
		(fp_line
			(start -3.7211 -3.80365)
			(end -2.2479 -3.80365)
			(stroke
				(width 0.1)
				(type default)
			)
			(layer "B.Fab")
		)
		(fp_line
			(start 3.7211 -3.34645)
			(end 3.7211 -3.80365)
			(stroke
				(width 0.1)
				(type default)
			)
			(layer "B.Fab")
		)
		(fp_line
			(start 3.724402 3.80365)
			(end 2.2479 3.80365)
			(stroke
				(width 0.1)
				(type default)
			)
			(layer "B.Fab")
		)
		(fp_line
			(start 2.2479 3.80365)
			(end 2.2479 3.9624)
			(stroke
				(width 0.1)
				(type default)
			)
			(layer "B.Fab")
		)
		(fp_line
			(start -2.2479 3.80365)
			(end -3.7211 3.80365)
			(stroke
				(width 0.1)
				(type default)
			)
			(layer "B.Fab")
		)
		(fp_line
			(start -3.7211 3.80365)
			(end -3.7211 -3.80365)
			(stroke
				(width 0.1)
				(type default)
			)
			(layer "B.Fab")
		)
		(fp_line
			(start 2.2479 3.9624)
			(end -2.2479 3.9624)
			(stroke
				(width 0.1)
				(type default)
			)
			(layer "B.Fab")
		)
		(fp_line
			(start -2.2479 3.9624)
			(end -2.2479 3.80365)
			(stroke
				(width 0.1)
				(type default)
			)
			(layer "B.Fab")
		)
		(fp_poly
			(pts
				(xy 3.8862 -3.570986) (xy 4.6482 -3.189986) (xy 4.6482 -3.951986)
			)
			(stroke
				(width 0)
				(type default)
			)
			(fill yes)
			(layer "B.Fab")
		)
		(pad "1" smd rect
			(at 2.921 -3.57505)
			(size 0.3556 1.4986)
			(layers "B.Cu" "B.Mask" "B.Paste")
			(net "PU_U4_PIN1")
		)
		(pad "2" smd rect
			(at 2.921 -2.925064)
			(size 0.3556 1.4986)
			(layers "B.Cu" "B.Mask" "B.Paste")
			(net "PCA9555_A1")
		)
		(pad "3" smd rect
			(at 2.921 -2.275078)
			(size 0.3556 1.4986)
			(layers "B.Cu" "B.Mask" "B.Paste")
			(net "PCA9555_A2")
		)
		(pad "4" smd rect
			(at 2.921 -1.625092)
			(size 0.3556 1.4986)
			(layers "B.Cu" "B.Mask" "B.Paste")
			(net "P52V_HS1_FLT")
		)
		(pad "5" smd rect
			(at 2.921 -0.975106)
			(size 0.3556 1.4986)
			(layers "B.Cu" "B.Mask" "B.Paste")
			(net "P12V_BRICK0_ALERT_N")
		)
		(pad "6" smd rect
			(at 2.921 -0.32512)
			(size 0.3556 1.4986)
			(layers "B.Cu" "B.Mask" "B.Paste")
			(net "P12V_BRICK1_ALERT_N")
		)
		(pad "7" smd rect
			(at 2.921 0.32512)
			(size 0.3556 1.4986)
			(layers "B.Cu" "B.Mask" "B.Paste")
			(net "P12V_BRICK2_ALERT_N")
		)
		(pad "8" smd rect
			(at 2.921 0.975106)
			(size 0.3556 1.4986)
			(layers "B.Cu" "B.Mask" "B.Paste")
			(net "P12V_BRICK3_ALERT_N")
		)
		(pad "9" smd rect
			(at 2.921 1.625092)
			(size 0.3556 1.4986)
			(layers "B.Cu" "B.Mask" "B.Paste")
			(net "TP_U4_P05")
		)
		(pad "10" smd rect
			(at 2.921 2.275078)
			(size 0.3556 1.4986)
			(layers "B.Cu" "B.Mask" "B.Paste")
			(net "TP_U4_P06")
		)
		(pad "11" smd rect
			(at 2.921 2.925064)
			(size 0.3556 1.4986)
			(layers "B.Cu" "B.Mask" "B.Paste")
			(net "P12V_HPDB_PWRGD")
		)
		(pad "12" smd rect
			(at 2.921 3.57505)
			(size 0.3556 1.4986)
			(layers "B.Cu" "B.Mask" "B.Paste")
			(net "GND")
		)
		(pad "13" smd rect
			(at -2.921 3.57505)
			(size 0.3556 1.4986)
			(layers "B.Cu" "B.Mask" "B.Paste")
			(net "PWRGD_P3V3_HPDB")
		)
		(pad "14" smd rect
			(at -2.921 2.925064)
			(size 0.3556 1.4986)
			(layers "B.Cu" "B.Mask" "B.Paste")
			(net "PRSNT_HPDB_N")
		)
		(pad "15" smd rect
			(at -2.921 2.275078)
			(size 0.3556 1.4986)
			(layers "B.Cu" "B.Mask" "B.Paste")
			(net "BOARD_ID_0")
		)
		(pad "16" smd rect
			(at -2.921 1.625092)
			(size 0.3556 1.4986)
			(layers "B.Cu" "B.Mask" "B.Paste")
			(net "BOARD_ID_1")
		)
		(pad "17" smd rect
			(at -2.921 0.975106)
			(size 0.3556 1.4986)
			(layers "B.Cu" "B.Mask" "B.Paste")
			(net "BOARD_ID_2")
		)
		(pad "18" smd rect
			(at -2.921 0.32512)
			(size 0.3556 1.4986)
			(layers "B.Cu" "B.Mask" "B.Paste")
			(net "SKU_ID_0")
		)
		(pad "19" smd rect
			(at -2.921 -0.32512)
			(size 0.3556 1.4986)
			(layers "B.Cu" "B.Mask" "B.Paste")
			(net "SKU_ID_1")
		)
		(pad "20" smd rect
			(at -2.921 -0.975106)
			(size 0.3556 1.4986)
			(layers "B.Cu" "B.Mask" "B.Paste")
			(net "SKU_ID_2")
		)
		(pad "21" smd rect
			(at -2.921 -1.625092)
			(size 0.3556 1.4986)
			(layers "B.Cu" "B.Mask" "B.Paste")
			(net "PCA9555_A0")
		)
		(pad "22" smd rect
			(at -2.921 -2.275078)
			(size 0.3556 1.4986)
			(layers "B.Cu" "B.Mask" "B.Paste")
			(net "SMB_VPDB_IOEXP_SCL")
		)
		(pad "23" smd rect
			(at -2.921 -2.925064)
			(size 0.3556 1.4986)
			(layers "B.Cu" "B.Mask" "B.Paste")
			(net "SMB_VPDB_IOEXP_SDA")
		)
		(pad "24" smd rect
			(at -2.921 -3.57505)
			(size 0.3556 1.4986)
			(layers "B.Cu" "B.Mask" "B.Paste")
			(net "P3V3_AUX")
		)
	)
	(footprint ""
		(layer "B.Cu")
		(at 208.153 -82.55 -90)
		(property "Reference" "R22"
			(at 0 0 90)
			(layer "B.SilkS")
			(hide yes)
			(effects
				(font
					(size 1.27 1.27)
				)
				(justify mirror)
			)
		)
		(property "Value" ""
			(at 0 0 90)
			(layer "B.Fab")
			(effects
				(font
					(size 1.27 1.27)
				)
				(justify mirror)
			)
		)
		(duplicate_pad_numbers_are_jumpers no)
		(fp_line
			(start -0.7874 0.4064)
			(end 0.7874 0.4064)
			(stroke
				(width 0.1524)
				(type default)
			)
			(layer "B.SilkS")
		)
		(fp_line
			(start 0.7874 0.4064)
			(end 0.7874 -0.4064)
			(stroke
				(width 0.1524)
				(type default)
			)
			(layer "B.SilkS")
		)
		(fp_line
			(start -0.7874 -0.4064)
			(end -0.7874 0.4064)
			(stroke
				(width 0.1524)
				(type default)
			)
			(layer "B.SilkS")
		)
		(fp_line
			(start 0.7874 -0.4064)
			(end -0.7874 -0.4064)
			(stroke
				(width 0.1524)
				(type default)
			)
			(layer "B.SilkS")
		)
		(fp_line
			(start -0.67945 0.3048)
			(end -0.120396 0.3048)
			(stroke
				(width 0.1)
				(type default)
			)
			(layer "B.Fab")
		)
		(fp_line
			(start -0.120396 0.3048)
			(end -0.120396 0.2794)
			(stroke
				(width 0.1)
				(type default)
			)
			(layer "B.Fab")
		)
		(fp_line
			(start 0.12065 0.3048)
			(end 0.67945 0.3048)
			(stroke
				(width 0.1)
				(type default)
			)
			(layer "B.Fab")
		)
		(fp_line
			(start 0.67945 0.3048)
			(end 0.67945 -0.305054)
			(stroke
				(width 0.1)
				(type default)
			)
			(layer "B.Fab")
		)
		(fp_line
			(start -0.120396 0.2794)
			(end 0.12065 0.2794)
			(stroke
				(width 0.1)
				(type default)
			)
			(layer "B.Fab")
		)
		(fp_line
			(start 0.12065 0.2794)
			(end 0.12065 0.3048)
			(stroke
				(width 0.1)
				(type default)
			)
			(layer "B.Fab")
		)
		(fp_line
			(start -0.12065 -0.2794)
			(end -0.12065 -0.3048)
			(stroke
				(width 0.1)
				(type default)
			)
			(layer "B.Fab")
		)
		(fp_line
			(start 0.12065 -0.2794)
			(end -0.12065 -0.2794)
			(stroke
				(width 0.1)
				(type default)
			)
			(layer "B.Fab")
		)
		(fp_line
			(start -0.67945 -0.3048)
			(end -0.67945 0.3048)
			(stroke
				(width 0.1)
				(type default)
			)
			(layer "B.Fab")
		)
		(fp_line
			(start -0.12065 -0.3048)
			(end -0.67945 -0.3048)
			(stroke
				(width 0.1)
				(type default)
			)
			(layer "B.Fab")
		)
		(fp_line
			(start 0.12065 -0.305054)
			(end 0.12065 -0.2794)
			(stroke
				(width 0.1)
				(type default)
			)
			(layer "B.Fab")
		)
		(fp_line
			(start 0.67945 -0.305054)
			(end 0.12065 -0.305054)
			(stroke
				(width 0.1)
				(type default)
			)
			(layer "B.Fab")
		)
		(pad "1" smd circle
			(at 0.40005 0 90)
			(size 0 0)
			(layers "B.Cu" "B.Mask" "B.Paste")
			(net "PCA9555_A1")
		)
		(pad "2" smd circle
			(at -0.40005 0 90)
			(size 0 0)
			(layers "B.Cu" "B.Mask" "B.Paste")
			(net "GND")
		)
	)
	(footprint ""
		(layer "B.Cu")
		(at 58.928 -76.327 180)
		(property "Reference" "R180"
			(at 0 0 0)
			(layer "B.SilkS")
			(hide yes)
			(effects
				(font
					(size 1.27 1.27)
				)
				(justify mirror)
			)
		)
		(property "Value" ""
			(at 0 0 0)
			(layer "B.Fab")
			(effects
				(font
					(size 1.27 1.27)
				)
				(justify mirror)
			)
		)
		(duplicate_pad_numbers_are_jumpers no)
		(fp_line
			(start 0.7874 0.4064)
			(end 0.7874 -0.4064)
			(stroke
				(width 0.1524)
				(type default)
			)
			(layer "B.SilkS")
		)
		(fp_line
			(start 0.7874 -0.4064)
			(end -0.7874 -0.4064)
			(stroke
				(width 0.1524)
				(type default)
			)
			(layer "B.SilkS")
		)
		(fp_line
			(start -0.7874 0.4064)
			(end 0.7874 0.4064)
			(stroke
				(width 0.1524)
				(type default)
			)
			(layer "B.SilkS")
		)
		(fp_line
			(start -0.7874 -0.4064)
			(end -0.7874 0.4064)
			(stroke
				(width 0.1524)
				(type default)
			)
			(layer "B.SilkS")
		)
		(fp_line
			(start 0.67945 0.3048)
			(end 0.67945 -0.305054)
			(stroke
				(width 0.1)
				(type default)
			)
			(layer "B.Fab")
		)
		(fp_line
			(start 0.67945 -0.305054)
			(end 0.12065 -0.305054)
			(stroke
				(width 0.1)
				(type default)
			)
			(layer "B.Fab")
		)
		(fp_line
			(start 0.12065 0.3048)
			(end 0.67945 0.3048)
			(stroke
				(width 0.1)
				(type default)
			)
			(layer "B.Fab")
		)
		(fp_line
			(start 0.12065 0.2794)
			(end 0.12065 0.3048)
			(stroke
				(width 0.1)
				(type default)
			)
			(layer "B.Fab")
		)
		(fp_line
			(start 0.12065 -0.2794)
			(end -0.12065 -0.2794)
			(stroke
				(width 0.1)
				(type default)
			)
			(layer "B.Fab")
		)
		(fp_line
			(start 0.12065 -0.305054)
			(end 0.12065 -0.2794)
			(stroke
				(width 0.1)
				(type default)
			)
			(layer "B.Fab")
		)
		(fp_line
			(start -0.120396 0.3048)
			(end -0.120396 0.2794)
			(stroke
				(width 0.1)
				(type default)
			)
			(layer "B.Fab")
		)
		(fp_line
			(start -0.120396 0.2794)
			(end 0.12065 0.2794)
			(stroke
				(width 0.1)
				(type default)
			)
			(layer "B.Fab")
		)
		(fp_line
			(start -0.12065 -0.2794)
			(end -0.12065 -0.3048)
			(stroke
				(width 0.1)
				(type default)
			)
			(layer "B.Fab")
		)
		(fp_line
			(start -0.12065 -0.3048)
			(end -0.67945 -0.3048)
			(stroke
				(width 0.1)
				(type default)
			)
			(layer "B.Fab")
		)
		(fp_line
			(start -0.67945 0.3048)
			(end -0.120396 0.3048)
			(stroke
				(width 0.1)
				(type default)
			)
			(layer "B.Fab")
		)
		(fp_line
			(start -0.67945 -0.3048)
			(end -0.67945 0.3048)
			(stroke
				(width 0.1)
				(type default)
			)
			(layer "B.Fab")
		)
		(pad "1" smd circle
			(at 0.40005 0)
			(size 0 0)
			(layers "B.Cu" "B.Mask" "B.Paste")
			(net "SMB_P52V_VPDB_SCL")
		)
		(pad "2" smd circle
			(at -0.40005 0)
			(size 0 0)
			(layers "B.Cu" "B.Mask" "B.Paste")
			(net "SMB_BRICK3_SCL")
		)
	)
	(footprint ""
		(layer "B.Cu")
		(at 275.931122 -92.441522 -90)
		(property "Reference" "PD14"
			(at -0.649478 2.399792 270)
			(unlocked yes)
			(layer "B.SilkS")
			(effects
				(font
					(size 0.7874 0.5842)
					(thickness 0.1524)
				)
				(justify left mirror)
			)
		)
		(property "Value" ""
			(at 0 0 90)
			(layer "B.Fab")
			(effects
				(font
					(size 1.27 1.27)
				)
				(justify mirror)
			)
		)
		(duplicate_pad_numbers_are_jumpers no)
		(fp_line
			(start -2.032 0.7112)
			(end 1.651 0.7112)
			(stroke
				(width 0.1524)
				(type default)
			)
			(layer "B.SilkS")
		)
		(fp_line
			(start 1.651 0.7112)
			(end 1.651 -0.7112)
			(stroke
				(width 0.1524)
				(type default)
			)
			(layer "B.SilkS")
		)
		(fp_line
			(start -1.778 0.6858)
			(end -1.778 -0.6858)
			(stroke
				(width 0.1524)
				(type default)
			)
			(layer "B.SilkS")
		)
		(fp_line
			(start 0.299974 0.500126)
			(end -0.199898 0)
			(stroke
				(width 0.1524)
				(type default)
			)
			(layer "B.SilkS")
		)
		(fp_line
			(start -0.199898 0)
			(end 0.299974 -0.500126)
			(stroke
				(width 0.1524)
				(type default)
			)
			(layer "B.SilkS")
		)
		(fp_line
			(start -0.299974 -0.500126)
			(end -0.299974 0.500126)
			(stroke
				(width 0.1524)
				(type default)
			)
			(layer "B.SilkS")
		)
		(fp_line
			(start 0.299974 -0.500126)
			(end 0.299974 0.500126)
			(stroke
				(width 0.1524)
				(type default)
			)
			(layer "B.SilkS")
		)
		(fp_line
			(start -1.905 -0.6858)
			(end -1.905 0.6858)
			(stroke
				(width 0.1524)
				(type default)
			)
			(layer "B.SilkS")
		)
		(fp_line
			(start -1.651 -0.6858)
			(end -1.651 0.6858)
			(stroke
				(width 0.1524)
				(type default)
			)
			(layer "B.SilkS")
		)
		(fp_line
			(start -2.032 -0.7112)
			(end -2.032 0.7112)
			(stroke
				(width 0.1524)
				(type default)
			)
			(layer "B.SilkS")
		)
		(fp_line
			(start 1.651 -0.7112)
			(end -2.032 -0.7112)
			(stroke
				(width 0.1524)
				(type default)
			)
			(layer "B.SilkS")
		)
		(fp_line
			(start -0.899922 0.700024)
			(end 0.899922 0.700024)
			(stroke
				(width 0.1)
				(type default)
			)
			(layer "B.Fab")
		)
		(fp_line
			(start 0.899922 0.700024)
			(end 0.899922 0.175006)
			(stroke
				(width 0.1)
				(type default)
			)
			(layer "B.Fab")
		)
		(fp_line
			(start 0.299974 0.500126)
			(end -0.199898 0)
			(stroke
				(width 0.1)
				(type default)
			)
			(layer "B.Fab")
		)
		(fp_line
			(start -1.35001 0.175006)
			(end -0.899922 0.175006)
			(stroke
				(width 0.1)
				(type default)
			)
			(layer "B.Fab")
		)
		(fp_line
			(start -0.899922 0.175006)
			(end -0.899922 0.700024)
			(stroke
				(width 0.1)
				(type default)
			)
			(layer "B.Fab")
		)
		(fp_line
			(start 0.899922 0.175006)
			(end 1.35001 0.175006)
			(stroke
				(width 0.1)
				(type default)
			)
			(layer "B.Fab")
		)
		(fp_line
			(start 1.35001 0.175006)
			(end 1.35001 -0.225044)
			(stroke
				(width 0.1)
				(type default)
			)
			(layer "B.Fab")
		)
		(fp_line
			(start -0.199898 0)
			(end 0.299974 -0.500126)
			(stroke
				(width 0.1)
				(type default)
			)
			(layer "B.Fab")
		)
		(fp_line
			(start -1.35001 -0.225044)
			(end -1.35001 0.175006)
			(stroke
				(width 0.1)
				(type default)
			)
			(layer "B.Fab")
		)
		(fp_line
			(start -0.899922 -0.225044)
			(end -1.35001 -0.225044)
			(stroke
				(width 0.1)
				(type default)
			)
			(layer "B.Fab")
		)
		(fp_line
			(start 0.899922 -0.225044)
			(end 0.899922 -0.700024)
			(stroke
				(width 0.1)
				(type default)
			)
			(layer "B.Fab")
		)
		(fp_line
			(start 1.35001 -0.225044)
			(end 0.899922 -0.225044)
			(stroke
				(width 0.1)
				(type default)
			)
			(layer "B.Fab")
		)
		(fp_line
			(start -0.299974 -0.500126)
			(end -0.299974 0.500126)
			(stroke
				(width 0.1)
				(type default)
			)
			(layer "B.Fab")
		)
		(fp_line
			(start 0.299974 -0.500126)
			(end 0.299974 0.500126)
			(stroke
				(width 0.1)
				(type default)
			)
			(layer "B.Fab")
		)
		(fp_line
			(start -0.899922 -0.700024)
			(end -0.899922 -0.225044)
			(stroke
				(width 0.1)
				(type default)
			)
			(layer "B.Fab")
		)
		(fp_line
			(start 0.899922 -0.700024)
			(end -0.899922 -0.700024)
			(stroke
				(width 0.1)
				(type default)
			)
			(layer "B.Fab")
		)
		(fp_text user "-"
			(at -1.8288 -0.24765 270)
			(unlocked yes)
			(layer "B.SilkS")
			(effects
				(font
					(size 1.905 1.4224)
					(thickness 0.1524)
				)
				(justify left mirror)
			)
		)
		(fp_text user "+"
			(at 2.271522 -1.532128 270)
			(unlocked yes)
			(layer "B.SilkS")
			(effects
				(font
					(size 1.905 1.4224)
					(thickness 0.1524)
				)
				(justify left mirror)
			)
		)
		(fp_text user "+"
			(at 2.794 -0.19685 270)
			(unlocked yes)
			(layer "B.Fab")
			(effects
				(font
					(size 1.905 1.4224)
					(thickness 0.1524)
				)
				(justify left mirror)
			)
		)
		(fp_text user "-"
			(at -1.8288 -0.24765 270)
			(unlocked yes)
			(layer "B.Fab")
			(effects
				(font
					(size 1.905 1.4224)
					(thickness 0.1524)
				)
				(justify left mirror)
			)
		)
		(pad "1" smd rect
			(at 1.0922 0 270)
			(size 0.8128 0.8636)
			(layers "B.Cu" "B.Mask" "B.Paste")
			(net "P52V_HS1_4287_GATE2_R")
		)
		(pad "2" smd rect
			(at -1.0922 0 90)
			(size 0.8128 0.8636)
			(layers "B.Cu" "B.Mask" "B.Paste")
			(net "P52V_HS1_GATE2_R1")
		)
	)
	(footprint ""
		(layer "B.Cu")
		(at 282.956 -36.449 90)
		(property "Reference" "R153"
			(at 0 0 90)
			(layer "B.SilkS")
			(hide yes)
			(effects
				(font
					(size 1.27 1.27)
				)
				(justify mirror)
			)
		)
		(property "Value" ""
			(at 0 0 90)
			(layer "B.Fab")
			(effects
				(font
					(size 1.27 1.27)
				)
				(justify mirror)
			)
		)
		(duplicate_pad_numbers_are_jumpers no)
		(fp_line
			(start 0.7874 -0.4064)
			(end -0.7874 -0.4064)
			(stroke
				(width 0.1524)
				(type default)
			)
			(layer "B.SilkS")
		)
		(fp_line
			(start -0.7874 -0.4064)
			(end -0.7874 0.4064)
			(stroke
				(width 0.1524)
				(type default)
			)
			(layer "B.SilkS")
		)
		(fp_line
			(start 0.7874 0.4064)
			(end 0.7874 -0.4064)
			(stroke
				(width 0.1524)
				(type default)
			)
			(layer "B.SilkS")
		)
		(fp_line
			(start -0.7874 0.4064)
			(end 0.7874 0.4064)
			(stroke
				(width 0.1524)
				(type default)
			)
			(layer "B.SilkS")
		)
		(fp_line
			(start 0.67945 -0.305054)
			(end 0.12065 -0.305054)
			(stroke
				(width 0.1)
				(type default)
			)
			(layer "B.Fab")
		)
		(fp_line
			(start 0.12065 -0.305054)
			(end 0.12065 -0.2794)
			(stroke
				(width 0.1)
				(type default)
			)
			(layer "B.Fab")
		)
		(fp_line
			(start -0.12065 -0.3048)
			(end -0.67945 -0.3048)
			(stroke
				(width 0.1)
				(type default)
			)
			(layer "B.Fab")
		)
		(fp_line
			(start -0.67945 -0.3048)
			(end -0.67945 0.3048)
			(stroke
				(width 0.1)
				(type default)
			)
			(layer "B.Fab")
		)
		(fp_line
			(start 0.12065 -0.2794)
			(end -0.12065 -0.2794)
			(stroke
				(width 0.1)
				(type default)
			)
			(layer "B.Fab")
		)
		(fp_line
			(start -0.12065 -0.2794)
			(end -0.12065 -0.3048)
			(stroke
				(width 0.1)
				(type default)
			)
			(layer "B.Fab")
		)
		(fp_line
			(start 0.12065 0.2794)
			(end 0.12065 0.3048)
			(stroke
				(width 0.1)
				(type default)
			)
			(layer "B.Fab")
		)
		(fp_line
			(start -0.120396 0.2794)
			(end 0.12065 0.2794)
			(stroke
				(width 0.1)
				(type default)
			)
			(layer "B.Fab")
		)
		(fp_line
			(start 0.67945 0.3048)
			(end 0.67945 -0.305054)
			(stroke
				(width 0.1)
				(type default)
			)
			(layer "B.Fab")
		)
		(fp_line
			(start 0.12065 0.3048)
			(end 0.67945 0.3048)
			(stroke
				(width 0.1)
				(type default)
			)
			(layer "B.Fab")
		)
		(fp_line
			(start -0.120396 0.3048)
			(end -0.120396 0.2794)
			(stroke
				(width 0.1)
				(type default)
			)
			(layer "B.Fab")
		)
		(fp_line
			(start -0.67945 0.3048)
			(end -0.120396 0.3048)
			(stroke
				(width 0.1)
				(type default)
			)
			(layer "B.Fab")
		)
		(pad "1" smd circle
			(at 0.40005 0 270)
			(size 0 0)
			(layers "B.Cu" "B.Mask" "B.Paste")
			(net "P52V_HS1_GPO1")
		)
		(pad "2" smd circle
			(at -0.40005 0 270)
			(size 0 0)
			(layers "B.Cu" "B.Mask" "B.Paste")
			(net "P52V_HS1_FLT")
		)
	)
	(footprint ""
		(layer "B.Cu")
		(at 176.779174 -77.597 180)
		(property "Reference" "C72"
			(at 0 0 0)
			(layer "B.SilkS")
			(hide yes)
			(effects
				(font
					(size 1.27 1.27)
				)
				(justify mirror)
			)
		)
		(property "Value" ""
			(at 0 0 0)
			(layer "B.Fab")
			(effects
				(font
					(size 1.27 1.27)
				)
				(justify mirror)
			)
		)
		(duplicate_pad_numbers_are_jumpers no)
		(fp_line
			(start 0.7874 0.4064)
			(end 0.7874 -0.4064)
			(stroke
				(width 0.1524)
				(type default)
			)
			(layer "B.SilkS")
		)
		(fp_line
			(start 0.7874 -0.4064)
			(end -0.7874 -0.4064)
			(stroke
				(width 0.1524)
				(type default)
			)
			(layer "B.SilkS")
		)
		(fp_line
			(start -0.7874 0.4064)
			(end 0.7874 0.4064)
			(stroke
				(width 0.1524)
				(type default)
			)
			(layer "B.SilkS")
		)
		(fp_line
			(start -0.7874 -0.4064)
			(end -0.7874 0.4064)
			(stroke
				(width 0.1524)
				(type default)
			)
			(layer "B.SilkS")
		)
		(fp_line
			(start 0.67945 0.3048)
			(end 0.67945 -0.305054)
			(stroke
				(width 0.1)
				(type default)
			)
			(layer "B.Fab")
		)
		(fp_line
			(start 0.67945 -0.305054)
			(end 0.12065 -0.305054)
			(stroke
				(width 0.1)
				(type default)
			)
			(layer "B.Fab")
		)
		(fp_line
			(start 0.12065 0.3048)
			(end 0.67945 0.3048)
			(stroke
				(width 0.1)
				(type default)
			)
			(layer "B.Fab")
		)
		(fp_line
			(start 0.12065 0.2794)
			(end 0.12065 0.3048)
			(stroke
				(width 0.1)
				(type default)
			)
			(layer "B.Fab")
		)
		(fp_line
			(start 0.12065 -0.2794)
			(end -0.12065 -0.2794)
			(stroke
				(width 0.1)
				(type default)
			)
			(layer "B.Fab")
		)
		(fp_line
			(start 0.12065 -0.305054)
			(end 0.12065 -0.2794)
			(stroke
				(width 0.1)
				(type default)
			)
			(layer "B.Fab")
		)
		(fp_line
			(start -0.120396 0.3048)
			(end -0.120396 0.2794)
			(stroke
				(width 0.1)
				(type default)
			)
			(layer "B.Fab")
		)
		(fp_line
			(start -0.120396 0.2794)
			(end 0.12065 0.2794)
			(stroke
				(width 0.1)
				(type default)
			)
			(layer "B.Fab")
		)
		(fp_line
			(start -0.12065 -0.2794)
			(end -0.12065 -0.3048)
			(stroke
				(width 0.1)
				(type default)
			)
			(layer "B.Fab")
		)
		(fp_line
			(start -0.12065 -0.3048)
			(end -0.67945 -0.3048)
			(stroke
				(width 0.1)
				(type default)
			)
			(layer "B.Fab")
		)
		(fp_line
			(start -0.67945 0.3048)
			(end -0.120396 0.3048)
			(stroke
				(width 0.1)
				(type default)
			)
			(layer "B.Fab")
		)
		(fp_line
			(start -0.67945 -0.3048)
			(end -0.67945 0.3048)
			(stroke
				(width 0.1)
				(type default)
			)
			(layer "B.Fab")
		)
		(pad "1" smd circle
			(at 0.40005 0)
			(size 0 0)
			(layers "B.Cu" "B.Mask" "B.Paste")
			(net "P12V_BRICK2_ALERT_N")
		)
		(pad "2" smd circle
			(at -0.40005 0)
			(size 0 0)
			(layers "B.Cu" "B.Mask" "B.Paste")
			(net "GND")
		)
	)
	(footprint ""
		(layer "B.Cu")
		(at 189.611 -85.979)
		(property "Reference" "R184"
			(at 0 0 0)
			(layer "B.SilkS")
			(hide yes)
			(effects
				(font
					(size 1.27 1.27)
				)
				(justify mirror)
			)
		)
		(property "Value" ""
			(at 0 0 0)
			(layer "B.Fab")
			(effects
				(font
					(size 1.27 1.27)
				)
				(justify mirror)
			)
		)
		(duplicate_pad_numbers_are_jumpers no)
		(fp_line
			(start -0.7874 -0.4064)
			(end -0.7874 0.4064)
			(stroke
				(width 0.1524)
				(type default)
			)
			(layer "B.SilkS")
		)
		(fp_line
			(start -0.7874 0.4064)
			(end 0.7874 0.4064)
			(stroke
				(width 0.1524)
				(type default)
			)
			(layer "B.SilkS")
		)
		(fp_line
			(start 0.7874 -0.4064)
			(end -0.7874 -0.4064)
			(stroke
				(width 0.1524)
				(type default)
			)
			(layer "B.SilkS")
		)
		(fp_line
			(start 0.7874 0.4064)
			(end 0.7874 -0.4064)
			(stroke
				(width 0.1524)
				(type default)
			)
			(layer "B.SilkS")
		)
		(fp_line
			(start -0.67945 -0.3048)
			(end -0.67945 0.3048)
			(stroke
				(width 0.1)
				(type default)
			)
			(layer "B.Fab")
		)
		(fp_line
			(start -0.67945 0.3048)
			(end -0.120396 0.3048)
			(stroke
				(width 0.1)
				(type default)
			)
			(layer "B.Fab")
		)
		(fp_line
			(start -0.12065 -0.3048)
			(end -0.67945 -0.3048)
			(stroke
				(width 0.1)
				(type default)
			)
			(layer "B.Fab")
		)
		(fp_line
			(start -0.12065 -0.2794)
			(end -0.12065 -0.3048)
			(stroke
				(width 0.1)
				(type default)
			)
			(layer "B.Fab")
		)
		(fp_line
			(start -0.120396 0.2794)
			(end 0.12065 0.2794)
			(stroke
				(width 0.1)
				(type default)
			)
			(layer "B.Fab")
		)
		(fp_line
			(start -0.120396 0.3048)
			(end -0.120396 0.2794)
			(stroke
				(width 0.1)
				(type default)
			)
			(layer "B.Fab")
		)
		(fp_line
			(start 0.12065 -0.305054)
			(end 0.12065 -0.2794)
			(stroke
				(width 0.1)
				(type default)
			)
			(layer "B.Fab")
		)
		(fp_line
			(start 0.12065 -0.2794)
			(end -0.12065 -0.2794)
			(stroke
				(width 0.1)
				(type default)
			)
			(layer "B.Fab")
		)
		(fp_line
			(start 0.12065 0.2794)
			(end 0.12065 0.3048)
			(stroke
				(width 0.1)
				(type default)
			)
			(layer "B.Fab")
		)
		(fp_line
			(start 0.12065 0.3048)
			(end 0.67945 0.3048)
			(stroke
				(width 0.1)
				(type default)
			)
			(layer "B.Fab")
		)
		(fp_line
			(start 0.67945 -0.305054)
			(end 0.12065 -0.305054)
			(stroke
				(width 0.1)
				(type default)
			)
			(layer "B.Fab")
		)
		(fp_line
			(start 0.67945 0.3048)
			(end 0.67945 -0.305054)
			(stroke
				(width 0.1)
				(type default)
			)
			(layer "B.Fab")
		)
		(pad "1" smd circle
			(at 0.40005 0 180)
			(size 0 0)
			(layers "B.Cu" "B.Mask" "B.Paste")
			(net "SMB_P52V_VPDB_SCL_R")
		)
		(pad "2" smd circle
			(at -0.40005 0 180)
			(size 0 0)
			(layers "B.Cu" "B.Mask" "B.Paste")
			(net "SMB_P52V_VPDB_SCL")
		)
	)
	(footprint ""
		(layer "B.Cu")
		(at 238.76 -75.819 90)
		(property "Reference" "R75"
			(at 0 0 90)
			(layer "B.SilkS")
			(hide yes)
			(effects
				(font
					(size 1.27 1.27)
				)
				(justify mirror)
			)
		)
		(property "Value" ""
			(at 0 0 90)
			(layer "B.Fab")
			(effects
				(font
					(size 1.27 1.27)
				)
				(justify mirror)
			)
		)
		(duplicate_pad_numbers_are_jumpers no)
		(fp_line
			(start 0.7874 -0.4064)
			(end -0.7874 -0.4064)
			(stroke
				(width 0.1524)
				(type default)
			)
			(layer "B.SilkS")
		)
		(fp_line
			(start -0.7874 -0.4064)
			(end -0.7874 0.4064)
			(stroke
				(width 0.1524)
				(type default)
			)
			(layer "B.SilkS")
		)
		(fp_line
			(start 0.7874 0.4064)
			(end 0.7874 -0.4064)
			(stroke
				(width 0.1524)
				(type default)
			)
			(layer "B.SilkS")
		)
		(fp_line
			(start -0.7874 0.4064)
			(end 0.7874 0.4064)
			(stroke
				(width 0.1524)
				(type default)
			)
			(layer "B.SilkS")
		)
		(fp_line
			(start 0.67945 -0.305054)
			(end 0.12065 -0.305054)
			(stroke
				(width 0.1)
				(type default)
			)
			(layer "B.Fab")
		)
		(fp_line
			(start 0.12065 -0.305054)
			(end 0.12065 -0.2794)
			(stroke
				(width 0.1)
				(type default)
			)
			(layer "B.Fab")
		)
		(fp_line
			(start -0.12065 -0.3048)
			(end -0.67945 -0.3048)
			(stroke
				(width 0.1)
				(type default)
			)
			(layer "B.Fab")
		)
		(fp_line
			(start -0.67945 -0.3048)
			(end -0.67945 0.3048)
			(stroke
				(width 0.1)
				(type default)
			)
			(layer "B.Fab")
		)
		(fp_line
			(start 0.12065 -0.2794)
			(end -0.12065 -0.2794)
			(stroke
				(width 0.1)
				(type default)
			)
			(layer "B.Fab")
		)
		(fp_line
			(start -0.12065 -0.2794)
			(end -0.12065 -0.3048)
			(stroke
				(width 0.1)
				(type default)
			)
			(layer "B.Fab")
		)
		(fp_line
			(start 0.12065 0.2794)
			(end 0.12065 0.3048)
			(stroke
				(width 0.1)
				(type default)
			)
			(layer "B.Fab")
		)
		(fp_line
			(start -0.120396 0.2794)
			(end 0.12065 0.2794)
			(stroke
				(width 0.1)
				(type default)
			)
			(layer "B.Fab")
		)
		(fp_line
			(start 0.67945 0.3048)
			(end 0.67945 -0.305054)
			(stroke
				(width 0.1)
				(type default)
			)
			(layer "B.Fab")
		)
		(fp_line
			(start 0.12065 0.3048)
			(end 0.67945 0.3048)
			(stroke
				(width 0.1)
				(type default)
			)
			(layer "B.Fab")
		)
		(fp_line
			(start -0.120396 0.3048)
			(end -0.120396 0.2794)
			(stroke
				(width 0.1)
				(type default)
			)
			(layer "B.Fab")
		)
		(fp_line
			(start -0.67945 0.3048)
			(end -0.120396 0.3048)
			(stroke
				(width 0.1)
				(type default)
			)
			(layer "B.Fab")
		)
		(pad "1" smd circle
			(at 0.40005 0 270)
			(size 0 0)
			(layers "B.Cu" "B.Mask" "B.Paste")
			(net "P3V3_AUX")
		)
		(pad "2" smd circle
			(at -0.40005 0 270)
			(size 0 0)
			(layers "B.Cu" "B.Mask" "B.Paste")
			(net "SMB_MB_PDB_R_SDA")
		)
	)
	(footprint ""
		(layer "B.Cu")
		(at 223.52 -78.359 -90)
		(property "Reference" "R40"
			(at 0 0 90)
			(layer "B.SilkS")
			(hide yes)
			(effects
				(font
					(size 1.27 1.27)
				)
				(justify mirror)
			)
		)
		(property "Value" ""
			(at 0 0 90)
			(layer "B.Fab")
			(effects
				(font
					(size 1.27 1.27)
				)
				(justify mirror)
			)
		)
		(duplicate_pad_numbers_are_jumpers no)
		(fp_line
			(start -0.7874 0.4064)
			(end 0.7874 0.4064)
			(stroke
				(width 0.1524)
				(type default)
			)
			(layer "B.SilkS")
		)
		(fp_line
			(start 0.7874 0.4064)
			(end 0.7874 -0.4064)
			(stroke
				(width 0.1524)
				(type default)
			)
			(layer "B.SilkS")
		)
		(fp_line
			(start -0.7874 -0.4064)
			(end -0.7874 0.4064)
			(stroke
				(width 0.1524)
				(type default)
			)
			(layer "B.SilkS")
		)
		(fp_line
			(start 0.7874 -0.4064)
			(end -0.7874 -0.4064)
			(stroke
				(width 0.1524)
				(type default)
			)
			(layer "B.SilkS")
		)
		(fp_line
			(start -0.67945 0.3048)
			(end -0.120396 0.3048)
			(stroke
				(width 0.1)
				(type default)
			)
			(layer "B.Fab")
		)
		(fp_line
			(start -0.120396 0.3048)
			(end -0.120396 0.2794)
			(stroke
				(width 0.1)
				(type default)
			)
			(layer "B.Fab")
		)
		(fp_line
			(start 0.12065 0.3048)
			(end 0.67945 0.3048)
			(stroke
				(width 0.1)
				(type default)
			)
			(layer "B.Fab")
		)
		(fp_line
			(start 0.67945 0.3048)
			(end 0.67945 -0.305054)
			(stroke
				(width 0.1)
				(type default)
			)
			(layer "B.Fab")
		)
		(fp_line
			(start -0.120396 0.2794)
			(end 0.12065 0.2794)
			(stroke
				(width 0.1)
				(type default)
			)
			(layer "B.Fab")
		)
		(fp_line
			(start 0.12065 0.2794)
			(end 0.12065 0.3048)
			(stroke
				(width 0.1)
				(type default)
			)
			(layer "B.Fab")
		)
		(fp_line
			(start -0.12065 -0.2794)
			(end -0.12065 -0.3048)
			(stroke
				(width 0.1)
				(type default)
			)
			(layer "B.Fab")
		)
		(fp_line
			(start 0.12065 -0.2794)
			(end -0.12065 -0.2794)
			(stroke
				(width 0.1)
				(type default)
			)
			(layer "B.Fab")
		)
		(fp_line
			(start -0.67945 -0.3048)
			(end -0.67945 0.3048)
			(stroke
				(width 0.1)
				(type default)
			)
			(layer "B.Fab")
		)
		(fp_line
			(start -0.12065 -0.3048)
			(end -0.67945 -0.3048)
			(stroke
				(width 0.1)
				(type default)
			)
			(layer "B.Fab")
		)
		(fp_line
			(start 0.12065 -0.305054)
			(end 0.12065 -0.2794)
			(stroke
				(width 0.1)
				(type default)
			)
			(layer "B.Fab")
		)
		(fp_line
			(start 0.67945 -0.305054)
			(end 0.12065 -0.305054)
			(stroke
				(width 0.1)
				(type default)
			)
			(layer "B.Fab")
		)
		(pad "1" smd circle
			(at 0.40005 0 90)
			(size 0 0)
			(layers "B.Cu" "B.Mask" "B.Paste")
			(net "P3V3_AUX")
		)
		(pad "2" smd circle
			(at -0.40005 0 90)
			(size 0 0)
			(layers "B.Cu" "B.Mask" "B.Paste")
			(net "FRU_ADDR0")
		)
	)
	(footprint ""
		(layer "B.Cu")
		(at 132.850128 -76.708 -90)
		(property "Reference" "PR52"
			(at 0 0 90)
			(layer "B.SilkS")
			(hide yes)
			(effects
				(font
					(size 1.27 1.27)
				)
				(justify mirror)
			)
		)
		(property "Value" ""
			(at 0 0 90)
			(layer "B.Fab")
			(effects
				(font
					(size 1.27 1.27)
				)
				(justify mirror)
			)
		)
		(duplicate_pad_numbers_are_jumpers no)
		(fp_line
			(start -0.7874 0.4064)
			(end 0.7874 0.4064)
			(stroke
				(width 0.1524)
				(type default)
			)
			(layer "B.SilkS")
		)
		(fp_line
			(start 0.7874 0.4064)
			(end 0.7874 -0.4064)
			(stroke
				(width 0.1524)
				(type default)
			)
			(layer "B.SilkS")
		)
		(fp_line
			(start -0.7874 -0.4064)
			(end -0.7874 0.4064)
			(stroke
				(width 0.1524)
				(type default)
			)
			(layer "B.SilkS")
		)
		(fp_line
			(start 0.7874 -0.4064)
			(end -0.7874 -0.4064)
			(stroke
				(width 0.1524)
				(type default)
			)
			(layer "B.SilkS")
		)
		(fp_line
			(start -0.67945 0.3048)
			(end -0.120396 0.3048)
			(stroke
				(width 0.1)
				(type default)
			)
			(layer "B.Fab")
		)
		(fp_line
			(start -0.120396 0.3048)
			(end -0.120396 0.2794)
			(stroke
				(width 0.1)
				(type default)
			)
			(layer "B.Fab")
		)
		(fp_line
			(start 0.12065 0.3048)
			(end 0.67945 0.3048)
			(stroke
				(width 0.1)
				(type default)
			)
			(layer "B.Fab")
		)
		(fp_line
			(start 0.67945 0.3048)
			(end 0.67945 -0.305054)
			(stroke
				(width 0.1)
				(type default)
			)
			(layer "B.Fab")
		)
		(fp_line
			(start -0.120396 0.2794)
			(end 0.12065 0.2794)
			(stroke
				(width 0.1)
				(type default)
			)
			(layer "B.Fab")
		)
		(fp_line
			(start 0.12065 0.2794)
			(end 0.12065 0.3048)
			(stroke
				(width 0.1)
				(type default)
			)
			(layer "B.Fab")
		)
		(fp_line
			(start -0.12065 -0.2794)
			(end -0.12065 -0.3048)
			(stroke
				(width 0.1)
				(type default)
			)
			(layer "B.Fab")
		)
		(fp_line
			(start 0.12065 -0.2794)
			(end -0.12065 -0.2794)
			(stroke
				(width 0.1)
				(type default)
			)
			(layer "B.Fab")
		)
		(fp_line
			(start -0.67945 -0.3048)
			(end -0.67945 0.3048)
			(stroke
				(width 0.1)
				(type default)
			)
			(layer "B.Fab")
		)
		(fp_line
			(start -0.12065 -0.3048)
			(end -0.67945 -0.3048)
			(stroke
				(width 0.1)
				(type default)
			)
			(layer "B.Fab")
		)
		(fp_line
			(start 0.12065 -0.305054)
			(end 0.12065 -0.2794)
			(stroke
				(width 0.1)
				(type default)
			)
			(layer "B.Fab")
		)
		(fp_line
			(start 0.67945 -0.305054)
			(end 0.12065 -0.305054)
			(stroke
				(width 0.1)
				(type default)
			)
			(layer "B.Fab")
		)
		(pad "1" smd circle
			(at 0.40005 0 90)
			(size 0 0)
			(layers "B.Cu" "B.Mask" "B.Paste")
			(net "P12V_MB0_SENSE-")
		)
		(pad "2" smd circle
			(at -0.40005 0 90)
			(size 0 0)
			(layers "B.Cu" "B.Mask" "B.Paste")
			(net "GND")
		)
	)
	(footprint ""
		(layer "B.Cu")
		(at 205.74 -86.614 180)
		(property "Reference" "R126"
			(at 0 0 0)
			(layer "B.SilkS")
			(hide yes)
			(effects
				(font
					(size 1.27 1.27)
				)
				(justify mirror)
			)
		)
		(property "Value" ""
			(at 0 0 0)
			(layer "B.Fab")
			(effects
				(font
					(size 1.27 1.27)
				)
				(justify mirror)
			)
		)
		(duplicate_pad_numbers_are_jumpers no)
		(fp_line
			(start 0.7874 0.4064)
			(end 0.7874 -0.4064)
			(stroke
				(width 0.1524)
				(type default)
			)
			(layer "B.SilkS")
		)
		(fp_line
			(start 0.7874 -0.4064)
			(end -0.7874 -0.4064)
			(stroke
				(width 0.1524)
				(type default)
			)
			(layer "B.SilkS")
		)
		(fp_line
			(start -0.7874 0.4064)
			(end 0.7874 0.4064)
			(stroke
				(width 0.1524)
				(type default)
			)
			(layer "B.SilkS")
		)
		(fp_line
			(start -0.7874 -0.4064)
			(end -0.7874 0.4064)
			(stroke
				(width 0.1524)
				(type default)
			)
			(layer "B.SilkS")
		)
		(fp_line
			(start 0.67945 0.3048)
			(end 0.67945 -0.305054)
			(stroke
				(width 0.1)
				(type default)
			)
			(layer "B.Fab")
		)
		(fp_line
			(start 0.67945 -0.305054)
			(end 0.12065 -0.305054)
			(stroke
				(width 0.1)
				(type default)
			)
			(layer "B.Fab")
		)
		(fp_line
			(start 0.12065 0.3048)
			(end 0.67945 0.3048)
			(stroke
				(width 0.1)
				(type default)
			)
			(layer "B.Fab")
		)
		(fp_line
			(start 0.12065 0.2794)
			(end 0.12065 0.3048)
			(stroke
				(width 0.1)
				(type default)
			)
			(layer "B.Fab")
		)
		(fp_line
			(start 0.12065 -0.2794)
			(end -0.12065 -0.2794)
			(stroke
				(width 0.1)
				(type default)
			)
			(layer "B.Fab")
		)
		(fp_line
			(start 0.12065 -0.305054)
			(end 0.12065 -0.2794)
			(stroke
				(width 0.1)
				(type default)
			)
			(layer "B.Fab")
		)
		(fp_line
			(start -0.120396 0.3048)
			(end -0.120396 0.2794)
			(stroke
				(width 0.1)
				(type default)
			)
			(layer "B.Fab")
		)
		(fp_line
			(start -0.120396 0.2794)
			(end 0.12065 0.2794)
			(stroke
				(width 0.1)
				(type default)
			)
			(layer "B.Fab")
		)
		(fp_line
			(start -0.12065 -0.2794)
			(end -0.12065 -0.3048)
			(stroke
				(width 0.1)
				(type default)
			)
			(layer "B.Fab")
		)
		(fp_line
			(start -0.12065 -0.3048)
			(end -0.67945 -0.3048)
			(stroke
				(width 0.1)
				(type default)
			)
			(layer "B.Fab")
		)
		(fp_line
			(start -0.67945 0.3048)
			(end -0.120396 0.3048)
			(stroke
				(width 0.1)
				(type default)
			)
			(layer "B.Fab")
		)
		(fp_line
			(start -0.67945 -0.3048)
			(end -0.67945 0.3048)
			(stroke
				(width 0.1)
				(type default)
			)
			(layer "B.Fab")
		)
		(pad "1" smd circle
			(at 0.40005 0)
			(size 0 0)
			(layers "B.Cu" "B.Mask" "B.Paste")
			(net "SMB_VPDB_MISC_SCL")
		)
		(pad "2" smd circle
			(at -0.40005 0)
			(size 0 0)
			(layers "B.Cu" "B.Mask" "B.Paste")
			(net "P3V3_AUX")
		)
	)
	(footprint ""
		(layer "B.Cu")
		(at 96.52 -76.327 180)
		(property "Reference" "R173"
			(at 0 0 0)
			(layer "B.SilkS")
			(hide yes)
			(effects
				(font
					(size 1.27 1.27)
				)
				(justify mirror)
			)
		)
		(property "Value" ""
			(at 0 0 0)
			(layer "B.Fab")
			(effects
				(font
					(size 1.27 1.27)
				)
				(justify mirror)
			)
		)
		(duplicate_pad_numbers_are_jumpers no)
		(fp_line
			(start 0.7874 0.4064)
			(end 0.7874 -0.4064)
			(stroke
				(width 0.1524)
				(type default)
			)
			(layer "B.SilkS")
		)
		(fp_line
			(start 0.7874 -0.4064)
			(end -0.7874 -0.4064)
			(stroke
				(width 0.1524)
				(type default)
			)
			(layer "B.SilkS")
		)
		(fp_line
			(start -0.7874 0.4064)
			(end 0.7874 0.4064)
			(stroke
				(width 0.1524)
				(type default)
			)
			(layer "B.SilkS")
		)
		(fp_line
			(start -0.7874 -0.4064)
			(end -0.7874 0.4064)
			(stroke
				(width 0.1524)
				(type default)
			)
			(layer "B.SilkS")
		)
		(fp_line
			(start 0.67945 0.3048)
			(end 0.67945 -0.305054)
			(stroke
				(width 0.1)
				(type default)
			)
			(layer "B.Fab")
		)
		(fp_line
			(start 0.67945 -0.305054)
			(end 0.12065 -0.305054)
			(stroke
				(width 0.1)
				(type default)
			)
			(layer "B.Fab")
		)
		(fp_line
			(start 0.12065 0.3048)
			(end 0.67945 0.3048)
			(stroke
				(width 0.1)
				(type default)
			)
			(layer "B.Fab")
		)
		(fp_line
			(start 0.12065 0.2794)
			(end 0.12065 0.3048)
			(stroke
				(width 0.1)
				(type default)
			)
			(layer "B.Fab")
		)
		(fp_line
			(start 0.12065 -0.2794)
			(end -0.12065 -0.2794)
			(stroke
				(width 0.1)
				(type default)
			)
			(layer "B.Fab")
		)
		(fp_line
			(start 0.12065 -0.305054)
			(end 0.12065 -0.2794)
			(stroke
				(width 0.1)
				(type default)
			)
			(layer "B.Fab")
		)
		(fp_line
			(start -0.120396 0.3048)
			(end -0.120396 0.2794)
			(stroke
				(width 0.1)
				(type default)
			)
			(layer "B.Fab")
		)
		(fp_line
			(start -0.120396 0.2794)
			(end 0.12065 0.2794)
			(stroke
				(width 0.1)
				(type default)
			)
			(layer "B.Fab")
		)
		(fp_line
			(start -0.12065 -0.2794)
			(end -0.12065 -0.3048)
			(stroke
				(width 0.1)
				(type default)
			)
			(layer "B.Fab")
		)
		(fp_line
			(start -0.12065 -0.3048)
			(end -0.67945 -0.3048)
			(stroke
				(width 0.1)
				(type default)
			)
			(layer "B.Fab")
		)
		(fp_line
			(start -0.67945 0.3048)
			(end -0.120396 0.3048)
			(stroke
				(width 0.1)
				(type default)
			)
			(layer "B.Fab")
		)
		(fp_line
			(start -0.67945 -0.3048)
			(end -0.67945 0.3048)
			(stroke
				(width 0.1)
				(type default)
			)
			(layer "B.Fab")
		)
		(pad "1" smd circle
			(at 0.40005 0)
			(size 0 0)
			(layers "B.Cu" "B.Mask" "B.Paste")
			(net "SMB_P52V_VPDB_SCL")
		)
		(pad "2" smd circle
			(at -0.40005 0)
			(size 0 0)
			(layers "B.Cu" "B.Mask" "B.Paste")
			(net "SMB_BRICK1_SCL")
		)
	)
	(footprint ""
		(layer "B.Cu")
		(at 230.632 -82.296 90)
		(property "Reference" "R140"
			(at 0 0 90)
			(layer "B.SilkS")
			(hide yes)
			(effects
				(font
					(size 1.27 1.27)
				)
				(justify mirror)
			)
		)
		(property "Value" ""
			(at 0 0 90)
			(layer "B.Fab")
			(effects
				(font
					(size 1.27 1.27)
				)
				(justify mirror)
			)
		)
		(duplicate_pad_numbers_are_jumpers no)
		(fp_line
			(start 0.7874 -0.4064)
			(end -0.7874 -0.4064)
			(stroke
				(width 0.1524)
				(type default)
			)
			(layer "B.SilkS")
		)
		(fp_line
			(start -0.7874 -0.4064)
			(end -0.7874 0.4064)
			(stroke
				(width 0.1524)
				(type default)
			)
			(layer "B.SilkS")
		)
		(fp_line
			(start 0.7874 0.4064)
			(end 0.7874 -0.4064)
			(stroke
				(width 0.1524)
				(type default)
			)
			(layer "B.SilkS")
		)
		(fp_line
			(start -0.7874 0.4064)
			(end 0.7874 0.4064)
			(stroke
				(width 0.1524)
				(type default)
			)
			(layer "B.SilkS")
		)
		(fp_line
			(start 0.67945 -0.305054)
			(end 0.12065 -0.305054)
			(stroke
				(width 0.1)
				(type default)
			)
			(layer "B.Fab")
		)
		(fp_line
			(start 0.12065 -0.305054)
			(end 0.12065 -0.2794)
			(stroke
				(width 0.1)
				(type default)
			)
			(layer "B.Fab")
		)
		(fp_line
			(start -0.12065 -0.3048)
			(end -0.67945 -0.3048)
			(stroke
				(width 0.1)
				(type default)
			)
			(layer "B.Fab")
		)
		(fp_line
			(start -0.67945 -0.3048)
			(end -0.67945 0.3048)
			(stroke
				(width 0.1)
				(type default)
			)
			(layer "B.Fab")
		)
		(fp_line
			(start 0.12065 -0.2794)
			(end -0.12065 -0.2794)
			(stroke
				(width 0.1)
				(type default)
			)
			(layer "B.Fab")
		)
		(fp_line
			(start -0.12065 -0.2794)
			(end -0.12065 -0.3048)
			(stroke
				(width 0.1)
				(type default)
			)
			(layer "B.Fab")
		)
		(fp_line
			(start 0.12065 0.2794)
			(end 0.12065 0.3048)
			(stroke
				(width 0.1)
				(type default)
			)
			(layer "B.Fab")
		)
		(fp_line
			(start -0.120396 0.2794)
			(end 0.12065 0.2794)
			(stroke
				(width 0.1)
				(type default)
			)
			(layer "B.Fab")
		)
		(fp_line
			(start 0.67945 0.3048)
			(end 0.67945 -0.305054)
			(stroke
				(width 0.1)
				(type default)
			)
			(layer "B.Fab")
		)
		(fp_line
			(start 0.12065 0.3048)
			(end 0.67945 0.3048)
			(stroke
				(width 0.1)
				(type default)
			)
			(layer "B.Fab")
		)
		(fp_line
			(start -0.120396 0.3048)
			(end -0.120396 0.2794)
			(stroke
				(width 0.1)
				(type default)
			)
			(layer "B.Fab")
		)
		(fp_line
			(start -0.67945 0.3048)
			(end -0.120396 0.3048)
			(stroke
				(width 0.1)
				(type default)
			)
			(layer "B.Fab")
		)
		(pad "1" smd circle
			(at 0.40005 0 270)
			(size 0 0)
			(layers "B.Cu" "B.Mask" "B.Paste")
			(net "GND")
		)
		(pad "2" smd circle
			(at -0.40005 0 270)
			(size 0 0)
			(layers "B.Cu" "B.Mask" "B.Paste")
			(net "PWRGD_P3V3_AUX_MB_BUF_R")
		)
	)
	(footprint ""
		(layer "B.Cu")
		(at 205.74 -91.948 180)
		(property "Reference" "R97"
			(at 0 0 0)
			(layer "B.SilkS")
			(hide yes)
			(effects
				(font
					(size 1.27 1.27)
				)
				(justify mirror)
			)
		)
		(property "Value" ""
			(at 0 0 0)
			(layer "B.Fab")
			(effects
				(font
					(size 1.27 1.27)
				)
				(justify mirror)
			)
		)
		(duplicate_pad_numbers_are_jumpers no)
		(fp_line
			(start 0.7874 0.4064)
			(end 0.7874 -0.4064)
			(stroke
				(width 0.1524)
				(type default)
			)
			(layer "B.SilkS")
		)
		(fp_line
			(start 0.7874 -0.4064)
			(end -0.7874 -0.4064)
			(stroke
				(width 0.1524)
				(type default)
			)
			(layer "B.SilkS")
		)
		(fp_line
			(start -0.7874 0.4064)
			(end 0.7874 0.4064)
			(stroke
				(width 0.1524)
				(type default)
			)
			(layer "B.SilkS")
		)
		(fp_line
			(start -0.7874 -0.4064)
			(end -0.7874 0.4064)
			(stroke
				(width 0.1524)
				(type default)
			)
			(layer "B.SilkS")
		)
		(fp_line
			(start 0.67945 0.3048)
			(end 0.67945 -0.305054)
			(stroke
				(width 0.1)
				(type default)
			)
			(layer "B.Fab")
		)
		(fp_line
			(start 0.67945 -0.305054)
			(end 0.12065 -0.305054)
			(stroke
				(width 0.1)
				(type default)
			)
			(layer "B.Fab")
		)
		(fp_line
			(start 0.12065 0.3048)
			(end 0.67945 0.3048)
			(stroke
				(width 0.1)
				(type default)
			)
			(layer "B.Fab")
		)
		(fp_line
			(start 0.12065 0.2794)
			(end 0.12065 0.3048)
			(stroke
				(width 0.1)
				(type default)
			)
			(layer "B.Fab")
		)
		(fp_line
			(start 0.12065 -0.2794)
			(end -0.12065 -0.2794)
			(stroke
				(width 0.1)
				(type default)
			)
			(layer "B.Fab")
		)
		(fp_line
			(start 0.12065 -0.305054)
			(end 0.12065 -0.2794)
			(stroke
				(width 0.1)
				(type default)
			)
			(layer "B.Fab")
		)
		(fp_line
			(start -0.120396 0.3048)
			(end -0.120396 0.2794)
			(stroke
				(width 0.1)
				(type default)
			)
			(layer "B.Fab")
		)
		(fp_line
			(start -0.120396 0.2794)
			(end 0.12065 0.2794)
			(stroke
				(width 0.1)
				(type default)
			)
			(layer "B.Fab")
		)
		(fp_line
			(start -0.12065 -0.2794)
			(end -0.12065 -0.3048)
			(stroke
				(width 0.1)
				(type default)
			)
			(layer "B.Fab")
		)
		(fp_line
			(start -0.12065 -0.3048)
			(end -0.67945 -0.3048)
			(stroke
				(width 0.1)
				(type default)
			)
			(layer "B.Fab")
		)
		(fp_line
			(start -0.67945 0.3048)
			(end -0.120396 0.3048)
			(stroke
				(width 0.1)
				(type default)
			)
			(layer "B.Fab")
		)
		(fp_line
			(start -0.67945 -0.3048)
			(end -0.67945 0.3048)
			(stroke
				(width 0.1)
				(type default)
			)
			(layer "B.Fab")
		)
		(pad "1" smd circle
			(at 0.40005 0)
			(size 0 0)
			(layers "B.Cu" "B.Mask" "B.Paste")
			(net "PCA9543_MISC_A0")
		)
		(pad "2" smd circle
			(at -0.40005 0)
			(size 0 0)
			(layers "B.Cu" "B.Mask" "B.Paste")
			(net "GND")
		)
	)
	(footprint ""
		(layer "B.Cu")
		(at 275.931122 -104.506522 -90)
		(property "Reference" "PD15"
			(at -0.522478 1.510792 270)
			(unlocked yes)
			(layer "B.SilkS")
			(effects
				(font
					(size 0.7874 0.5842)
					(thickness 0.1524)
				)
				(justify left mirror)
			)
		)
		(property "Value" ""
			(at 0 0 90)
			(layer "B.Fab")
			(effects
				(font
					(size 1.27 1.27)
				)
				(justify mirror)
			)
		)
		(duplicate_pad_numbers_are_jumpers no)
		(fp_line
			(start -2.032 0.7112)
			(end 1.651 0.7112)
			(stroke
				(width 0.1524)
				(type default)
			)
			(layer "B.SilkS")
		)
		(fp_line
			(start 1.651 0.7112)
			(end 1.651 -0.7112)
			(stroke
				(width 0.1524)
				(type default)
			)
			(layer "B.SilkS")
		)
		(fp_line
			(start -1.778 0.6858)
			(end -1.778 -0.6858)
			(stroke
				(width 0.1524)
				(type default)
			)
			(layer "B.SilkS")
		)
		(fp_line
			(start 0.299974 0.500126)
			(end -0.199898 0)
			(stroke
				(width 0.1524)
				(type default)
			)
			(layer "B.SilkS")
		)
		(fp_line
			(start -0.199898 0)
			(end 0.299974 -0.500126)
			(stroke
				(width 0.1524)
				(type default)
			)
			(layer "B.SilkS")
		)
		(fp_line
			(start -0.299974 -0.500126)
			(end -0.299974 0.500126)
			(stroke
				(width 0.1524)
				(type default)
			)
			(layer "B.SilkS")
		)
		(fp_line
			(start 0.299974 -0.500126)
			(end 0.299974 0.500126)
			(stroke
				(width 0.1524)
				(type default)
			)
			(layer "B.SilkS")
		)
		(fp_line
			(start -1.905 -0.6858)
			(end -1.905 0.6858)
			(stroke
				(width 0.1524)
				(type default)
			)
			(layer "B.SilkS")
		)
		(fp_line
			(start -1.651 -0.6858)
			(end -1.651 0.6858)
			(stroke
				(width 0.1524)
				(type default)
			)
			(layer "B.SilkS")
		)
		(fp_line
			(start -2.032 -0.7112)
			(end -2.032 0.7112)
			(stroke
				(width 0.1524)
				(type default)
			)
			(layer "B.SilkS")
		)
		(fp_line
			(start 1.651 -0.7112)
			(end -2.032 -0.7112)
			(stroke
				(width 0.1524)
				(type default)
			)
			(layer "B.SilkS")
		)
		(fp_line
			(start -0.899922 0.700024)
			(end 0.899922 0.700024)
			(stroke
				(width 0.1)
				(type default)
			)
			(layer "B.Fab")
		)
		(fp_line
			(start 0.899922 0.700024)
			(end 0.899922 0.175006)
			(stroke
				(width 0.1)
				(type default)
			)
			(layer "B.Fab")
		)
		(fp_line
			(start 0.299974 0.500126)
			(end -0.199898 0)
			(stroke
				(width 0.1)
				(type default)
			)
			(layer "B.Fab")
		)
		(fp_line
			(start -1.35001 0.175006)
			(end -0.899922 0.175006)
			(stroke
				(width 0.1)
				(type default)
			)
			(layer "B.Fab")
		)
		(fp_line
			(start -0.899922 0.175006)
			(end -0.899922 0.700024)
			(stroke
				(width 0.1)
				(type default)
			)
			(layer "B.Fab")
		)
		(fp_line
			(start 0.899922 0.175006)
			(end 1.35001 0.175006)
			(stroke
				(width 0.1)
				(type default)
			)
			(layer "B.Fab")
		)
		(fp_line
			(start 1.35001 0.175006)
			(end 1.35001 -0.225044)
			(stroke
				(width 0.1)
				(type default)
			)
			(layer "B.Fab")
		)
		(fp_line
			(start -0.199898 0)
			(end 0.299974 -0.500126)
			(stroke
				(width 0.1)
				(type default)
			)
			(layer "B.Fab")
		)
		(fp_line
			(start -1.35001 -0.225044)
			(end -1.35001 0.175006)
			(stroke
				(width 0.1)
				(type default)
			)
			(layer "B.Fab")
		)
		(fp_line
			(start -0.899922 -0.225044)
			(end -1.35001 -0.225044)
			(stroke
				(width 0.1)
				(type default)
			)
			(layer "B.Fab")
		)
		(fp_line
			(start 0.899922 -0.225044)
			(end 0.899922 -0.700024)
			(stroke
				(width 0.1)
				(type default)
			)
			(layer "B.Fab")
		)
		(fp_line
			(start 1.35001 -0.225044)
			(end 0.899922 -0.225044)
			(stroke
				(width 0.1)
				(type default)
			)
			(layer "B.Fab")
		)
		(fp_line
			(start -0.299974 -0.500126)
			(end -0.299974 0.500126)
			(stroke
				(width 0.1)
				(type default)
			)
			(layer "B.Fab")
		)
		(fp_line
			(start 0.299974 -0.500126)
			(end 0.299974 0.500126)
			(stroke
				(width 0.1)
				(type default)
			)
			(layer "B.Fab")
		)
		(fp_line
			(start -0.899922 -0.700024)
			(end -0.899922 -0.225044)
			(stroke
				(width 0.1)
				(type default)
			)
			(layer "B.Fab")
		)
		(fp_line
			(start 0.899922 -0.700024)
			(end -0.899922 -0.700024)
			(stroke
				(width 0.1)
				(type default)
			)
			(layer "B.Fab")
		)
		(fp_text user "-"
			(at -1.8288 -0.24765 270)
			(unlocked yes)
			(layer "B.SilkS")
			(effects
				(font
					(size 1.905 1.4224)
					(thickness 0.1524)
				)
				(justify left mirror)
			)
		)
		(fp_text user "+"
			(at 2.296922 -1.570228 270)
			(unlocked yes)
			(layer "B.SilkS")
			(effects
				(font
					(size 1.905 1.4224)
					(thickness 0.1524)
				)
				(justify left mirror)
			)
		)
		(fp_text user "+"
			(at 2.794 -0.19685 270)
			(unlocked yes)
			(layer "B.Fab")
			(effects
				(font
					(size 1.905 1.4224)
					(thickness 0.1524)
				)
				(justify left mirror)
			)
		)
		(fp_text user "-"
			(at -1.8288 -0.24765 270)
			(unlocked yes)
			(layer "B.Fab")
			(effects
				(font
					(size 1.905 1.4224)
					(thickness 0.1524)
				)
				(justify left mirror)
			)
		)
		(pad "1" smd rect
			(at 1.0922 0 270)
			(size 0.8128 0.8636)
			(layers "B.Cu" "B.Mask" "B.Paste")
			(net "P52V_HS1_4287_GATE_R")
		)
		(pad "2" smd rect
			(at -1.0922 0 90)
			(size 0.8128 0.8636)
			(layers "B.Cu" "B.Mask" "B.Paste")
			(net "P52V_HS1_GATE_R1")
		)
	)
	(footprint ""
		(layer "B.Cu")
		(at 140.850112 -76.708 90)
		(property "Reference" "PR58"
			(at 0 0 90)
			(layer "B.SilkS")
			(hide yes)
			(effects
				(font
					(size 1.27 1.27)
				)
				(justify mirror)
			)
		)
		(property "Value" ""
			(at 0 0 90)
			(layer "B.Fab")
			(effects
				(font
					(size 1.27 1.27)
				)
				(justify mirror)
			)
		)
		(duplicate_pad_numbers_are_jumpers no)
		(fp_line
			(start 0.7874 -0.4064)
			(end -0.7874 -0.4064)
			(stroke
				(width 0.1524)
				(type default)
			)
			(layer "B.SilkS")
		)
		(fp_line
			(start -0.7874 -0.4064)
			(end -0.7874 0.4064)
			(stroke
				(width 0.1524)
				(type default)
			)
			(layer "B.SilkS")
		)
		(fp_line
			(start 0.7874 0.4064)
			(end 0.7874 -0.4064)
			(stroke
				(width 0.1524)
				(type default)
			)
			(layer "B.SilkS")
		)
		(fp_line
			(start -0.7874 0.4064)
			(end 0.7874 0.4064)
			(stroke
				(width 0.1524)
				(type default)
			)
			(layer "B.SilkS")
		)
		(fp_line
			(start 0.67945 -0.305054)
			(end 0.12065 -0.305054)
			(stroke
				(width 0.1)
				(type default)
			)
			(layer "B.Fab")
		)
		(fp_line
			(start 0.12065 -0.305054)
			(end 0.12065 -0.2794)
			(stroke
				(width 0.1)
				(type default)
			)
			(layer "B.Fab")
		)
		(fp_line
			(start -0.12065 -0.3048)
			(end -0.67945 -0.3048)
			(stroke
				(width 0.1)
				(type default)
			)
			(layer "B.Fab")
		)
		(fp_line
			(start -0.67945 -0.3048)
			(end -0.67945 0.3048)
			(stroke
				(width 0.1)
				(type default)
			)
			(layer "B.Fab")
		)
		(fp_line
			(start 0.12065 -0.2794)
			(end -0.12065 -0.2794)
			(stroke
				(width 0.1)
				(type default)
			)
			(layer "B.Fab")
		)
		(fp_line
			(start -0.12065 -0.2794)
			(end -0.12065 -0.3048)
			(stroke
				(width 0.1)
				(type default)
			)
			(layer "B.Fab")
		)
		(fp_line
			(start 0.12065 0.2794)
			(end 0.12065 0.3048)
			(stroke
				(width 0.1)
				(type default)
			)
			(layer "B.Fab")
		)
		(fp_line
			(start -0.120396 0.2794)
			(end 0.12065 0.2794)
			(stroke
				(width 0.1)
				(type default)
			)
			(layer "B.Fab")
		)
		(fp_line
			(start 0.67945 0.3048)
			(end 0.67945 -0.305054)
			(stroke
				(width 0.1)
				(type default)
			)
			(layer "B.Fab")
		)
		(fp_line
			(start 0.12065 0.3048)
			(end 0.67945 0.3048)
			(stroke
				(width 0.1)
				(type default)
			)
			(layer "B.Fab")
		)
		(fp_line
			(start -0.120396 0.3048)
			(end -0.120396 0.2794)
			(stroke
				(width 0.1)
				(type default)
			)
			(layer "B.Fab")
		)
		(fp_line
			(start -0.67945 0.3048)
			(end -0.120396 0.3048)
			(stroke
				(width 0.1)
				(type default)
			)
			(layer "B.Fab")
		)
		(pad "1" smd circle
			(at 0.40005 0 270)
			(size 0 0)
			(layers "B.Cu" "B.Mask" "B.Paste")
			(net "GND")
		)
		(pad "2" smd circle
			(at -0.40005 0 270)
			(size 0 0)
			(layers "B.Cu" "B.Mask" "B.Paste")
			(net "BRICK0_PMBADD")
		)
	)
	(footprint ""
		(layer "B.Cu")
		(at 273.685 -26.543 90)
		(property "Reference" "U37"
			(at -2.32537 1.7399 0)
			(unlocked yes)
			(layer "B.SilkS")
			(effects
				(font
					(size 0.7874 0.5842)
					(thickness 0.1524)
				)
				(justify left mirror)
			)
		)
		(property "Value" ""
			(at 0 0 90)
			(layer "B.Fab")
			(effects
				(font
					(size 1.27 1.27)
				)
				(justify mirror)
			)
		)
		(duplicate_pad_numbers_are_jumpers no)
		(fp_line
			(start 1.603248 -1.500124)
			(end -1.603248 -1.500124)
			(stroke
				(width 0.1524)
				(type default)
			)
			(layer "B.SilkS")
		)
		(fp_line
			(start -1.603248 -1.500124)
			(end -1.603248 1.500124)
			(stroke
				(width 0.1524)
				(type default)
			)
			(layer "B.SilkS")
		)
		(fp_line
			(start 1.603248 1.500124)
			(end 1.603248 -1.500124)
			(stroke
				(width 0.1524)
				(type default)
			)
			(layer "B.SilkS")
		)
		(fp_line
			(start -1.603248 1.500124)
			(end 1.603248 1.500124)
			(stroke
				(width 0.1524)
				(type default)
			)
			(layer "B.SilkS")
		)
		(fp_line
			(start 0.700024 -1.500124)
			(end 0.700024 -1.169924)
			(stroke
				(width 0.1)
				(type default)
			)
			(layer "B.Fab")
		)
		(fp_line
			(start -0.700024 -1.500124)
			(end 0.700024 -1.500124)
			(stroke
				(width 0.1)
				(type default)
			)
			(layer "B.Fab")
		)
		(fp_line
			(start 1.249934 -1.169924)
			(end 1.249934 -0.729996)
			(stroke
				(width 0.1)
				(type default)
			)
			(layer "B.Fab")
		)
		(fp_line
			(start 0.700024 -1.169924)
			(end 1.249934 -1.169924)
			(stroke
				(width 0.1)
				(type default)
			)
			(layer "B.Fab")
		)
		(fp_line
			(start 1.249934 -0.729996)
			(end 0.6985 -0.729996)
			(stroke
				(width 0.1)
				(type default)
			)
			(layer "B.Fab")
		)
		(fp_line
			(start 0.6985 -0.729996)
			(end 0.6985 0.729996)
			(stroke
				(width 0.1)
				(type default)
			)
			(layer "B.Fab")
		)
		(fp_line
			(start -0.700024 -0.219964)
			(end -0.700024 -1.500124)
			(stroke
				(width 0.1)
				(type default)
			)
			(layer "B.Fab")
		)
		(fp_line
			(start -1.249934 -0.219964)
			(end -0.700024 -0.219964)
			(stroke
				(width 0.1)
				(type default)
			)
			(layer "B.Fab")
		)
		(fp_line
			(start -0.700024 0.219964)
			(end -1.249934 0.219964)
			(stroke
				(width 0.1)
				(type default)
			)
			(layer "B.Fab")
		)
		(fp_line
			(start -1.249934 0.219964)
			(end -1.249934 -0.219964)
			(stroke
				(width 0.1)
				(type default)
			)
			(layer "B.Fab")
		)
		(fp_line
			(start 1.249934 0.729996)
			(end 1.249934 1.169924)
			(stroke
				(width 0.1)
				(type default)
			)
			(layer "B.Fab")
		)
		(fp_line
			(start 0.6985 0.729996)
			(end 1.249934 0.729996)
			(stroke
				(width 0.1)
				(type default)
			)
			(layer "B.Fab")
		)
		(fp_line
			(start 1.249934 1.169924)
			(end 0.700024 1.169924)
			(stroke
				(width 0.1)
				(type default)
			)
			(layer "B.Fab")
		)
		(fp_line
			(start 0.700024 1.169924)
			(end 0.700024 1.500124)
			(stroke
				(width 0.1)
				(type default)
			)
			(layer "B.Fab")
		)
		(fp_line
			(start 0.700024 1.500124)
			(end -0.700024 1.500124)
			(stroke
				(width 0.1)
				(type default)
			)
			(layer "B.Fab")
		)
		(fp_line
			(start -0.700024 1.500124)
			(end -0.700024 0.219964)
			(stroke
				(width 0.1)
				(type default)
			)
			(layer "B.Fab")
		)
		(fp_rect
			(start 0.700024 1.500124)
			(end -0.700024 -1.500124)
			(stroke
				(width 0)
				(type default)
			)
			(fill no)
			(layer "B.Fab")
		)
		(pad "D" smd rect
			(at -0.999998 0)
			(size 0.8128 0.9144)
			(layers "B.Cu" "B.Mask" "B.Paste")
			(net "P52V_HS1_EN")
		)
		(pad "G" smd rect
			(at 0.999998 -0.94996)
			(size 0.8128 0.9144)
			(layers "B.Cu" "B.Mask" "B.Paste")
			(net "FM_AC_PWR_CYCLE_R_BUF")
		)
		(pad "S" smd rect
			(at 0.999998 0.94996)
			(size 0.8128 0.9144)
			(layers "B.Cu" "B.Mask" "B.Paste")
			(net "GND")
		)
	)
	(footprint ""
		(layer "B.Cu")
		(at 222.25 -75.057 -90)
		(property "Reference" "R44"
			(at 0 0 90)
			(layer "B.SilkS")
			(hide yes)
			(effects
				(font
					(size 1.27 1.27)
				)
				(justify mirror)
			)
		)
		(property "Value" ""
			(at 0 0 90)
			(layer "B.Fab")
			(effects
				(font
					(size 1.27 1.27)
				)
				(justify mirror)
			)
		)
		(duplicate_pad_numbers_are_jumpers no)
		(fp_line
			(start -0.7874 0.4064)
			(end 0.7874 0.4064)
			(stroke
				(width 0.1524)
				(type default)
			)
			(layer "B.SilkS")
		)
		(fp_line
			(start 0.7874 0.4064)
			(end 0.7874 -0.4064)
			(stroke
				(width 0.1524)
				(type default)
			)
			(layer "B.SilkS")
		)
		(fp_line
			(start -0.7874 -0.4064)
			(end -0.7874 0.4064)
			(stroke
				(width 0.1524)
				(type default)
			)
			(layer "B.SilkS")
		)
		(fp_line
			(start 0.7874 -0.4064)
			(end -0.7874 -0.4064)
			(stroke
				(width 0.1524)
				(type default)
			)
			(layer "B.SilkS")
		)
		(fp_line
			(start -0.67945 0.3048)
			(end -0.120396 0.3048)
			(stroke
				(width 0.1)
				(type default)
			)
			(layer "B.Fab")
		)
		(fp_line
			(start -0.120396 0.3048)
			(end -0.120396 0.2794)
			(stroke
				(width 0.1)
				(type default)
			)
			(layer "B.Fab")
		)
		(fp_line
			(start 0.12065 0.3048)
			(end 0.67945 0.3048)
			(stroke
				(width 0.1)
				(type default)
			)
			(layer "B.Fab")
		)
		(fp_line
			(start 0.67945 0.3048)
			(end 0.67945 -0.305054)
			(stroke
				(width 0.1)
				(type default)
			)
			(layer "B.Fab")
		)
		(fp_line
			(start -0.120396 0.2794)
			(end 0.12065 0.2794)
			(stroke
				(width 0.1)
				(type default)
			)
			(layer "B.Fab")
		)
		(fp_line
			(start 0.12065 0.2794)
			(end 0.12065 0.3048)
			(stroke
				(width 0.1)
				(type default)
			)
			(layer "B.Fab")
		)
		(fp_line
			(start -0.12065 -0.2794)
			(end -0.12065 -0.3048)
			(stroke
				(width 0.1)
				(type default)
			)
			(layer "B.Fab")
		)
		(fp_line
			(start 0.12065 -0.2794)
			(end -0.12065 -0.2794)
			(stroke
				(width 0.1)
				(type default)
			)
			(layer "B.Fab")
		)
		(fp_line
			(start -0.67945 -0.3048)
			(end -0.67945 0.3048)
			(stroke
				(width 0.1)
				(type default)
			)
			(layer "B.Fab")
		)
		(fp_line
			(start -0.12065 -0.3048)
			(end -0.67945 -0.3048)
			(stroke
				(width 0.1)
				(type default)
			)
			(layer "B.Fab")
		)
		(fp_line
			(start 0.12065 -0.305054)
			(end 0.12065 -0.2794)
			(stroke
				(width 0.1)
				(type default)
			)
			(layer "B.Fab")
		)
		(fp_line
			(start 0.67945 -0.305054)
			(end 0.12065 -0.305054)
			(stroke
				(width 0.1)
				(type default)
			)
			(layer "B.Fab")
		)
		(pad "1" smd circle
			(at 0.40005 0 90)
			(size 0 0)
			(layers "B.Cu" "B.Mask" "B.Paste")
			(net "GND")
		)
		(pad "2" smd circle
			(at -0.40005 0 90)
			(size 0 0)
			(layers "B.Cu" "B.Mask" "B.Paste")
			(net "FRU_ADDR1")
		)
	)
	(footprint ""
		(layer "B.Cu")
		(at 96.52 -77.47 180)
		(property "Reference" "C59"
			(at 0 0 0)
			(layer "B.SilkS")
			(hide yes)
			(effects
				(font
					(size 1.27 1.27)
				)
				(justify mirror)
			)
		)
		(property "Value" ""
			(at 0 0 0)
			(layer "B.Fab")
			(effects
				(font
					(size 1.27 1.27)
				)
				(justify mirror)
			)
		)
		(duplicate_pad_numbers_are_jumpers no)
		(fp_line
			(start 0.7874 0.4064)
			(end 0.7874 -0.4064)
			(stroke
				(width 0.1524)
				(type default)
			)
			(layer "B.SilkS")
		)
		(fp_line
			(start 0.7874 -0.4064)
			(end -0.7874 -0.4064)
			(stroke
				(width 0.1524)
				(type default)
			)
			(layer "B.SilkS")
		)
		(fp_line
			(start -0.7874 0.4064)
			(end 0.7874 0.4064)
			(stroke
				(width 0.1524)
				(type default)
			)
			(layer "B.SilkS")
		)
		(fp_line
			(start -0.7874 -0.4064)
			(end -0.7874 0.4064)
			(stroke
				(width 0.1524)
				(type default)
			)
			(layer "B.SilkS")
		)
		(fp_line
			(start 0.67945 0.3048)
			(end 0.67945 -0.305054)
			(stroke
				(width 0.1)
				(type default)
			)
			(layer "B.Fab")
		)
		(fp_line
			(start 0.67945 -0.305054)
			(end 0.12065 -0.305054)
			(stroke
				(width 0.1)
				(type default)
			)
			(layer "B.Fab")
		)
		(fp_line
			(start 0.12065 0.3048)
			(end 0.67945 0.3048)
			(stroke
				(width 0.1)
				(type default)
			)
			(layer "B.Fab")
		)
		(fp_line
			(start 0.12065 0.2794)
			(end 0.12065 0.3048)
			(stroke
				(width 0.1)
				(type default)
			)
			(layer "B.Fab")
		)
		(fp_line
			(start 0.12065 -0.2794)
			(end -0.12065 -0.2794)
			(stroke
				(width 0.1)
				(type default)
			)
			(layer "B.Fab")
		)
		(fp_line
			(start 0.12065 -0.305054)
			(end 0.12065 -0.2794)
			(stroke
				(width 0.1)
				(type default)
			)
			(layer "B.Fab")
		)
		(fp_line
			(start -0.120396 0.3048)
			(end -0.120396 0.2794)
			(stroke
				(width 0.1)
				(type default)
			)
			(layer "B.Fab")
		)
		(fp_line
			(start -0.120396 0.2794)
			(end 0.12065 0.2794)
			(stroke
				(width 0.1)
				(type default)
			)
			(layer "B.Fab")
		)
		(fp_line
			(start -0.12065 -0.2794)
			(end -0.12065 -0.3048)
			(stroke
				(width 0.1)
				(type default)
			)
			(layer "B.Fab")
		)
		(fp_line
			(start -0.12065 -0.3048)
			(end -0.67945 -0.3048)
			(stroke
				(width 0.1)
				(type default)
			)
			(layer "B.Fab")
		)
		(fp_line
			(start -0.67945 0.3048)
			(end -0.120396 0.3048)
			(stroke
				(width 0.1)
				(type default)
			)
			(layer "B.Fab")
		)
		(fp_line
			(start -0.67945 -0.3048)
			(end -0.67945 0.3048)
			(stroke
				(width 0.1)
				(type default)
			)
			(layer "B.Fab")
		)
		(pad "1" smd circle
			(at 0.40005 0)
			(size 0 0)
			(layers "B.Cu" "B.Mask" "B.Paste")
			(net "SMB_P52V_VPDB_SCL")
		)
		(pad "2" smd circle
			(at -0.40005 0)
			(size 0 0)
			(layers "B.Cu" "B.Mask" "B.Paste")
			(net "GND")
		)
	)
	(footprint ""
		(layer "B.Cu")
		(at 236.982 -70.993 90)
		(property "Reference" "R69"
			(at 0 0 90)
			(layer "B.SilkS")
			(hide yes)
			(effects
				(font
					(size 1.27 1.27)
				)
				(justify mirror)
			)
		)
		(property "Value" ""
			(at 0 0 90)
			(layer "B.Fab")
			(effects
				(font
					(size 1.27 1.27)
				)
				(justify mirror)
			)
		)
		(duplicate_pad_numbers_are_jumpers no)
		(fp_line
			(start 0.7874 -0.4064)
			(end -0.7874 -0.4064)
			(stroke
				(width 0.1524)
				(type default)
			)
			(layer "B.SilkS")
		)
		(fp_line
			(start -0.7874 -0.4064)
			(end -0.7874 0.4064)
			(stroke
				(width 0.1524)
				(type default)
			)
			(layer "B.SilkS")
		)
		(fp_line
			(start 0.7874 0.4064)
			(end 0.7874 -0.4064)
			(stroke
				(width 0.1524)
				(type default)
			)
			(layer "B.SilkS")
		)
		(fp_line
			(start -0.7874 0.4064)
			(end 0.7874 0.4064)
			(stroke
				(width 0.1524)
				(type default)
			)
			(layer "B.SilkS")
		)
		(fp_line
			(start 0.67945 -0.305054)
			(end 0.12065 -0.305054)
			(stroke
				(width 0.1)
				(type default)
			)
			(layer "B.Fab")
		)
		(fp_line
			(start 0.12065 -0.305054)
			(end 0.12065 -0.2794)
			(stroke
				(width 0.1)
				(type default)
			)
			(layer "B.Fab")
		)
		(fp_line
			(start -0.12065 -0.3048)
			(end -0.67945 -0.3048)
			(stroke
				(width 0.1)
				(type default)
			)
			(layer "B.Fab")
		)
		(fp_line
			(start -0.67945 -0.3048)
			(end -0.67945 0.3048)
			(stroke
				(width 0.1)
				(type default)
			)
			(layer "B.Fab")
		)
		(fp_line
			(start 0.12065 -0.2794)
			(end -0.12065 -0.2794)
			(stroke
				(width 0.1)
				(type default)
			)
			(layer "B.Fab")
		)
		(fp_line
			(start -0.12065 -0.2794)
			(end -0.12065 -0.3048)
			(stroke
				(width 0.1)
				(type default)
			)
			(layer "B.Fab")
		)
		(fp_line
			(start 0.12065 0.2794)
			(end 0.12065 0.3048)
			(stroke
				(width 0.1)
				(type default)
			)
			(layer "B.Fab")
		)
		(fp_line
			(start -0.120396 0.2794)
			(end 0.12065 0.2794)
			(stroke
				(width 0.1)
				(type default)
			)
			(layer "B.Fab")
		)
		(fp_line
			(start 0.67945 0.3048)
			(end 0.67945 -0.305054)
			(stroke
				(width 0.1)
				(type default)
			)
			(layer "B.Fab")
		)
		(fp_line
			(start 0.12065 0.3048)
			(end 0.67945 0.3048)
			(stroke
				(width 0.1)
				(type default)
			)
			(layer "B.Fab")
		)
		(fp_line
			(start -0.120396 0.3048)
			(end -0.120396 0.2794)
			(stroke
				(width 0.1)
				(type default)
			)
			(layer "B.Fab")
		)
		(fp_line
			(start -0.67945 0.3048)
			(end -0.120396 0.3048)
			(stroke
				(width 0.1)
				(type default)
			)
			(layer "B.Fab")
		)
		(pad "1" smd circle
			(at 0.40005 0 270)
			(size 0 0)
			(layers "B.Cu" "B.Mask" "B.Paste")
			(net "RST_SMB_PDB_N")
		)
		(pad "2" smd circle
			(at -0.40005 0 270)
			(size 0 0)
			(layers "B.Cu" "B.Mask" "B.Paste")
			(net "RST_SMB_PDB_R_N")
		)
	)
	(footprint ""
		(layer "B.Cu")
		(at 38.989 -84.074)
		(property "Reference" "R79"
			(at 0 0 0)
			(layer "B.SilkS")
			(hide yes)
			(effects
				(font
					(size 1.27 1.27)
				)
				(justify mirror)
			)
		)
		(property "Value" ""
			(at 0 0 0)
			(layer "B.Fab")
			(effects
				(font
					(size 1.27 1.27)
				)
				(justify mirror)
			)
		)
		(duplicate_pad_numbers_are_jumpers no)
		(fp_line
			(start -0.7874 -0.4064)
			(end -0.7874 0.4064)
			(stroke
				(width 0.1524)
				(type default)
			)
			(layer "B.SilkS")
		)
		(fp_line
			(start -0.7874 0.4064)
			(end 0.7874 0.4064)
			(stroke
				(width 0.1524)
				(type default)
			)
			(layer "B.SilkS")
		)
		(fp_line
			(start 0.7874 -0.4064)
			(end -0.7874 -0.4064)
			(stroke
				(width 0.1524)
				(type default)
			)
			(layer "B.SilkS")
		)
		(fp_line
			(start 0.7874 0.4064)
			(end 0.7874 -0.4064)
			(stroke
				(width 0.1524)
				(type default)
			)
			(layer "B.SilkS")
		)
		(fp_line
			(start -0.67945 -0.3048)
			(end -0.67945 0.3048)
			(stroke
				(width 0.1)
				(type default)
			)
			(layer "B.Fab")
		)
		(fp_line
			(start -0.67945 0.3048)
			(end -0.120396 0.3048)
			(stroke
				(width 0.1)
				(type default)
			)
			(layer "B.Fab")
		)
		(fp_line
			(start -0.12065 -0.3048)
			(end -0.67945 -0.3048)
			(stroke
				(width 0.1)
				(type default)
			)
			(layer "B.Fab")
		)
		(fp_line
			(start -0.12065 -0.2794)
			(end -0.12065 -0.3048)
			(stroke
				(width 0.1)
				(type default)
			)
			(layer "B.Fab")
		)
		(fp_line
			(start -0.120396 0.2794)
			(end 0.12065 0.2794)
			(stroke
				(width 0.1)
				(type default)
			)
			(layer "B.Fab")
		)
		(fp_line
			(start -0.120396 0.3048)
			(end -0.120396 0.2794)
			(stroke
				(width 0.1)
				(type default)
			)
			(layer "B.Fab")
		)
		(fp_line
			(start 0.12065 -0.305054)
			(end 0.12065 -0.2794)
			(stroke
				(width 0.1)
				(type default)
			)
			(layer "B.Fab")
		)
		(fp_line
			(start 0.12065 -0.2794)
			(end -0.12065 -0.2794)
			(stroke
				(width 0.1)
				(type default)
			)
			(layer "B.Fab")
		)
		(fp_line
			(start 0.12065 0.2794)
			(end 0.12065 0.3048)
			(stroke
				(width 0.1)
				(type default)
			)
			(layer "B.Fab")
		)
		(fp_line
			(start 0.12065 0.3048)
			(end 0.67945 0.3048)
			(stroke
				(width 0.1)
				(type default)
			)
			(layer "B.Fab")
		)
		(fp_line
			(start 0.67945 -0.305054)
			(end 0.12065 -0.305054)
			(stroke
				(width 0.1)
				(type default)
			)
			(layer "B.Fab")
		)
		(fp_line
			(start 0.67945 0.3048)
			(end 0.67945 -0.305054)
			(stroke
				(width 0.1)
				(type default)
			)
			(layer "B.Fab")
		)
		(pad "1" smd circle
			(at 0.40005 0 180)
			(size 0 0)
			(layers "B.Cu" "B.Mask" "B.Paste")
			(net "SMB_P52V_HPDB_SDA")
		)
		(pad "2" smd circle
			(at -0.40005 0 180)
			(size 0 0)
			(layers "B.Cu" "B.Mask" "B.Paste")
			(net "SMB_P52V_HPDB_R_SDA")
		)
	)
	(footprint ""
		(layer "B.Cu")
		(at 269.621 -33.147)
		(property "Reference" "PR213"
			(at 0 0 0)
			(layer "B.SilkS")
			(hide yes)
			(effects
				(font
					(size 1.27 1.27)
				)
				(justify mirror)
			)
		)
		(property "Value" ""
			(at 0 0 0)
			(layer "B.Fab")
			(effects
				(font
					(size 1.27 1.27)
				)
				(justify mirror)
			)
		)
		(duplicate_pad_numbers_are_jumpers no)
		(fp_line
			(start -0.7874 -0.4064)
			(end -0.7874 0.4064)
			(stroke
				(width 0.1524)
				(type default)
			)
			(layer "B.SilkS")
		)
		(fp_line
			(start -0.7874 0.4064)
			(end 0.7874 0.4064)
			(stroke
				(width 0.1524)
				(type default)
			)
			(layer "B.SilkS")
		)
		(fp_line
			(start 0.7874 -0.4064)
			(end -0.7874 -0.4064)
			(stroke
				(width 0.1524)
				(type default)
			)
			(layer "B.SilkS")
		)
		(fp_line
			(start 0.7874 0.4064)
			(end 0.7874 -0.4064)
			(stroke
				(width 0.1524)
				(type default)
			)
			(layer "B.SilkS")
		)
		(fp_line
			(start -0.67945 -0.3048)
			(end -0.67945 0.3048)
			(stroke
				(width 0.1)
				(type default)
			)
			(layer "B.Fab")
		)
		(fp_line
			(start -0.67945 0.3048)
			(end -0.120396 0.3048)
			(stroke
				(width 0.1)
				(type default)
			)
			(layer "B.Fab")
		)
		(fp_line
			(start -0.12065 -0.3048)
			(end -0.67945 -0.3048)
			(stroke
				(width 0.1)
				(type default)
			)
			(layer "B.Fab")
		)
		(fp_line
			(start -0.12065 -0.2794)
			(end -0.12065 -0.3048)
			(stroke
				(width 0.1)
				(type default)
			)
			(layer "B.Fab")
		)
		(fp_line
			(start -0.120396 0.2794)
			(end 0.12065 0.2794)
			(stroke
				(width 0.1)
				(type default)
			)
			(layer "B.Fab")
		)
		(fp_line
			(start -0.120396 0.3048)
			(end -0.120396 0.2794)
			(stroke
				(width 0.1)
				(type default)
			)
			(layer "B.Fab")
		)
		(fp_line
			(start 0.12065 -0.305054)
			(end 0.12065 -0.2794)
			(stroke
				(width 0.1)
				(type default)
			)
			(layer "B.Fab")
		)
		(fp_line
			(start 0.12065 -0.2794)
			(end -0.12065 -0.2794)
			(stroke
				(width 0.1)
				(type default)
			)
			(layer "B.Fab")
		)
		(fp_line
			(start 0.12065 0.2794)
			(end 0.12065 0.3048)
			(stroke
				(width 0.1)
				(type default)
			)
			(layer "B.Fab")
		)
		(fp_line
			(start 0.12065 0.3048)
			(end 0.67945 0.3048)
			(stroke
				(width 0.1)
				(type default)
			)
			(layer "B.Fab")
		)
		(fp_line
			(start 0.67945 -0.305054)
			(end 0.12065 -0.305054)
			(stroke
				(width 0.1)
				(type default)
			)
			(layer "B.Fab")
		)
		(fp_line
			(start 0.67945 0.3048)
			(end 0.67945 -0.305054)
			(stroke
				(width 0.1)
				(type default)
			)
			(layer "B.Fab")
		)
		(pad "1" smd circle
			(at 0.40005 0 180)
			(size 0 0)
			(layers "B.Cu" "B.Mask" "B.Paste")
			(net "P52V_HS1_SIO")
		)
		(pad "2" smd circle
			(at -0.40005 0 180)
			(size 0 0)
			(layers "B.Cu" "B.Mask" "B.Paste")
			(net "GND_FIELD_SIGNAL")
		)
	)
	(footprint ""
		(layer "B.Cu")
		(at 147.32 -113.792)
		(property "Reference" "U23"
			(at 2.667 -2.51333 0)
			(unlocked yes)
			(layer "B.SilkS")
			(effects
				(font
					(size 0.7874 0.5842)
					(thickness 0.1524)
				)
				(justify left mirror)
			)
		)
		(property "Value" ""
			(at 0 0 0)
			(layer "B.Fab")
			(effects
				(font
					(size 1.27 1.27)
				)
				(justify mirror)
			)
		)
		(duplicate_pad_numbers_are_jumpers no)
		(fp_line
			(start -1.603248 -1.500124)
			(end -1.603248 1.500124)
			(stroke
				(width 0.1524)
				(type default)
			)
			(layer "B.SilkS")
		)
		(fp_line
			(start -1.603248 1.500124)
			(end 1.603248 1.500124)
			(stroke
				(width 0.1524)
				(type default)
			)
			(layer "B.SilkS")
		)
		(fp_line
			(start 1.603248 -1.500124)
			(end -1.603248 -1.500124)
			(stroke
				(width 0.1524)
				(type default)
			)
			(layer "B.SilkS")
		)
		(fp_line
			(start 1.603248 1.500124)
			(end 1.603248 -1.500124)
			(stroke
				(width 0.1524)
				(type default)
			)
			(layer "B.SilkS")
		)
		(fp_line
			(start -1.249934 -0.219964)
			(end -0.700024 -0.219964)
			(stroke
				(width 0.1)
				(type default)
			)
			(layer "B.Fab")
		)
		(fp_line
			(start -1.249934 0.219964)
			(end -1.249934 -0.219964)
			(stroke
				(width 0.1)
				(type default)
			)
			(layer "B.Fab")
		)
		(fp_line
			(start -0.700024 -1.500124)
			(end 0.700024 -1.500124)
			(stroke
				(width 0.1)
				(type default)
			)
			(layer "B.Fab")
		)
		(fp_line
			(start -0.700024 -0.219964)
			(end -0.700024 -1.500124)
			(stroke
				(width 0.1)
				(type default)
			)
			(layer "B.Fab")
		)
		(fp_line
			(start -0.700024 0.219964)
			(end -1.249934 0.219964)
			(stroke
				(width 0.1)
				(type default)
			)
			(layer "B.Fab")
		)
		(fp_line
			(start -0.700024 1.500124)
			(end -0.700024 0.219964)
			(stroke
				(width 0.1)
				(type default)
			)
			(layer "B.Fab")
		)
		(fp_line
			(start 0.6985 -0.729996)
			(end 0.6985 0.729996)
			(stroke
				(width 0.1)
				(type default)
			)
			(layer "B.Fab")
		)
		(fp_line
			(start 0.6985 0.729996)
			(end 1.249934 0.729996)
			(stroke
				(width 0.1)
				(type default)
			)
			(layer "B.Fab")
		)
		(fp_line
			(start 0.700024 -1.500124)
			(end 0.700024 -1.169924)
			(stroke
				(width 0.1)
				(type default)
			)
			(layer "B.Fab")
		)
		(fp_line
			(start 0.700024 -1.169924)
			(end 1.249934 -1.169924)
			(stroke
				(width 0.1)
				(type default)
			)
			(layer "B.Fab")
		)
		(fp_line
			(start 0.700024 1.169924)
			(end 0.700024 1.500124)
			(stroke
				(width 0.1)
				(type default)
			)
			(layer "B.Fab")
		)
		(fp_line
			(start 0.700024 1.500124)
			(end -0.700024 1.500124)
			(stroke
				(width 0.1)
				(type default)
			)
			(layer "B.Fab")
		)
		(fp_line
			(start 1.249934 -1.169924)
			(end 1.249934 -0.729996)
			(stroke
				(width 0.1)
				(type default)
			)
			(layer "B.Fab")
		)
		(fp_line
			(start 1.249934 -0.729996)
			(end 0.6985 -0.729996)
			(stroke
				(width 0.1)
				(type default)
			)
			(layer "B.Fab")
		)
		(fp_line
			(start 1.249934 0.729996)
			(end 1.249934 1.169924)
			(stroke
				(width 0.1)
				(type default)
			)
			(layer "B.Fab")
		)
		(fp_line
			(start 1.249934 1.169924)
			(end 0.700024 1.169924)
			(stroke
				(width 0.1)
				(type default)
			)
			(layer "B.Fab")
		)
		(fp_rect
			(start 0.700024 1.500124)
			(end -0.700024 -1.500124)
			(stroke
				(width 0)
				(type default)
			)
			(fill no)
			(layer "B.Fab")
		)
		(pad "D" smd rect
			(at -0.999998 0 270)
			(size 0.8128 0.9144)
			(layers "B.Cu" "B.Mask" "B.Paste")
			(net "BRICK_P12V0_EN_R_N")
		)
		(pad "G" smd rect
			(at 0.999998 -0.94996 270)
			(size 0.8128 0.9144)
			(layers "B.Cu" "B.Mask" "B.Paste")
			(net "PWRGD_P52V_HS1_PG")
		)
		(pad "S" smd rect
			(at 0.999998 0.94996 270)
			(size 0.8128 0.9144)
			(layers "B.Cu" "B.Mask" "B.Paste")
			(net "GND")
		)
	)
	(footprint ""
		(layer "B.Cu")
		(at 209.169 -82.55 90)
		(property "Reference" "R20"
			(at 0 0 90)
			(layer "B.SilkS")
			(hide yes)
			(effects
				(font
					(size 1.27 1.27)
				)
				(justify mirror)
			)
		)
		(property "Value" ""
			(at 0 0 90)
			(layer "B.Fab")
			(effects
				(font
					(size 1.27 1.27)
				)
				(justify mirror)
			)
		)
		(duplicate_pad_numbers_are_jumpers no)
		(fp_line
			(start 0.7874 -0.4064)
			(end -0.7874 -0.4064)
			(stroke
				(width 0.1524)
				(type default)
			)
			(layer "B.SilkS")
		)
		(fp_line
			(start -0.7874 -0.4064)
			(end -0.7874 0.4064)
			(stroke
				(width 0.1524)
				(type default)
			)
			(layer "B.SilkS")
		)
		(fp_line
			(start 0.7874 0.4064)
			(end 0.7874 -0.4064)
			(stroke
				(width 0.1524)
				(type default)
			)
			(layer "B.SilkS")
		)
		(fp_line
			(start -0.7874 0.4064)
			(end 0.7874 0.4064)
			(stroke
				(width 0.1524)
				(type default)
			)
			(layer "B.SilkS")
		)
		(fp_line
			(start 0.67945 -0.305054)
			(end 0.12065 -0.305054)
			(stroke
				(width 0.1)
				(type default)
			)
			(layer "B.Fab")
		)
		(fp_line
			(start 0.12065 -0.305054)
			(end 0.12065 -0.2794)
			(stroke
				(width 0.1)
				(type default)
			)
			(layer "B.Fab")
		)
		(fp_line
			(start -0.12065 -0.3048)
			(end -0.67945 -0.3048)
			(stroke
				(width 0.1)
				(type default)
			)
			(layer "B.Fab")
		)
		(fp_line
			(start -0.67945 -0.3048)
			(end -0.67945 0.3048)
			(stroke
				(width 0.1)
				(type default)
			)
			(layer "B.Fab")
		)
		(fp_line
			(start 0.12065 -0.2794)
			(end -0.12065 -0.2794)
			(stroke
				(width 0.1)
				(type default)
			)
			(layer "B.Fab")
		)
		(fp_line
			(start -0.12065 -0.2794)
			(end -0.12065 -0.3048)
			(stroke
				(width 0.1)
				(type default)
			)
			(layer "B.Fab")
		)
		(fp_line
			(start 0.12065 0.2794)
			(end 0.12065 0.3048)
			(stroke
				(width 0.1)
				(type default)
			)
			(layer "B.Fab")
		)
		(fp_line
			(start -0.120396 0.2794)
			(end 0.12065 0.2794)
			(stroke
				(width 0.1)
				(type default)
			)
			(layer "B.Fab")
		)
		(fp_line
			(start 0.67945 0.3048)
			(end 0.67945 -0.305054)
			(stroke
				(width 0.1)
				(type default)
			)
			(layer "B.Fab")
		)
		(fp_line
			(start 0.12065 0.3048)
			(end 0.67945 0.3048)
			(stroke
				(width 0.1)
				(type default)
			)
			(layer "B.Fab")
		)
		(fp_line
			(start -0.120396 0.3048)
			(end -0.120396 0.2794)
			(stroke
				(width 0.1)
				(type default)
			)
			(layer "B.Fab")
		)
		(fp_line
			(start -0.67945 0.3048)
			(end -0.120396 0.3048)
			(stroke
				(width 0.1)
				(type default)
			)
			(layer "B.Fab")
		)
		(pad "1" smd circle
			(at 0.40005 0 270)
			(size 0 0)
			(layers "B.Cu" "B.Mask" "B.Paste")
			(net "P3V3_AUX")
		)
		(pad "2" smd circle
			(at -0.40005 0 270)
			(size 0 0)
			(layers "B.Cu" "B.Mask" "B.Paste")
			(net "PCA9555_A2")
		)
	)
	(footprint ""
		(layer "B.Cu")
		(at 233.68 -87.884 -90)
		(property "Reference" "U9"
			(at 4.699 -0.86233 270)
			(unlocked yes)
			(layer "B.SilkS")
			(effects
				(font
					(size 0.7874 0.5842)
					(thickness 0.1524)
				)
				(justify left mirror)
			)
		)
		(property "Value" ""
			(at 0 0 90)
			(layer "B.Fab")
			(effects
				(font
					(size 1.27 1.27)
				)
				(justify mirror)
			)
		)
		(duplicate_pad_numbers_are_jumpers no)
		(fp_line
			(start -2.032 1.549908)
			(end 2.032 1.549908)
			(stroke
				(width 0.1524)
				(type default)
			)
			(layer "B.SilkS")
		)
		(fp_line
			(start 2.032 1.549908)
			(end 2.032 -1.549908)
			(stroke
				(width 0.1524)
				(type default)
			)
			(layer "B.SilkS")
		)
		(fp_line
			(start -2.032 -1.549908)
			(end -2.032 1.549908)
			(stroke
				(width 0.1524)
				(type default)
			)
			(layer "B.SilkS")
		)
		(fp_line
			(start 2.032 -1.549908)
			(end -2.032 -1.549908)
			(stroke
				(width 0.1524)
				(type default)
			)
			(layer "B.SilkS")
		)
		(fp_poly
			(pts
				(xy 2.9464 -1.2192) (xy 2.9464 -0.7112) (xy 2.1844 -0.9652)
			)
			(stroke
				(width 0)
				(type default)
			)
			(fill yes)
			(layer "B.SilkS")
		)
		(fp_line
			(start -0.849884 1.549908)
			(end -0.849884 -1.549908)
			(stroke
				(width 0.1)
				(type default)
			)
			(layer "B.Fab")
		)
		(fp_line
			(start 0.849884 1.549908)
			(end -0.849884 1.549908)
			(stroke
				(width 0.1)
				(type default)
			)
			(layer "B.Fab")
		)
		(fp_line
			(start -0.849884 -1.549908)
			(end 0.849884 -1.549908)
			(stroke
				(width 0.1)
				(type default)
			)
			(layer "B.Fab")
		)
		(fp_line
			(start 0.849884 -1.549908)
			(end 0.849884 1.549908)
			(stroke
				(width 0.1)
				(type default)
			)
			(layer "B.Fab")
		)
		(fp_poly
			(pts
				(xy 2.9464 -1.2192) (xy 2.9464 -0.7112) (xy 2.1844 -0.9652)
			)
			(stroke
				(width 0)
				(type default)
			)
			(fill yes)
			(layer "B.Fab")
		)
		(pad "1" smd rect
			(at 1.225042 -0.94996 180)
			(size 0.4572 1.3208)
			(layers "B.Cu" "B.Mask" "B.Paste")
			(net "PWRGD_P3V3_AUX_MB_BUF_N")
		)
		(pad "2" smd rect
			(at 1.225042 0 180)
			(size 0.4572 1.3208)
			(layers "B.Cu" "B.Mask" "B.Paste")
			(net "RST_SMB_PDB_N")
		)
		(pad "3" smd rect
			(at 1.225042 0.94996 180)
			(size 0.4572 1.3208)
			(layers "B.Cu" "B.Mask" "B.Paste")
			(net "GND")
		)
		(pad "4" smd rect
			(at -1.225042 0.94996 180)
			(size 0.4572 1.3208)
			(layers "B.Cu" "B.Mask" "B.Paste")
			(net "RST_SMB_PDB_BUF_R_N")
		)
		(pad "5" smd rect
			(at -1.225042 -0.94996 180)
			(size 0.4572 1.3208)
			(layers "B.Cu" "B.Mask" "B.Paste")
			(net "P3V3_AUX")
		)
	)
	(footprint ""
		(layer "B.Cu")
		(at 238.682784 -89.50579 180)
		(property "Reference" "R1"
			(at 0 0 0)
			(layer "B.SilkS")
			(hide yes)
			(effects
				(font
					(size 1.27 1.27)
				)
				(justify mirror)
			)
		)
		(property "Value" ""
			(at 0 0 0)
			(layer "B.Fab")
			(effects
				(font
					(size 1.27 1.27)
				)
				(justify mirror)
			)
		)
		(duplicate_pad_numbers_are_jumpers no)
		(fp_line
			(start 0.7874 0.4064)
			(end 0.7874 -0.4064)
			(stroke
				(width 0.1524)
				(type default)
			)
			(layer "B.SilkS")
		)
		(fp_line
			(start 0.7874 -0.4064)
			(end -0.7874 -0.4064)
			(stroke
				(width 0.1524)
				(type default)
			)
			(layer "B.SilkS")
		)
		(fp_line
			(start -0.7874 0.4064)
			(end 0.7874 0.4064)
			(stroke
				(width 0.1524)
				(type default)
			)
			(layer "B.SilkS")
		)
		(fp_line
			(start -0.7874 -0.4064)
			(end -0.7874 0.4064)
			(stroke
				(width 0.1524)
				(type default)
			)
			(layer "B.SilkS")
		)
		(fp_line
			(start 0.67945 0.3048)
			(end 0.67945 -0.305054)
			(stroke
				(width 0.1)
				(type default)
			)
			(layer "B.Fab")
		)
		(fp_line
			(start 0.67945 -0.305054)
			(end 0.12065 -0.305054)
			(stroke
				(width 0.1)
				(type default)
			)
			(layer "B.Fab")
		)
		(fp_line
			(start 0.12065 0.3048)
			(end 0.67945 0.3048)
			(stroke
				(width 0.1)
				(type default)
			)
			(layer "B.Fab")
		)
		(fp_line
			(start 0.12065 0.2794)
			(end 0.12065 0.3048)
			(stroke
				(width 0.1)
				(type default)
			)
			(layer "B.Fab")
		)
		(fp_line
			(start 0.12065 -0.2794)
			(end -0.12065 -0.2794)
			(stroke
				(width 0.1)
				(type default)
			)
			(layer "B.Fab")
		)
		(fp_line
			(start 0.12065 -0.305054)
			(end 0.12065 -0.2794)
			(stroke
				(width 0.1)
				(type default)
			)
			(layer "B.Fab")
		)
		(fp_line
			(start -0.120396 0.3048)
			(end -0.120396 0.2794)
			(stroke
				(width 0.1)
				(type default)
			)
			(layer "B.Fab")
		)
		(fp_line
			(start -0.120396 0.2794)
			(end 0.12065 0.2794)
			(stroke
				(width 0.1)
				(type default)
			)
			(layer "B.Fab")
		)
		(fp_line
			(start -0.12065 -0.2794)
			(end -0.12065 -0.3048)
			(stroke
				(width 0.1)
				(type default)
			)
			(layer "B.Fab")
		)
		(fp_line
			(start -0.12065 -0.3048)
			(end -0.67945 -0.3048)
			(stroke
				(width 0.1)
				(type default)
			)
			(layer "B.Fab")
		)
		(fp_line
			(start -0.67945 0.3048)
			(end -0.120396 0.3048)
			(stroke
				(width 0.1)
				(type default)
			)
			(layer "B.Fab")
		)
		(fp_line
			(start -0.67945 -0.3048)
			(end -0.67945 0.3048)
			(stroke
				(width 0.1)
				(type default)
			)
			(layer "B.Fab")
		)
		(pad "1" smd circle
			(at 0.40005 0)
			(size 0 0)
			(layers "B.Cu" "B.Mask" "B.Paste")
			(net "SMB_PDB_MISC_SCL_R")
		)
		(pad "2" smd circle
			(at -0.40005 0)
			(size 0 0)
			(layers "B.Cu" "B.Mask" "B.Paste")
			(net "P3V3_AUX")
		)
	)
	(footprint ""
		(layer "B.Cu")
		(at 134.493 -77.597 180)
		(property "Reference" "C52"
			(at 0 0 0)
			(layer "B.SilkS")
			(hide yes)
			(effects
				(font
					(size 1.27 1.27)
				)
				(justify mirror)
			)
		)
		(property "Value" ""
			(at 0 0 0)
			(layer "B.Fab")
			(effects
				(font
					(size 1.27 1.27)
				)
				(justify mirror)
			)
		)
		(duplicate_pad_numbers_are_jumpers no)
		(fp_line
			(start 0.7874 0.4064)
			(end 0.7874 -0.4064)
			(stroke
				(width 0.1524)
				(type default)
			)
			(layer "B.SilkS")
		)
		(fp_line
			(start 0.7874 -0.4064)
			(end -0.7874 -0.4064)
			(stroke
				(width 0.1524)
				(type default)
			)
			(layer "B.SilkS")
		)
		(fp_line
			(start -0.7874 0.4064)
			(end 0.7874 0.4064)
			(stroke
				(width 0.1524)
				(type default)
			)
			(layer "B.SilkS")
		)
		(fp_line
			(start -0.7874 -0.4064)
			(end -0.7874 0.4064)
			(stroke
				(width 0.1524)
				(type default)
			)
			(layer "B.SilkS")
		)
		(fp_line
			(start 0.67945 0.3048)
			(end 0.67945 -0.305054)
			(stroke
				(width 0.1)
				(type default)
			)
			(layer "B.Fab")
		)
		(fp_line
			(start 0.67945 -0.305054)
			(end 0.12065 -0.305054)
			(stroke
				(width 0.1)
				(type default)
			)
			(layer "B.Fab")
		)
		(fp_line
			(start 0.12065 0.3048)
			(end 0.67945 0.3048)
			(stroke
				(width 0.1)
				(type default)
			)
			(layer "B.Fab")
		)
		(fp_line
			(start 0.12065 0.2794)
			(end 0.12065 0.3048)
			(stroke
				(width 0.1)
				(type default)
			)
			(layer "B.Fab")
		)
		(fp_line
			(start 0.12065 -0.2794)
			(end -0.12065 -0.2794)
			(stroke
				(width 0.1)
				(type default)
			)
			(layer "B.Fab")
		)
		(fp_line
			(start 0.12065 -0.305054)
			(end 0.12065 -0.2794)
			(stroke
				(width 0.1)
				(type default)
			)
			(layer "B.Fab")
		)
		(fp_line
			(start -0.120396 0.3048)
			(end -0.120396 0.2794)
			(stroke
				(width 0.1)
				(type default)
			)
			(layer "B.Fab")
		)
		(fp_line
			(start -0.120396 0.2794)
			(end 0.12065 0.2794)
			(stroke
				(width 0.1)
				(type default)
			)
			(layer "B.Fab")
		)
		(fp_line
			(start -0.12065 -0.2794)
			(end -0.12065 -0.3048)
			(stroke
				(width 0.1)
				(type default)
			)
			(layer "B.Fab")
		)
		(fp_line
			(start -0.12065 -0.3048)
			(end -0.67945 -0.3048)
			(stroke
				(width 0.1)
				(type default)
			)
			(layer "B.Fab")
		)
		(fp_line
			(start -0.67945 0.3048)
			(end -0.120396 0.3048)
			(stroke
				(width 0.1)
				(type default)
			)
			(layer "B.Fab")
		)
		(fp_line
			(start -0.67945 -0.3048)
			(end -0.67945 0.3048)
			(stroke
				(width 0.1)
				(type default)
			)
			(layer "B.Fab")
		)
		(pad "1" smd circle
			(at 0.40005 0)
			(size 0 0)
			(layers "B.Cu" "B.Mask" "B.Paste")
			(net "SMB_P52V_VPDB_SDA")
		)
		(pad "2" smd circle
			(at -0.40005 0)
			(size 0 0)
			(layers "B.Cu" "B.Mask" "B.Paste")
			(net "GND")
		)
	)
	(footprint ""
		(layer "B.Cu")
		(at 282.067 -30.734 90)
		(property "Reference" "R5915"
			(at 0 0 90)
			(layer "B.SilkS")
			(hide yes)
			(effects
				(font
					(size 1.27 1.27)
				)
				(justify mirror)
			)
		)
		(property "Value" ""
			(at 0 0 90)
			(layer "B.Fab")
			(effects
				(font
					(size 1.27 1.27)
				)
				(justify mirror)
			)
		)
		(duplicate_pad_numbers_are_jumpers no)
		(fp_line
			(start 1.651 -0.8382)
			(end -1.651 -0.8382)
			(stroke
				(width 0.1524)
				(type default)
			)
			(layer "B.SilkS")
		)
		(fp_line
			(start -1.651 -0.8382)
			(end -1.651 0.8382)
			(stroke
				(width 0.1524)
				(type default)
			)
			(layer "B.SilkS")
		)
		(fp_line
			(start 1.651 0.8382)
			(end 1.651 -0.8382)
			(stroke
				(width 0.1524)
				(type default)
			)
			(layer "B.SilkS")
		)
		(fp_line
			(start -1.651 0.8382)
			(end 1.651 0.8382)
			(stroke
				(width 0.1524)
				(type default)
			)
			(layer "B.SilkS")
		)
		(fp_line
			(start 1.559814 -0.7366)
			(end 1.559814 0.7366)
			(stroke
				(width 0.1)
				(type default)
			)
			(layer "B.Fab")
		)
		(fp_line
			(start 1.524 -0.7366)
			(end 1.559814 -0.7366)
			(stroke
				(width 0.1)
				(type default)
			)
			(layer "B.Fab")
		)
		(fp_line
			(start -1.524 -0.7366)
			(end 1.524 -0.7366)
			(stroke
				(width 0.1)
				(type default)
			)
			(layer "B.Fab")
		)
		(fp_line
			(start -1.560576 -0.7366)
			(end -1.524 -0.7366)
			(stroke
				(width 0.1)
				(type default)
			)
			(layer "B.Fab")
		)
		(fp_line
			(start 1.559814 0.7366)
			(end 1.524 0.7366)
			(stroke
				(width 0.1)
				(type default)
			)
			(layer "B.Fab")
		)
		(fp_line
			(start 1.524 0.7366)
			(end -1.524 0.7366)
			(stroke
				(width 0.1)
				(type default)
			)
			(layer "B.Fab")
		)
		(fp_line
			(start -1.524 0.7366)
			(end -1.560576 0.7366)
			(stroke
				(width 0.1)
				(type default)
			)
			(layer "B.Fab")
		)
		(fp_line
			(start -1.560576 0.7366)
			(end -1.560576 -0.7366)
			(stroke
				(width 0.1)
				(type default)
			)
			(layer "B.Fab")
		)
		(pad "1" smd rect
			(at 0.94996 0 90)
			(size 1.1176 1.3716)
			(layers "B.Cu" "B.Mask" "B.Paste")
			(net "P52V_1_R")
		)
		(pad "2" smd rect
			(at -0.94996 0 90)
			(size 1.1176 1.3716)
			(layers "B.Cu" "B.Mask" "B.Paste")
			(net "FM_AC_PWR_CYCLE_BUF")
		)
	)
	(footprint ""
		(layer "B.Cu")
		(at 272.669 -47.625 -90)
		(property "Reference" "R5908"
			(at 0 0 90)
			(layer "B.SilkS")
			(hide yes)
			(effects
				(font
					(size 1.27 1.27)
				)
				(justify mirror)
			)
		)
		(property "Value" ""
			(at 0 0 90)
			(layer "B.Fab")
			(effects
				(font
					(size 1.27 1.27)
				)
				(justify mirror)
			)
		)
		(duplicate_pad_numbers_are_jumpers no)
		(fp_line
			(start -0.7874 0.4064)
			(end 0.7874 0.4064)
			(stroke
				(width 0.1524)
				(type default)
			)
			(layer "B.SilkS")
		)
		(fp_line
			(start 0.7874 0.4064)
			(end 0.7874 -0.4064)
			(stroke
				(width 0.1524)
				(type default)
			)
			(layer "B.SilkS")
		)
		(fp_line
			(start -0.7874 -0.4064)
			(end -0.7874 0.4064)
			(stroke
				(width 0.1524)
				(type default)
			)
			(layer "B.SilkS")
		)
		(fp_line
			(start 0.7874 -0.4064)
			(end -0.7874 -0.4064)
			(stroke
				(width 0.1524)
				(type default)
			)
			(layer "B.SilkS")
		)
		(fp_line
			(start -0.67945 0.3048)
			(end -0.120396 0.3048)
			(stroke
				(width 0.1)
				(type default)
			)
			(layer "B.Fab")
		)
		(fp_line
			(start -0.120396 0.3048)
			(end -0.120396 0.2794)
			(stroke
				(width 0.1)
				(type default)
			)
			(layer "B.Fab")
		)
		(fp_line
			(start 0.12065 0.3048)
			(end 0.67945 0.3048)
			(stroke
				(width 0.1)
				(type default)
			)
			(layer "B.Fab")
		)
		(fp_line
			(start 0.67945 0.3048)
			(end 0.67945 -0.305054)
			(stroke
				(width 0.1)
				(type default)
			)
			(layer "B.Fab")
		)
		(fp_line
			(start -0.120396 0.2794)
			(end 0.12065 0.2794)
			(stroke
				(width 0.1)
				(type default)
			)
			(layer "B.Fab")
		)
		(fp_line
			(start 0.12065 0.2794)
			(end 0.12065 0.3048)
			(stroke
				(width 0.1)
				(type default)
			)
			(layer "B.Fab")
		)
		(fp_line
			(start -0.12065 -0.2794)
			(end -0.12065 -0.3048)
			(stroke
				(width 0.1)
				(type default)
			)
			(layer "B.Fab")
		)
		(fp_line
			(start 0.12065 -0.2794)
			(end -0.12065 -0.2794)
			(stroke
				(width 0.1)
				(type default)
			)
			(layer "B.Fab")
		)
		(fp_line
			(start -0.67945 -0.3048)
			(end -0.67945 0.3048)
			(stroke
				(width 0.1)
				(type default)
			)
			(layer "B.Fab")
		)
		(fp_line
			(start -0.12065 -0.3048)
			(end -0.67945 -0.3048)
			(stroke
				(width 0.1)
				(type default)
			)
			(layer "B.Fab")
		)
		(fp_line
			(start 0.12065 -0.305054)
			(end 0.12065 -0.2794)
			(stroke
				(width 0.1)
				(type default)
			)
			(layer "B.Fab")
		)
		(fp_line
			(start 0.67945 -0.305054)
			(end 0.12065 -0.305054)
			(stroke
				(width 0.1)
				(type default)
			)
			(layer "B.Fab")
		)
		(pad "1" smd circle
			(at 0.40005 0 90)
			(size 0 0)
			(layers "B.Cu" "B.Mask" "B.Paste")
			(net "P52V_HS1_ADR1")
		)
		(pad "2" smd circle
			(at -0.40005 0 90)
			(size 0 0)
			(layers "B.Cu" "B.Mask" "B.Paste")
			(net "GND_FIELD_SIGNAL")
		)
	)
	(footprint ""
		(layer "B.Cu")
		(at 136.779 -77.597 180)
		(property "Reference" "C53"
			(at 0 0 0)
			(layer "B.SilkS")
			(hide yes)
			(effects
				(font
					(size 1.27 1.27)
				)
				(justify mirror)
			)
		)
		(property "Value" ""
			(at 0 0 0)
			(layer "B.Fab")
			(effects
				(font
					(size 1.27 1.27)
				)
				(justify mirror)
			)
		)
		(duplicate_pad_numbers_are_jumpers no)
		(fp_line
			(start 0.7874 0.4064)
			(end 0.7874 -0.4064)
			(stroke
				(width 0.1524)
				(type default)
			)
			(layer "B.SilkS")
		)
		(fp_line
			(start 0.7874 -0.4064)
			(end -0.7874 -0.4064)
			(stroke
				(width 0.1524)
				(type default)
			)
			(layer "B.SilkS")
		)
		(fp_line
			(start -0.7874 0.4064)
			(end 0.7874 0.4064)
			(stroke
				(width 0.1524)
				(type default)
			)
			(layer "B.SilkS")
		)
		(fp_line
			(start -0.7874 -0.4064)
			(end -0.7874 0.4064)
			(stroke
				(width 0.1524)
				(type default)
			)
			(layer "B.SilkS")
		)
		(fp_line
			(start 0.67945 0.3048)
			(end 0.67945 -0.305054)
			(stroke
				(width 0.1)
				(type default)
			)
			(layer "B.Fab")
		)
		(fp_line
			(start 0.67945 -0.305054)
			(end 0.12065 -0.305054)
			(stroke
				(width 0.1)
				(type default)
			)
			(layer "B.Fab")
		)
		(fp_line
			(start 0.12065 0.3048)
			(end 0.67945 0.3048)
			(stroke
				(width 0.1)
				(type default)
			)
			(layer "B.Fab")
		)
		(fp_line
			(start 0.12065 0.2794)
			(end 0.12065 0.3048)
			(stroke
				(width 0.1)
				(type default)
			)
			(layer "B.Fab")
		)
		(fp_line
			(start 0.12065 -0.2794)
			(end -0.12065 -0.2794)
			(stroke
				(width 0.1)
				(type default)
			)
			(layer "B.Fab")
		)
		(fp_line
			(start 0.12065 -0.305054)
			(end 0.12065 -0.2794)
			(stroke
				(width 0.1)
				(type default)
			)
			(layer "B.Fab")
		)
		(fp_line
			(start -0.120396 0.3048)
			(end -0.120396 0.2794)
			(stroke
				(width 0.1)
				(type default)
			)
			(layer "B.Fab")
		)
		(fp_line
			(start -0.120396 0.2794)
			(end 0.12065 0.2794)
			(stroke
				(width 0.1)
				(type default)
			)
			(layer "B.Fab")
		)
		(fp_line
			(start -0.12065 -0.2794)
			(end -0.12065 -0.3048)
			(stroke
				(width 0.1)
				(type default)
			)
			(layer "B.Fab")
		)
		(fp_line
			(start -0.12065 -0.3048)
			(end -0.67945 -0.3048)
			(stroke
				(width 0.1)
				(type default)
			)
			(layer "B.Fab")
		)
		(fp_line
			(start -0.67945 0.3048)
			(end -0.120396 0.3048)
			(stroke
				(width 0.1)
				(type default)
			)
			(layer "B.Fab")
		)
		(fp_line
			(start -0.67945 -0.3048)
			(end -0.67945 0.3048)
			(stroke
				(width 0.1)
				(type default)
			)
			(layer "B.Fab")
		)
		(pad "1" smd circle
			(at 0.40005 0)
			(size 0 0)
			(layers "B.Cu" "B.Mask" "B.Paste")
			(net "P12V_BRICK0_ALERT_N")
		)
		(pad "2" smd circle
			(at -0.40005 0)
			(size 0 0)
			(layers "B.Cu" "B.Mask" "B.Paste")
			(net "GND")
		)
	)
	(footprint ""
		(layer "B.Cu")
		(at 35.56 -105.283)
		(property "Reference" "R5873"
			(at 3.9878 -2.479548 0)
			(unlocked yes)
			(layer "B.SilkS")
			(effects
				(font
					(size 0.7874 0.5842)
					(thickness 0.1524)
				)
				(justify left mirror)
			)
		)
		(property "Value" ""
			(at 0 0 0)
			(layer "B.Fab")
			(effects
				(font
					(size 1.27 1.27)
				)
				(justify mirror)
			)
		)
		(duplicate_pad_numbers_are_jumpers no)
		(fp_line
			(start -4.0386 -1.7526)
			(end -4.0386 1.7526)
			(stroke
				(width 0.1524)
				(type default)
			)
			(layer "B.SilkS")
		)
		(fp_line
			(start -4.0386 1.7526)
			(end 4.0386 1.7526)
			(stroke
				(width 0.1524)
				(type default)
			)
			(layer "B.SilkS")
		)
		(fp_line
			(start 4.0386 -1.7526)
			(end -4.0386 -1.7526)
			(stroke
				(width 0.1524)
				(type default)
			)
			(layer "B.SilkS")
		)
		(fp_line
			(start 4.0386 1.7526)
			(end 4.0386 -1.7526)
			(stroke
				(width 0.1524)
				(type default)
			)
			(layer "B.SilkS")
		)
		(fp_line
			(start -4.0386 -1.7526)
			(end -4.0386 1.7526)
			(stroke
				(width 0.1)
				(type default)
			)
			(layer "B.Fab")
		)
		(fp_line
			(start -4.0386 1.7526)
			(end 4.0386 1.7526)
			(stroke
				(width 0.1)
				(type default)
			)
			(layer "B.Fab")
		)
		(fp_line
			(start 4.0386 -1.7526)
			(end -4.0386 -1.7526)
			(stroke
				(width 0.1)
				(type default)
			)
			(layer "B.Fab")
		)
		(fp_line
			(start 4.0386 1.7526)
			(end 4.0386 -1.7526)
			(stroke
				(width 0.1)
				(type default)
			)
			(layer "B.Fab")
		)
		(pad "1" smd circle
			(at 3.700018 0 270)
			(size 0 0)
			(layers "B.Cu" "B.Mask" "B.Paste")
			(net "P52V_HS")
		)
		(pad "2" smd circle
			(at -3.700018 0 90)
			(size 0 0)
			(layers "B.Cu" "B.Mask" "B.Paste")
			(net "P52V_FAN")
		)
		(pad "3" smd rect
			(at 2.70002 0 90)
			(size 0.4064 1.1176)
			(layers "B.Cu" "B.Mask" "B.Paste")
			(net "P52V_HS")
		)
		(pad "4" smd rect
			(at -2.70002 0 90)
			(size 0.4064 1.1176)
			(layers "B.Cu" "B.Mask" "B.Paste")
			(net "P52V_FAN")
		)
	)
	(footprint ""
		(layer "B.Cu")
		(at 139.065 -77.597 180)
		(property "Reference" "C54"
			(at 0 0 0)
			(layer "B.SilkS")
			(hide yes)
			(effects
				(font
					(size 1.27 1.27)
				)
				(justify mirror)
			)
		)
		(property "Value" ""
			(at 0 0 0)
			(layer "B.Fab")
			(effects
				(font
					(size 1.27 1.27)
				)
				(justify mirror)
			)
		)
		(duplicate_pad_numbers_are_jumpers no)
		(fp_line
			(start 0.7874 0.4064)
			(end 0.7874 -0.4064)
			(stroke
				(width 0.1524)
				(type default)
			)
			(layer "B.SilkS")
		)
		(fp_line
			(start 0.7874 -0.4064)
			(end -0.7874 -0.4064)
			(stroke
				(width 0.1524)
				(type default)
			)
			(layer "B.SilkS")
		)
		(fp_line
			(start -0.7874 0.4064)
			(end 0.7874 0.4064)
			(stroke
				(width 0.1524)
				(type default)
			)
			(layer "B.SilkS")
		)
		(fp_line
			(start -0.7874 -0.4064)
			(end -0.7874 0.4064)
			(stroke
				(width 0.1524)
				(type default)
			)
			(layer "B.SilkS")
		)
		(fp_line
			(start 0.67945 0.3048)
			(end 0.67945 -0.305054)
			(stroke
				(width 0.1)
				(type default)
			)
			(layer "B.Fab")
		)
		(fp_line
			(start 0.67945 -0.305054)
			(end 0.12065 -0.305054)
			(stroke
				(width 0.1)
				(type default)
			)
			(layer "B.Fab")
		)
		(fp_line
			(start 0.12065 0.3048)
			(end 0.67945 0.3048)
			(stroke
				(width 0.1)
				(type default)
			)
			(layer "B.Fab")
		)
		(fp_line
			(start 0.12065 0.2794)
			(end 0.12065 0.3048)
			(stroke
				(width 0.1)
				(type default)
			)
			(layer "B.Fab")
		)
		(fp_line
			(start 0.12065 -0.2794)
			(end -0.12065 -0.2794)
			(stroke
				(width 0.1)
				(type default)
			)
			(layer "B.Fab")
		)
		(fp_line
			(start 0.12065 -0.305054)
			(end 0.12065 -0.2794)
			(stroke
				(width 0.1)
				(type default)
			)
			(layer "B.Fab")
		)
		(fp_line
			(start -0.120396 0.3048)
			(end -0.120396 0.2794)
			(stroke
				(width 0.1)
				(type default)
			)
			(layer "B.Fab")
		)
		(fp_line
			(start -0.120396 0.2794)
			(end 0.12065 0.2794)
			(stroke
				(width 0.1)
				(type default)
			)
			(layer "B.Fab")
		)
		(fp_line
			(start -0.12065 -0.2794)
			(end -0.12065 -0.3048)
			(stroke
				(width 0.1)
				(type default)
			)
			(layer "B.Fab")
		)
		(fp_line
			(start -0.12065 -0.3048)
			(end -0.67945 -0.3048)
			(stroke
				(width 0.1)
				(type default)
			)
			(layer "B.Fab")
		)
		(fp_line
			(start -0.67945 0.3048)
			(end -0.120396 0.3048)
			(stroke
				(width 0.1)
				(type default)
			)
			(layer "B.Fab")
		)
		(fp_line
			(start -0.67945 -0.3048)
			(end -0.67945 0.3048)
			(stroke
				(width 0.1)
				(type default)
			)
			(layer "B.Fab")
		)
		(pad "1" smd circle
			(at 0.40005 0)
			(size 0 0)
			(layers "B.Cu" "B.Mask" "B.Paste")
			(net "SMB_P52V_VPDB_SCL")
		)
		(pad "2" smd circle
			(at -0.40005 0)
			(size 0 0)
			(layers "B.Cu" "B.Mask" "B.Paste")
			(net "GND")
		)
	)
	(footprint ""
		(layer "B.Cu")
		(at 212.344 -83.312)
		(property "Reference" "R28"
			(at 0 0 0)
			(layer "B.SilkS")
			(hide yes)
			(effects
				(font
					(size 1.27 1.27)
				)
				(justify mirror)
			)
		)
		(property "Value" ""
			(at 0 0 0)
			(layer "B.Fab")
			(effects
				(font
					(size 1.27 1.27)
				)
				(justify mirror)
			)
		)
		(duplicate_pad_numbers_are_jumpers no)
		(fp_line
			(start -0.7874 -0.4064)
			(end -0.7874 0.4064)
			(stroke
				(width 0.1524)
				(type default)
			)
			(layer "B.SilkS")
		)
		(fp_line
			(start -0.7874 0.4064)
			(end 0.7874 0.4064)
			(stroke
				(width 0.1524)
				(type default)
			)
			(layer "B.SilkS")
		)
		(fp_line
			(start 0.7874 -0.4064)
			(end -0.7874 -0.4064)
			(stroke
				(width 0.1524)
				(type default)
			)
			(layer "B.SilkS")
		)
		(fp_line
			(start 0.7874 0.4064)
			(end 0.7874 -0.4064)
			(stroke
				(width 0.1524)
				(type default)
			)
			(layer "B.SilkS")
		)
		(fp_line
			(start -0.67945 -0.3048)
			(end -0.67945 0.3048)
			(stroke
				(width 0.1)
				(type default)
			)
			(layer "B.Fab")
		)
		(fp_line
			(start -0.67945 0.3048)
			(end -0.120396 0.3048)
			(stroke
				(width 0.1)
				(type default)
			)
			(layer "B.Fab")
		)
		(fp_line
			(start -0.12065 -0.3048)
			(end -0.67945 -0.3048)
			(stroke
				(width 0.1)
				(type default)
			)
			(layer "B.Fab")
		)
		(fp_line
			(start -0.12065 -0.2794)
			(end -0.12065 -0.3048)
			(stroke
				(width 0.1)
				(type default)
			)
			(layer "B.Fab")
		)
		(fp_line
			(start -0.120396 0.2794)
			(end 0.12065 0.2794)
			(stroke
				(width 0.1)
				(type default)
			)
			(layer "B.Fab")
		)
		(fp_line
			(start -0.120396 0.3048)
			(end -0.120396 0.2794)
			(stroke
				(width 0.1)
				(type default)
			)
			(layer "B.Fab")
		)
		(fp_line
			(start 0.12065 -0.305054)
			(end 0.12065 -0.2794)
			(stroke
				(width 0.1)
				(type default)
			)
			(layer "B.Fab")
		)
		(fp_line
			(start 0.12065 -0.2794)
			(end -0.12065 -0.2794)
			(stroke
				(width 0.1)
				(type default)
			)
			(layer "B.Fab")
		)
		(fp_line
			(start 0.12065 0.2794)
			(end 0.12065 0.3048)
			(stroke
				(width 0.1)
				(type default)
			)
			(layer "B.Fab")
		)
		(fp_line
			(start 0.12065 0.3048)
			(end 0.67945 0.3048)
			(stroke
				(width 0.1)
				(type default)
			)
			(layer "B.Fab")
		)
		(fp_line
			(start 0.67945 -0.305054)
			(end 0.12065 -0.305054)
			(stroke
				(width 0.1)
				(type default)
			)
			(layer "B.Fab")
		)
		(fp_line
			(start 0.67945 0.3048)
			(end 0.67945 -0.305054)
			(stroke
				(width 0.1)
				(type default)
			)
			(layer "B.Fab")
		)
		(pad "1" smd circle
			(at 0.40005 0 180)
			(size 0 0)
			(layers "B.Cu" "B.Mask" "B.Paste")
			(net "P3V3_AUX")
		)
		(pad "2" smd circle
			(at -0.40005 0 180)
			(size 0 0)
			(layers "B.Cu" "B.Mask" "B.Paste")
			(net "PWRGD_GPU_HSC")
		)
	)
	(footprint ""
		(layer "B.Cu")
		(at 266.192 -33.9344)
		(property "Reference" "PR214"
			(at 0 0 0)
			(layer "B.SilkS")
			(hide yes)
			(effects
				(font
					(size 1.27 1.27)
				)
				(justify mirror)
			)
		)
		(property "Value" ""
			(at 0 0 0)
			(layer "B.Fab")
			(effects
				(font
					(size 1.27 1.27)
				)
				(justify mirror)
			)
		)
		(duplicate_pad_numbers_are_jumpers no)
		(fp_line
			(start -0.7874 -0.4064)
			(end -0.7874 0.4064)
			(stroke
				(width 0.1524)
				(type default)
			)
			(layer "B.SilkS")
		)
		(fp_line
			(start -0.7874 0.4064)
			(end 0.7874 0.4064)
			(stroke
				(width 0.1524)
				(type default)
			)
			(layer "B.SilkS")
		)
		(fp_line
			(start 0.7874 -0.4064)
			(end -0.7874 -0.4064)
			(stroke
				(width 0.1524)
				(type default)
			)
			(layer "B.SilkS")
		)
		(fp_line
			(start 0.7874 0.4064)
			(end 0.7874 -0.4064)
			(stroke
				(width 0.1524)
				(type default)
			)
			(layer "B.SilkS")
		)
		(fp_line
			(start -0.67945 -0.3048)
			(end -0.67945 0.3048)
			(stroke
				(width 0.1)
				(type default)
			)
			(layer "B.Fab")
		)
		(fp_line
			(start -0.67945 0.3048)
			(end -0.120396 0.3048)
			(stroke
				(width 0.1)
				(type default)
			)
			(layer "B.Fab")
		)
		(fp_line
			(start -0.12065 -0.3048)
			(end -0.67945 -0.3048)
			(stroke
				(width 0.1)
				(type default)
			)
			(layer "B.Fab")
		)
		(fp_line
			(start -0.12065 -0.2794)
			(end -0.12065 -0.3048)
			(stroke
				(width 0.1)
				(type default)
			)
			(layer "B.Fab")
		)
		(fp_line
			(start -0.120396 0.2794)
			(end 0.12065 0.2794)
			(stroke
				(width 0.1)
				(type default)
			)
			(layer "B.Fab")
		)
		(fp_line
			(start -0.120396 0.3048)
			(end -0.120396 0.2794)
			(stroke
				(width 0.1)
				(type default)
			)
			(layer "B.Fab")
		)
		(fp_line
			(start 0.12065 -0.305054)
			(end 0.12065 -0.2794)
			(stroke
				(width 0.1)
				(type default)
			)
			(layer "B.Fab")
		)
		(fp_line
			(start 0.12065 -0.2794)
			(end -0.12065 -0.2794)
			(stroke
				(width 0.1)
				(type default)
			)
			(layer "B.Fab")
		)
		(fp_line
			(start 0.12065 0.2794)
			(end 0.12065 0.3048)
			(stroke
				(width 0.1)
				(type default)
			)
			(layer "B.Fab")
		)
		(fp_line
			(start 0.12065 0.3048)
			(end 0.67945 0.3048)
			(stroke
				(width 0.1)
				(type default)
			)
			(layer "B.Fab")
		)
		(fp_line
			(start 0.67945 -0.305054)
			(end 0.12065 -0.305054)
			(stroke
				(width 0.1)
				(type default)
			)
			(layer "B.Fab")
		)
		(fp_line
			(start 0.67945 0.3048)
			(end 0.67945 -0.305054)
			(stroke
				(width 0.1)
				(type default)
			)
			(layer "B.Fab")
		)
		(pad "1" smd circle
			(at 0.40005 0 180)
			(size 0 0)
			(layers "B.Cu" "B.Mask" "B.Paste")
			(net "P52V_HS1_MODE")
		)
		(pad "2" smd circle
			(at -0.40005 0 180)
			(size 0 0)
			(layers "B.Cu" "B.Mask" "B.Paste")
			(net "P52V_HS1_INTVCC")
		)
	)
	(footprint ""
		(layer "B.Cu")
		(at 94.361 -78.613)
		(property "Reference" "R175"
			(at 0 0 0)
			(layer "B.SilkS")
			(hide yes)
			(effects
				(font
					(size 1.27 1.27)
				)
				(justify mirror)
			)
		)
		(property "Value" ""
			(at 0 0 0)
			(layer "B.Fab")
			(effects
				(font
					(size 1.27 1.27)
				)
				(justify mirror)
			)
		)
		(duplicate_pad_numbers_are_jumpers no)
		(fp_line
			(start -0.7874 -0.4064)
			(end -0.7874 0.4064)
			(stroke
				(width 0.1524)
				(type default)
			)
			(layer "B.SilkS")
		)
		(fp_line
			(start -0.7874 0.4064)
			(end 0.7874 0.4064)
			(stroke
				(width 0.1524)
				(type default)
			)
			(layer "B.SilkS")
		)
		(fp_line
			(start 0.7874 -0.4064)
			(end -0.7874 -0.4064)
			(stroke
				(width 0.1524)
				(type default)
			)
			(layer "B.SilkS")
		)
		(fp_line
			(start 0.7874 0.4064)
			(end 0.7874 -0.4064)
			(stroke
				(width 0.1524)
				(type default)
			)
			(layer "B.SilkS")
		)
		(fp_line
			(start -0.67945 -0.3048)
			(end -0.67945 0.3048)
			(stroke
				(width 0.1)
				(type default)
			)
			(layer "B.Fab")
		)
		(fp_line
			(start -0.67945 0.3048)
			(end -0.120396 0.3048)
			(stroke
				(width 0.1)
				(type default)
			)
			(layer "B.Fab")
		)
		(fp_line
			(start -0.12065 -0.3048)
			(end -0.67945 -0.3048)
			(stroke
				(width 0.1)
				(type default)
			)
			(layer "B.Fab")
		)
		(fp_line
			(start -0.12065 -0.2794)
			(end -0.12065 -0.3048)
			(stroke
				(width 0.1)
				(type default)
			)
			(layer "B.Fab")
		)
		(fp_line
			(start -0.120396 0.2794)
			(end 0.12065 0.2794)
			(stroke
				(width 0.1)
				(type default)
			)
			(layer "B.Fab")
		)
		(fp_line
			(start -0.120396 0.3048)
			(end -0.120396 0.2794)
			(stroke
				(width 0.1)
				(type default)
			)
			(layer "B.Fab")
		)
		(fp_line
			(start 0.12065 -0.305054)
			(end 0.12065 -0.2794)
			(stroke
				(width 0.1)
				(type default)
			)
			(layer "B.Fab")
		)
		(fp_line
			(start 0.12065 -0.2794)
			(end -0.12065 -0.2794)
			(stroke
				(width 0.1)
				(type default)
			)
			(layer "B.Fab")
		)
		(fp_line
			(start 0.12065 0.2794)
			(end 0.12065 0.3048)
			(stroke
				(width 0.1)
				(type default)
			)
			(layer "B.Fab")
		)
		(fp_line
			(start 0.12065 0.3048)
			(end 0.67945 0.3048)
			(stroke
				(width 0.1)
				(type default)
			)
			(layer "B.Fab")
		)
		(fp_line
			(start 0.67945 -0.305054)
			(end 0.12065 -0.305054)
			(stroke
				(width 0.1)
				(type default)
			)
			(layer "B.Fab")
		)
		(fp_line
			(start 0.67945 0.3048)
			(end 0.67945 -0.305054)
			(stroke
				(width 0.1)
				(type default)
			)
			(layer "B.Fab")
		)
		(pad "1" smd circle
			(at 0.40005 0 180)
			(size 0 0)
			(layers "B.Cu" "B.Mask" "B.Paste")
			(net "P3V3_AUX")
		)
		(pad "2" smd circle
			(at -0.40005 0 180)
			(size 0 0)
			(layers "B.Cu" "B.Mask" "B.Paste")
			(net "P12V_BRICK1_ALERT_N")
		)
	)
	(footprint ""
		(layer "B.Cu")
		(at 139.065 -76.327 180)
		(property "Reference" "R166"
			(at 0 0 0)
			(layer "B.SilkS")
			(hide yes)
			(effects
				(font
					(size 1.27 1.27)
				)
				(justify mirror)
			)
		)
		(property "Value" ""
			(at 0 0 0)
			(layer "B.Fab")
			(effects
				(font
					(size 1.27 1.27)
				)
				(justify mirror)
			)
		)
		(duplicate_pad_numbers_are_jumpers no)
		(fp_line
			(start 0.7874 0.4064)
			(end 0.7874 -0.4064)
			(stroke
				(width 0.1524)
				(type default)
			)
			(layer "B.SilkS")
		)
		(fp_line
			(start 0.7874 -0.4064)
			(end -0.7874 -0.4064)
			(stroke
				(width 0.1524)
				(type default)
			)
			(layer "B.SilkS")
		)
		(fp_line
			(start -0.7874 0.4064)
			(end 0.7874 0.4064)
			(stroke
				(width 0.1524)
				(type default)
			)
			(layer "B.SilkS")
		)
		(fp_line
			(start -0.7874 -0.4064)
			(end -0.7874 0.4064)
			(stroke
				(width 0.1524)
				(type default)
			)
			(layer "B.SilkS")
		)
		(fp_line
			(start 0.67945 0.3048)
			(end 0.67945 -0.305054)
			(stroke
				(width 0.1)
				(type default)
			)
			(layer "B.Fab")
		)
		(fp_line
			(start 0.67945 -0.305054)
			(end 0.12065 -0.305054)
			(stroke
				(width 0.1)
				(type default)
			)
			(layer "B.Fab")
		)
		(fp_line
			(start 0.12065 0.3048)
			(end 0.67945 0.3048)
			(stroke
				(width 0.1)
				(type default)
			)
			(layer "B.Fab")
		)
		(fp_line
			(start 0.12065 0.2794)
			(end 0.12065 0.3048)
			(stroke
				(width 0.1)
				(type default)
			)
			(layer "B.Fab")
		)
		(fp_line
			(start 0.12065 -0.2794)
			(end -0.12065 -0.2794)
			(stroke
				(width 0.1)
				(type default)
			)
			(layer "B.Fab")
		)
		(fp_line
			(start 0.12065 -0.305054)
			(end 0.12065 -0.2794)
			(stroke
				(width 0.1)
				(type default)
			)
			(layer "B.Fab")
		)
		(fp_line
			(start -0.120396 0.3048)
			(end -0.120396 0.2794)
			(stroke
				(width 0.1)
				(type default)
			)
			(layer "B.Fab")
		)
		(fp_line
			(start -0.120396 0.2794)
			(end 0.12065 0.2794)
			(stroke
				(width 0.1)
				(type default)
			)
			(layer "B.Fab")
		)
		(fp_line
			(start -0.12065 -0.2794)
			(end -0.12065 -0.3048)
			(stroke
				(width 0.1)
				(type default)
			)
			(layer "B.Fab")
		)
		(fp_line
			(start -0.12065 -0.3048)
			(end -0.67945 -0.3048)
			(stroke
				(width 0.1)
				(type default)
			)
			(layer "B.Fab")
		)
		(fp_line
			(start -0.67945 0.3048)
			(end -0.120396 0.3048)
			(stroke
				(width 0.1)
				(type default)
			)
			(layer "B.Fab")
		)
		(fp_line
			(start -0.67945 -0.3048)
			(end -0.67945 0.3048)
			(stroke
				(width 0.1)
				(type default)
			)
			(layer "B.Fab")
		)
		(pad "1" smd circle
			(at 0.40005 0)
			(size 0 0)
			(layers "B.Cu" "B.Mask" "B.Paste")
			(net "SMB_P52V_VPDB_SCL")
		)
		(pad "2" smd circle
			(at -0.40005 0)
			(size 0 0)
			(layers "B.Cu" "B.Mask" "B.Paste")
			(net "SMB_BRICK0_SCL")
		)
	)
	(footprint ""
		(layer "B.Cu")
		(at 238.555784 -78.96479 180)
		(property "Reference" "R2"
			(at 0 0 0)
			(layer "B.SilkS")
			(hide yes)
			(effects
				(font
					(size 1.27 1.27)
				)
				(justify mirror)
			)
		)
		(property "Value" ""
			(at 0 0 0)
			(layer "B.Fab")
			(effects
				(font
					(size 1.27 1.27)
				)
				(justify mirror)
			)
		)
		(duplicate_pad_numbers_are_jumpers no)
		(fp_line
			(start 0.7874 0.4064)
			(end 0.7874 -0.4064)
			(stroke
				(width 0.1524)
				(type default)
			)
			(layer "B.SilkS")
		)
		(fp_line
			(start 0.7874 -0.4064)
			(end -0.7874 -0.4064)
			(stroke
				(width 0.1524)
				(type default)
			)
			(layer "B.SilkS")
		)
		(fp_line
			(start -0.7874 0.4064)
			(end 0.7874 0.4064)
			(stroke
				(width 0.1524)
				(type default)
			)
			(layer "B.SilkS")
		)
		(fp_line
			(start -0.7874 -0.4064)
			(end -0.7874 0.4064)
			(stroke
				(width 0.1524)
				(type default)
			)
			(layer "B.SilkS")
		)
		(fp_line
			(start 0.67945 0.3048)
			(end 0.67945 -0.305054)
			(stroke
				(width 0.1)
				(type default)
			)
			(layer "B.Fab")
		)
		(fp_line
			(start 0.67945 -0.305054)
			(end 0.12065 -0.305054)
			(stroke
				(width 0.1)
				(type default)
			)
			(layer "B.Fab")
		)
		(fp_line
			(start 0.12065 0.3048)
			(end 0.67945 0.3048)
			(stroke
				(width 0.1)
				(type default)
			)
			(layer "B.Fab")
		)
		(fp_line
			(start 0.12065 0.2794)
			(end 0.12065 0.3048)
			(stroke
				(width 0.1)
				(type default)
			)
			(layer "B.Fab")
		)
		(fp_line
			(start 0.12065 -0.2794)
			(end -0.12065 -0.2794)
			(stroke
				(width 0.1)
				(type default)
			)
			(layer "B.Fab")
		)
		(fp_line
			(start 0.12065 -0.305054)
			(end 0.12065 -0.2794)
			(stroke
				(width 0.1)
				(type default)
			)
			(layer "B.Fab")
		)
		(fp_line
			(start -0.120396 0.3048)
			(end -0.120396 0.2794)
			(stroke
				(width 0.1)
				(type default)
			)
			(layer "B.Fab")
		)
		(fp_line
			(start -0.120396 0.2794)
			(end 0.12065 0.2794)
			(stroke
				(width 0.1)
				(type default)
			)
			(layer "B.Fab")
		)
		(fp_line
			(start -0.12065 -0.2794)
			(end -0.12065 -0.3048)
			(stroke
				(width 0.1)
				(type default)
			)
			(layer "B.Fab")
		)
		(fp_line
			(start -0.12065 -0.3048)
			(end -0.67945 -0.3048)
			(stroke
				(width 0.1)
				(type default)
			)
			(layer "B.Fab")
		)
		(fp_line
			(start -0.67945 0.3048)
			(end -0.120396 0.3048)
			(stroke
				(width 0.1)
				(type default)
			)
			(layer "B.Fab")
		)
		(fp_line
			(start -0.67945 -0.3048)
			(end -0.67945 0.3048)
			(stroke
				(width 0.1)
				(type default)
			)
			(layer "B.Fab")
		)
		(pad "1" smd circle
			(at 0.40005 0)
			(size 0 0)
			(layers "B.Cu" "B.Mask" "B.Paste")
			(net "SMB_PDB_MISC_SDA_R")
		)
		(pad "2" smd circle
			(at -0.40005 0)
			(size 0 0)
			(layers "B.Cu" "B.Mask" "B.Paste")
			(net "P3V3_AUX")
		)
	)
	(footprint ""
		(layer "B.Cu")
		(at 235.204 -70.993 90)
		(property "Reference" "R199"
			(at 0 0 90)
			(layer "B.SilkS")
			(hide yes)
			(effects
				(font
					(size 1.27 1.27)
				)
				(justify mirror)
			)
		)
		(property "Value" ""
			(at 0 0 90)
			(layer "B.Fab")
			(effects
				(font
					(size 1.27 1.27)
				)
				(justify mirror)
			)
		)
		(duplicate_pad_numbers_are_jumpers no)
		(fp_line
			(start 0.7874 -0.4064)
			(end -0.7874 -0.4064)
			(stroke
				(width 0.1524)
				(type default)
			)
			(layer "B.SilkS")
		)
		(fp_line
			(start -0.7874 -0.4064)
			(end -0.7874 0.4064)
			(stroke
				(width 0.1524)
				(type default)
			)
			(layer "B.SilkS")
		)
		(fp_line
			(start 0.7874 0.4064)
			(end 0.7874 -0.4064)
			(stroke
				(width 0.1524)
				(type default)
			)
			(layer "B.SilkS")
		)
		(fp_line
			(start -0.7874 0.4064)
			(end 0.7874 0.4064)
			(stroke
				(width 0.1524)
				(type default)
			)
			(layer "B.SilkS")
		)
		(fp_line
			(start 0.67945 -0.305054)
			(end 0.12065 -0.305054)
			(stroke
				(width 0.1)
				(type default)
			)
			(layer "B.Fab")
		)
		(fp_line
			(start 0.12065 -0.305054)
			(end 0.12065 -0.2794)
			(stroke
				(width 0.1)
				(type default)
			)
			(layer "B.Fab")
		)
		(fp_line
			(start -0.12065 -0.3048)
			(end -0.67945 -0.3048)
			(stroke
				(width 0.1)
				(type default)
			)
			(layer "B.Fab")
		)
		(fp_line
			(start -0.67945 -0.3048)
			(end -0.67945 0.3048)
			(stroke
				(width 0.1)
				(type default)
			)
			(layer "B.Fab")
		)
		(fp_line
			(start 0.12065 -0.2794)
			(end -0.12065 -0.2794)
			(stroke
				(width 0.1)
				(type default)
			)
			(layer "B.Fab")
		)
		(fp_line
			(start -0.12065 -0.2794)
			(end -0.12065 -0.3048)
			(stroke
				(width 0.1)
				(type default)
			)
			(layer "B.Fab")
		)
		(fp_line
			(start 0.12065 0.2794)
			(end 0.12065 0.3048)
			(stroke
				(width 0.1)
				(type default)
			)
			(layer "B.Fab")
		)
		(fp_line
			(start -0.120396 0.2794)
			(end 0.12065 0.2794)
			(stroke
				(width 0.1)
				(type default)
			)
			(layer "B.Fab")
		)
		(fp_line
			(start 0.67945 0.3048)
			(end 0.67945 -0.305054)
			(stroke
				(width 0.1)
				(type default)
			)
			(layer "B.Fab")
		)
		(fp_line
			(start 0.12065 0.3048)
			(end 0.67945 0.3048)
			(stroke
				(width 0.1)
				(type default)
			)
			(layer "B.Fab")
		)
		(fp_line
			(start -0.120396 0.3048)
			(end -0.120396 0.2794)
			(stroke
				(width 0.1)
				(type default)
			)
			(layer "B.Fab")
		)
		(fp_line
			(start -0.67945 0.3048)
			(end -0.120396 0.3048)
			(stroke
				(width 0.1)
				(type default)
			)
			(layer "B.Fab")
		)
		(pad "1" smd circle
			(at 0.40005 0 270)
			(size 0 0)
			(layers "B.Cu" "B.Mask" "B.Paste")
			(net "P3V3_AUX")
		)
		(pad "2" smd circle
			(at -0.40005 0 270)
			(size 0 0)
			(layers "B.Cu" "B.Mask" "B.Paste")
			(net "P3V3_AUX_SCALED")
		)
	)
	(footprint ""
		(layer "B.Cu")
		(at 172.850302 -76.708 -90)
		(property "Reference" "PR319"
			(at 0 0 90)
			(layer "B.SilkS")
			(hide yes)
			(effects
				(font
					(size 1.27 1.27)
				)
				(justify mirror)
			)
		)
		(property "Value" ""
			(at 0 0 90)
			(layer "B.Fab")
			(effects
				(font
					(size 1.27 1.27)
				)
				(justify mirror)
			)
		)
		(duplicate_pad_numbers_are_jumpers no)
		(fp_line
			(start -0.7874 0.4064)
			(end 0.7874 0.4064)
			(stroke
				(width 0.1524)
				(type default)
			)
			(layer "B.SilkS")
		)
		(fp_line
			(start 0.7874 0.4064)
			(end 0.7874 -0.4064)
			(stroke
				(width 0.1524)
				(type default)
			)
			(layer "B.SilkS")
		)
		(fp_line
			(start -0.7874 -0.4064)
			(end -0.7874 0.4064)
			(stroke
				(width 0.1524)
				(type default)
			)
			(layer "B.SilkS")
		)
		(fp_line
			(start 0.7874 -0.4064)
			(end -0.7874 -0.4064)
			(stroke
				(width 0.1524)
				(type default)
			)
			(layer "B.SilkS")
		)
		(fp_line
			(start -0.67945 0.3048)
			(end -0.120396 0.3048)
			(stroke
				(width 0.1)
				(type default)
			)
			(layer "B.Fab")
		)
		(fp_line
			(start -0.120396 0.3048)
			(end -0.120396 0.2794)
			(stroke
				(width 0.1)
				(type default)
			)
			(layer "B.Fab")
		)
		(fp_line
			(start 0.12065 0.3048)
			(end 0.67945 0.3048)
			(stroke
				(width 0.1)
				(type default)
			)
			(layer "B.Fab")
		)
		(fp_line
			(start 0.67945 0.3048)
			(end 0.67945 -0.305054)
			(stroke
				(width 0.1)
				(type default)
			)
			(layer "B.Fab")
		)
		(fp_line
			(start -0.120396 0.2794)
			(end 0.12065 0.2794)
			(stroke
				(width 0.1)
				(type default)
			)
			(layer "B.Fab")
		)
		(fp_line
			(start 0.12065 0.2794)
			(end 0.12065 0.3048)
			(stroke
				(width 0.1)
				(type default)
			)
			(layer "B.Fab")
		)
		(fp_line
			(start -0.12065 -0.2794)
			(end -0.12065 -0.3048)
			(stroke
				(width 0.1)
				(type default)
			)
			(layer "B.Fab")
		)
		(fp_line
			(start 0.12065 -0.2794)
			(end -0.12065 -0.2794)
			(stroke
				(width 0.1)
				(type default)
			)
			(layer "B.Fab")
		)
		(fp_line
			(start -0.67945 -0.3048)
			(end -0.67945 0.3048)
			(stroke
				(width 0.1)
				(type default)
			)
			(layer "B.Fab")
		)
		(fp_line
			(start -0.12065 -0.3048)
			(end -0.67945 -0.3048)
			(stroke
				(width 0.1)
				(type default)
			)
			(layer "B.Fab")
		)
		(fp_line
			(start 0.12065 -0.305054)
			(end 0.12065 -0.2794)
			(stroke
				(width 0.1)
				(type default)
			)
			(layer "B.Fab")
		)
		(fp_line
			(start 0.67945 -0.305054)
			(end 0.12065 -0.305054)
			(stroke
				(width 0.1)
				(type default)
			)
			(layer "B.Fab")
		)
		(pad "1" smd circle
			(at 0.40005 0 90)
			(size 0 0)
			(layers "B.Cu" "B.Mask" "B.Paste")
			(net "P12V_MB2_SENSE-")
		)
		(pad "2" smd circle
			(at -0.40005 0 90)
			(size 0 0)
			(layers "B.Cu" "B.Mask" "B.Paste")
			(net "GND")
		)
	)
	(footprint ""
		(layer "B.Cu")
		(at 45.687996 -56.774842)
		(property "Reference" "C98"
			(at 0 0 0)
			(layer "B.SilkS")
			(hide yes)
			(effects
				(font
					(size 1.27 1.27)
				)
				(justify mirror)
			)
		)
		(property "Value" ""
			(at 0 0 0)
			(layer "B.Fab")
			(effects
				(font
					(size 1.27 1.27)
				)
				(justify mirror)
			)
		)
		(duplicate_pad_numbers_are_jumpers no)
		(fp_line
			(start -0.7874 -0.4064)
			(end -0.7874 0.4064)
			(stroke
				(width 0.1524)
				(type default)
			)
			(layer "B.SilkS")
		)
		(fp_line
			(start -0.7874 0.4064)
			(end 0.7874 0.4064)
			(stroke
				(width 0.1524)
				(type default)
			)
			(layer "B.SilkS")
		)
		(fp_line
			(start 0.7874 -0.4064)
			(end -0.7874 -0.4064)
			(stroke
				(width 0.1524)
				(type default)
			)
			(layer "B.SilkS")
		)
		(fp_line
			(start 0.7874 0.4064)
			(end 0.7874 -0.4064)
			(stroke
				(width 0.1524)
				(type default)
			)
			(layer "B.SilkS")
		)
		(fp_line
			(start -0.67945 -0.3048)
			(end -0.67945 0.3048)
			(stroke
				(width 0.1)
				(type default)
			)
			(layer "B.Fab")
		)
		(fp_line
			(start -0.67945 0.3048)
			(end -0.120396 0.3048)
			(stroke
				(width 0.1)
				(type default)
			)
			(layer "B.Fab")
		)
		(fp_line
			(start -0.12065 -0.3048)
			(end -0.67945 -0.3048)
			(stroke
				(width 0.1)
				(type default)
			)
			(layer "B.Fab")
		)
		(fp_line
			(start -0.12065 -0.2794)
			(end -0.12065 -0.3048)
			(stroke
				(width 0.1)
				(type default)
			)
			(layer "B.Fab")
		)
		(fp_line
			(start -0.120396 0.2794)
			(end 0.12065 0.2794)
			(stroke
				(width 0.1)
				(type default)
			)
			(layer "B.Fab")
		)
		(fp_line
			(start -0.120396 0.3048)
			(end -0.120396 0.2794)
			(stroke
				(width 0.1)
				(type default)
			)
			(layer "B.Fab")
		)
		(fp_line
			(start 0.12065 -0.305054)
			(end 0.12065 -0.2794)
			(stroke
				(width 0.1)
				(type default)
			)
			(layer "B.Fab")
		)
		(fp_line
			(start 0.12065 -0.2794)
			(end -0.12065 -0.2794)
			(stroke
				(width 0.1)
				(type default)
			)
			(layer "B.Fab")
		)
		(fp_line
			(start 0.12065 0.2794)
			(end 0.12065 0.3048)
			(stroke
				(width 0.1)
				(type default)
			)
			(layer "B.Fab")
		)
		(fp_line
			(start 0.12065 0.3048)
			(end 0.67945 0.3048)
			(stroke
				(width 0.1)
				(type default)
			)
			(layer "B.Fab")
		)
		(fp_line
			(start 0.67945 -0.305054)
			(end 0.12065 -0.305054)
			(stroke
				(width 0.1)
				(type default)
			)
			(layer "B.Fab")
		)
		(fp_line
			(start 0.67945 0.3048)
			(end 0.67945 -0.305054)
			(stroke
				(width 0.1)
				(type default)
			)
			(layer "B.Fab")
		)
		(pad "1" smd circle
			(at 0.40005 0 180)
			(size 0 0)
			(layers "B.Cu" "B.Mask" "B.Paste")
			(net "P12V_HPDB_0_ISET_R")
		)
		(pad "2" smd circle
			(at -0.40005 0 180)
			(size 0 0)
			(layers "B.Cu" "B.Mask" "B.Paste")
			(net "GND")
		)
	)
	(footprint ""
		(layer "B.Cu")
		(at 212.344 -69.723 -90)
		(property "Reference" "R91"
			(at 0 0 90)
			(layer "B.SilkS")
			(hide yes)
			(effects
				(font
					(size 1.27 1.27)
				)
				(justify mirror)
			)
		)
		(property "Value" ""
			(at 0 0 90)
			(layer "B.Fab")
			(effects
				(font
					(size 1.27 1.27)
				)
				(justify mirror)
			)
		)
		(duplicate_pad_numbers_are_jumpers no)
		(fp_line
			(start -0.7874 0.4064)
			(end 0.7874 0.4064)
			(stroke
				(width 0.1524)
				(type default)
			)
			(layer "B.SilkS")
		)
		(fp_line
			(start 0.7874 0.4064)
			(end 0.7874 -0.4064)
			(stroke
				(width 0.1524)
				(type default)
			)
			(layer "B.SilkS")
		)
		(fp_line
			(start -0.7874 -0.4064)
			(end -0.7874 0.4064)
			(stroke
				(width 0.1524)
				(type default)
			)
			(layer "B.SilkS")
		)
		(fp_line
			(start 0.7874 -0.4064)
			(end -0.7874 -0.4064)
			(stroke
				(width 0.1524)
				(type default)
			)
			(layer "B.SilkS")
		)
		(fp_line
			(start -0.67945 0.3048)
			(end -0.120396 0.3048)
			(stroke
				(width 0.1)
				(type default)
			)
			(layer "B.Fab")
		)
		(fp_line
			(start -0.120396 0.3048)
			(end -0.120396 0.2794)
			(stroke
				(width 0.1)
				(type default)
			)
			(layer "B.Fab")
		)
		(fp_line
			(start 0.12065 0.3048)
			(end 0.67945 0.3048)
			(stroke
				(width 0.1)
				(type default)
			)
			(layer "B.Fab")
		)
		(fp_line
			(start 0.67945 0.3048)
			(end 0.67945 -0.305054)
			(stroke
				(width 0.1)
				(type default)
			)
			(layer "B.Fab")
		)
		(fp_line
			(start -0.120396 0.2794)
			(end 0.12065 0.2794)
			(stroke
				(width 0.1)
				(type default)
			)
			(layer "B.Fab")
		)
		(fp_line
			(start 0.12065 0.2794)
			(end 0.12065 0.3048)
			(stroke
				(width 0.1)
				(type default)
			)
			(layer "B.Fab")
		)
		(fp_line
			(start -0.12065 -0.2794)
			(end -0.12065 -0.3048)
			(stroke
				(width 0.1)
				(type default)
			)
			(layer "B.Fab")
		)
		(fp_line
			(start 0.12065 -0.2794)
			(end -0.12065 -0.2794)
			(stroke
				(width 0.1)
				(type default)
			)
			(layer "B.Fab")
		)
		(fp_line
			(start -0.67945 -0.3048)
			(end -0.67945 0.3048)
			(stroke
				(width 0.1)
				(type default)
			)
			(layer "B.Fab")
		)
		(fp_line
			(start -0.12065 -0.3048)
			(end -0.67945 -0.3048)
			(stroke
				(width 0.1)
				(type default)
			)
			(layer "B.Fab")
		)
		(fp_line
			(start 0.12065 -0.305054)
			(end 0.12065 -0.2794)
			(stroke
				(width 0.1)
				(type default)
			)
			(layer "B.Fab")
		)
		(fp_line
			(start 0.67945 -0.305054)
			(end 0.12065 -0.305054)
			(stroke
				(width 0.1)
				(type default)
			)
			(layer "B.Fab")
		)
		(pad "1" smd circle
			(at 0.40005 0 90)
			(size 0 0)
			(layers "B.Cu" "B.Mask" "B.Paste")
			(net "P3V3_AUX")
		)
		(pad "2" smd circle
			(at -0.40005 0 90)
			(size 0 0)
			(layers "B.Cu" "B.Mask" "B.Paste")
			(net "SKU_ID_1")
		)
	)
	(footprint ""
		(layer "B.Cu")
		(at 238.682784 -88.36279)
		(property "Reference" "R6"
			(at 0 0 0)
			(layer "B.SilkS")
			(hide yes)
			(effects
				(font
					(size 1.27 1.27)
				)
				(justify mirror)
			)
		)
		(property "Value" ""
			(at 0 0 0)
			(layer "B.Fab")
			(effects
				(font
					(size 1.27 1.27)
				)
				(justify mirror)
			)
		)
		(duplicate_pad_numbers_are_jumpers no)
		(fp_line
			(start -0.7874 -0.4064)
			(end -0.7874 0.4064)
			(stroke
				(width 0.1524)
				(type default)
			)
			(layer "B.SilkS")
		)
		(fp_line
			(start -0.7874 0.4064)
			(end 0.7874 0.4064)
			(stroke
				(width 0.1524)
				(type default)
			)
			(layer "B.SilkS")
		)
		(fp_line
			(start 0.7874 -0.4064)
			(end -0.7874 -0.4064)
			(stroke
				(width 0.1524)
				(type default)
			)
			(layer "B.SilkS")
		)
		(fp_line
			(start 0.7874 0.4064)
			(end 0.7874 -0.4064)
			(stroke
				(width 0.1524)
				(type default)
			)
			(layer "B.SilkS")
		)
		(fp_line
			(start -0.67945 -0.3048)
			(end -0.67945 0.3048)
			(stroke
				(width 0.1)
				(type default)
			)
			(layer "B.Fab")
		)
		(fp_line
			(start -0.67945 0.3048)
			(end -0.120396 0.3048)
			(stroke
				(width 0.1)
				(type default)
			)
			(layer "B.Fab")
		)
		(fp_line
			(start -0.12065 -0.3048)
			(end -0.67945 -0.3048)
			(stroke
				(width 0.1)
				(type default)
			)
			(layer "B.Fab")
		)
		(fp_line
			(start -0.12065 -0.2794)
			(end -0.12065 -0.3048)
			(stroke
				(width 0.1)
				(type default)
			)
			(layer "B.Fab")
		)
		(fp_line
			(start -0.120396 0.2794)
			(end 0.12065 0.2794)
			(stroke
				(width 0.1)
				(type default)
			)
			(layer "B.Fab")
		)
		(fp_line
			(start -0.120396 0.3048)
			(end -0.120396 0.2794)
			(stroke
				(width 0.1)
				(type default)
			)
			(layer "B.Fab")
		)
		(fp_line
			(start 0.12065 -0.305054)
			(end 0.12065 -0.2794)
			(stroke
				(width 0.1)
				(type default)
			)
			(layer "B.Fab")
		)
		(fp_line
			(start 0.12065 -0.2794)
			(end -0.12065 -0.2794)
			(stroke
				(width 0.1)
				(type default)
			)
			(layer "B.Fab")
		)
		(fp_line
			(start 0.12065 0.2794)
			(end 0.12065 0.3048)
			(stroke
				(width 0.1)
				(type default)
			)
			(layer "B.Fab")
		)
		(fp_line
			(start 0.12065 0.3048)
			(end 0.67945 0.3048)
			(stroke
				(width 0.1)
				(type default)
			)
			(layer "B.Fab")
		)
		(fp_line
			(start 0.67945 -0.305054)
			(end 0.12065 -0.305054)
			(stroke
				(width 0.1)
				(type default)
			)
			(layer "B.Fab")
		)
		(fp_line
			(start 0.67945 0.3048)
			(end 0.67945 -0.305054)
			(stroke
				(width 0.1)
				(type default)
			)
			(layer "B.Fab")
		)
		(pad "1" smd circle
			(at 0.40005 0 180)
			(size 0 0)
			(layers "B.Cu" "B.Mask" "B.Paste")
			(net "SMB_MB_PDB_SCL")
		)
		(pad "2" smd circle
			(at -0.40005 0 180)
			(size 0 0)
			(layers "B.Cu" "B.Mask" "B.Paste")
			(net "SMB_PDB_MISC_SCL_R")
		)
	)
	(footprint ""
		(layer "B.Cu")
		(at 102.824534 -76.708 -90)
		(property "Reference" "PR65"
			(at 0 0 90)
			(layer "B.SilkS")
			(hide yes)
			(effects
				(font
					(size 1.27 1.27)
				)
				(justify mirror)
			)
		)
		(property "Value" ""
			(at 0 0 90)
			(layer "B.Fab")
			(effects
				(font
					(size 1.27 1.27)
				)
				(justify mirror)
			)
		)
		(duplicate_pad_numbers_are_jumpers no)
		(fp_line
			(start -0.7874 0.4064)
			(end 0.7874 0.4064)
			(stroke
				(width 0.1524)
				(type default)
			)
			(layer "B.SilkS")
		)
		(fp_line
			(start 0.7874 0.4064)
			(end 0.7874 -0.4064)
			(stroke
				(width 0.1524)
				(type default)
			)
			(layer "B.SilkS")
		)
		(fp_line
			(start -0.7874 -0.4064)
			(end -0.7874 0.4064)
			(stroke
				(width 0.1524)
				(type default)
			)
			(layer "B.SilkS")
		)
		(fp_line
			(start 0.7874 -0.4064)
			(end -0.7874 -0.4064)
			(stroke
				(width 0.1524)
				(type default)
			)
			(layer "B.SilkS")
		)
		(fp_line
			(start -0.67945 0.3048)
			(end -0.120396 0.3048)
			(stroke
				(width 0.1)
				(type default)
			)
			(layer "B.Fab")
		)
		(fp_line
			(start -0.120396 0.3048)
			(end -0.120396 0.2794)
			(stroke
				(width 0.1)
				(type default)
			)
			(layer "B.Fab")
		)
		(fp_line
			(start 0.12065 0.3048)
			(end 0.67945 0.3048)
			(stroke
				(width 0.1)
				(type default)
			)
			(layer "B.Fab")
		)
		(fp_line
			(start 0.67945 0.3048)
			(end 0.67945 -0.305054)
			(stroke
				(width 0.1)
				(type default)
			)
			(layer "B.Fab")
		)
		(fp_line
			(start -0.120396 0.2794)
			(end 0.12065 0.2794)
			(stroke
				(width 0.1)
				(type default)
			)
			(layer "B.Fab")
		)
		(fp_line
			(start 0.12065 0.2794)
			(end 0.12065 0.3048)
			(stroke
				(width 0.1)
				(type default)
			)
			(layer "B.Fab")
		)
		(fp_line
			(start -0.12065 -0.2794)
			(end -0.12065 -0.3048)
			(stroke
				(width 0.1)
				(type default)
			)
			(layer "B.Fab")
		)
		(fp_line
			(start 0.12065 -0.2794)
			(end -0.12065 -0.2794)
			(stroke
				(width 0.1)
				(type default)
			)
			(layer "B.Fab")
		)
		(fp_line
			(start -0.67945 -0.3048)
			(end -0.67945 0.3048)
			(stroke
				(width 0.1)
				(type default)
			)
			(layer "B.Fab")
		)
		(fp_line
			(start -0.12065 -0.3048)
			(end -0.67945 -0.3048)
			(stroke
				(width 0.1)
				(type default)
			)
			(layer "B.Fab")
		)
		(fp_line
			(start 0.12065 -0.305054)
			(end 0.12065 -0.2794)
			(stroke
				(width 0.1)
				(type default)
			)
			(layer "B.Fab")
		)
		(fp_line
			(start 0.67945 -0.305054)
			(end 0.12065 -0.305054)
			(stroke
				(width 0.1)
				(type default)
			)
			(layer "B.Fab")
		)
		(pad "1" smd rect
			(at 0.40005 0 270)
			(size 0.4572 0.508)
			(layers "B.Cu" "B.Mask" "B.Paste")
			(net "P12V_MB1_SENSE+")
		)
		(pad "2" smd rect
			(at -0.40005 0 270)
			(size 0.4572 0.508)
			(layers "B.Cu" "B.Mask" "B.Paste")
			(net "P12V_BRICK")
		)
	)
	(footprint ""
		(layer "B.Cu")
		(at 227.203 -95.504 90)
		(property "Reference" "C24"
			(at 0 0 90)
			(layer "B.SilkS")
			(hide yes)
			(effects
				(font
					(size 1.27 1.27)
				)
				(justify mirror)
			)
		)
		(property "Value" ""
			(at 0 0 90)
			(layer "B.Fab")
			(effects
				(font
					(size 1.27 1.27)
				)
				(justify mirror)
			)
		)
		(duplicate_pad_numbers_are_jumpers no)
		(fp_line
			(start 2.2098 -0.9398)
			(end -2.2098 -0.9398)
			(stroke
				(width 0.1524)
				(type default)
			)
			(layer "B.SilkS")
		)
		(fp_line
			(start -2.2098 -0.9398)
			(end -2.2098 0.9398)
			(stroke
				(width 0.1524)
				(type default)
			)
			(layer "B.SilkS")
		)
		(fp_line
			(start 2.2098 0.9398)
			(end 2.2098 -0.9398)
			(stroke
				(width 0.1524)
				(type default)
			)
			(layer "B.SilkS")
		)
		(fp_line
			(start -2.2098 0.9398)
			(end 2.2098 0.9398)
			(stroke
				(width 0.1524)
				(type default)
			)
			(layer "B.SilkS")
		)
		(fp_line
			(start 1.700022 -0.899922)
			(end -1.700022 -0.899922)
			(stroke
				(width 0.1)
				(type default)
			)
			(layer "B.Fab")
		)
		(fp_line
			(start -1.700022 -0.899922)
			(end -1.700022 0.899922)
			(stroke
				(width 0.1)
				(type default)
			)
			(layer "B.Fab")
		)
		(fp_line
			(start 1.700022 0.899922)
			(end 1.700022 -0.899922)
			(stroke
				(width 0.1)
				(type default)
			)
			(layer "B.Fab")
		)
		(fp_line
			(start -1.700022 0.899922)
			(end 1.700022 0.899922)
			(stroke
				(width 0.1)
				(type default)
			)
			(layer "B.Fab")
		)
		(pad "1" smd rect
			(at 1.4732 0 90)
			(size 1.1684 1.5748)
			(layers "B.Cu" "B.Mask" "B.Paste")
			(net "P52V_HS")
		)
		(pad "2" smd rect
			(at -1.4732 0 90)
			(size 1.1684 1.5748)
			(layers "B.Cu" "B.Mask" "B.Paste")
			(net "GND")
		)
	)
	(footprint ""
		(layer "B.Cu")
		(at 215.138 -95.504 90)
		(property "Reference" "C44"
			(at 0 0 90)
			(layer "B.SilkS")
			(hide yes)
			(effects
				(font
					(size 1.27 1.27)
				)
				(justify mirror)
			)
		)
		(property "Value" ""
			(at 0 0 90)
			(layer "B.Fab")
			(effects
				(font
					(size 1.27 1.27)
				)
				(justify mirror)
			)
		)
		(duplicate_pad_numbers_are_jumpers no)
		(fp_line
			(start 2.2098 -0.9398)
			(end -2.2098 -0.9398)
			(stroke
				(width 0.1524)
				(type default)
			)
			(layer "B.SilkS")
		)
		(fp_line
			(start -2.2098 -0.9398)
			(end -2.2098 0.9398)
			(stroke
				(width 0.1524)
				(type default)
			)
			(layer "B.SilkS")
		)
		(fp_line
			(start 2.2098 0.9398)
			(end 2.2098 -0.9398)
			(stroke
				(width 0.1524)
				(type default)
			)
			(layer "B.SilkS")
		)
		(fp_line
			(start -2.2098 0.9398)
			(end 2.2098 0.9398)
			(stroke
				(width 0.1524)
				(type default)
			)
			(layer "B.SilkS")
		)
		(fp_line
			(start 1.700022 -0.899922)
			(end -1.700022 -0.899922)
			(stroke
				(width 0.1)
				(type default)
			)
			(layer "B.Fab")
		)
		(fp_line
			(start -1.700022 -0.899922)
			(end -1.700022 0.899922)
			(stroke
				(width 0.1)
				(type default)
			)
			(layer "B.Fab")
		)
		(fp_line
			(start 1.700022 0.899922)
			(end 1.700022 -0.899922)
			(stroke
				(width 0.1)
				(type default)
			)
			(layer "B.Fab")
		)
		(fp_line
			(start -1.700022 0.899922)
			(end 1.700022 0.899922)
			(stroke
				(width 0.1)
				(type default)
			)
			(layer "B.Fab")
		)
		(pad "1" smd rect
			(at 1.4732 0 90)
			(size 1.1684 1.5748)
			(layers "B.Cu" "B.Mask" "B.Paste")
			(net "P52V_HS")
		)
		(pad "2" smd rect
			(at -1.4732 0 90)
			(size 1.1684 1.5748)
			(layers "B.Cu" "B.Mask" "B.Paste")
			(net "GND")
		)
	)
	(footprint ""
		(layer "B.Cu")
		(at 232.537 -91.313 -90)
		(property "Reference" "R35"
			(at 0 0 90)
			(layer "B.SilkS")
			(hide yes)
			(effects
				(font
					(size 1.27 1.27)
				)
				(justify mirror)
			)
		)
		(property "Value" ""
			(at 0 0 90)
			(layer "B.Fab")
			(effects
				(font
					(size 1.27 1.27)
				)
				(justify mirror)
			)
		)
		(duplicate_pad_numbers_are_jumpers no)
		(fp_line
			(start -0.7874 0.4064)
			(end 0.7874 0.4064)
			(stroke
				(width 0.1524)
				(type default)
			)
			(layer "B.SilkS")
		)
		(fp_line
			(start 0.7874 0.4064)
			(end 0.7874 -0.4064)
			(stroke
				(width 0.1524)
				(type default)
			)
			(layer "B.SilkS")
		)
		(fp_line
			(start -0.7874 -0.4064)
			(end -0.7874 0.4064)
			(stroke
				(width 0.1524)
				(type default)
			)
			(layer "B.SilkS")
		)
		(fp_line
			(start 0.7874 -0.4064)
			(end -0.7874 -0.4064)
			(stroke
				(width 0.1524)
				(type default)
			)
			(layer "B.SilkS")
		)
		(fp_line
			(start -0.67945 0.3048)
			(end -0.120396 0.3048)
			(stroke
				(width 0.1)
				(type default)
			)
			(layer "B.Fab")
		)
		(fp_line
			(start -0.120396 0.3048)
			(end -0.120396 0.2794)
			(stroke
				(width 0.1)
				(type default)
			)
			(layer "B.Fab")
		)
		(fp_line
			(start 0.12065 0.3048)
			(end 0.67945 0.3048)
			(stroke
				(width 0.1)
				(type default)
			)
			(layer "B.Fab")
		)
		(fp_line
			(start 0.67945 0.3048)
			(end 0.67945 -0.305054)
			(stroke
				(width 0.1)
				(type default)
			)
			(layer "B.Fab")
		)
		(fp_line
			(start -0.120396 0.2794)
			(end 0.12065 0.2794)
			(stroke
				(width 0.1)
				(type default)
			)
			(layer "B.Fab")
		)
		(fp_line
			(start 0.12065 0.2794)
			(end 0.12065 0.3048)
			(stroke
				(width 0.1)
				(type default)
			)
			(layer "B.Fab")
		)
		(fp_line
			(start -0.12065 -0.2794)
			(end -0.12065 -0.3048)
			(stroke
				(width 0.1)
				(type default)
			)
			(layer "B.Fab")
		)
		(fp_line
			(start 0.12065 -0.2794)
			(end -0.12065 -0.2794)
			(stroke
				(width 0.1)
				(type default)
			)
			(layer "B.Fab")
		)
		(fp_line
			(start -0.67945 -0.3048)
			(end -0.67945 0.3048)
			(stroke
				(width 0.1)
				(type default)
			)
			(layer "B.Fab")
		)
		(fp_line
			(start -0.12065 -0.3048)
			(end -0.67945 -0.3048)
			(stroke
				(width 0.1)
				(type default)
			)
			(layer "B.Fab")
		)
		(fp_line
			(start 0.12065 -0.305054)
			(end 0.12065 -0.2794)
			(stroke
				(width 0.1)
				(type default)
			)
			(layer "B.Fab")
		)
		(fp_line
			(start 0.67945 -0.305054)
			(end 0.12065 -0.305054)
			(stroke
				(width 0.1)
				(type default)
			)
			(layer "B.Fab")
		)
		(pad "1" smd circle
			(at 0.40005 0 90)
			(size 0 0)
			(layers "B.Cu" "B.Mask" "B.Paste")
			(net "RST_SMB_PDB_BUF_R_N")
		)
		(pad "2" smd circle
			(at -0.40005 0 90)
			(size 0 0)
			(layers "B.Cu" "B.Mask" "B.Paste")
			(net "RST_SMB_PDB_BUF_N")
		)
	)
	(footprint ""
		(layer "B.Cu")
		(at 211.074 -67.183 90)
		(property "Reference" "R93"
			(at 0 0 90)
			(layer "B.SilkS")
			(hide yes)
			(effects
				(font
					(size 1.27 1.27)
				)
				(justify mirror)
			)
		)
		(property "Value" ""
			(at 0 0 90)
			(layer "B.Fab")
			(effects
				(font
					(size 1.27 1.27)
				)
				(justify mirror)
			)
		)
		(duplicate_pad_numbers_are_jumpers no)
		(fp_line
			(start 0.7874 -0.4064)
			(end -0.7874 -0.4064)
			(stroke
				(width 0.1524)
				(type default)
			)
			(layer "B.SilkS")
		)
		(fp_line
			(start -0.7874 -0.4064)
			(end -0.7874 0.4064)
			(stroke
				(width 0.1524)
				(type default)
			)
			(layer "B.SilkS")
		)
		(fp_line
			(start 0.7874 0.4064)
			(end 0.7874 -0.4064)
			(stroke
				(width 0.1524)
				(type default)
			)
			(layer "B.SilkS")
		)
		(fp_line
			(start -0.7874 0.4064)
			(end 0.7874 0.4064)
			(stroke
				(width 0.1524)
				(type default)
			)
			(layer "B.SilkS")
		)
		(fp_line
			(start 0.67945 -0.305054)
			(end 0.12065 -0.305054)
			(stroke
				(width 0.1)
				(type default)
			)
			(layer "B.Fab")
		)
		(fp_line
			(start 0.12065 -0.305054)
			(end 0.12065 -0.2794)
			(stroke
				(width 0.1)
				(type default)
			)
			(layer "B.Fab")
		)
		(fp_line
			(start -0.12065 -0.3048)
			(end -0.67945 -0.3048)
			(stroke
				(width 0.1)
				(type default)
			)
			(layer "B.Fab")
		)
		(fp_line
			(start -0.67945 -0.3048)
			(end -0.67945 0.3048)
			(stroke
				(width 0.1)
				(type default)
			)
			(layer "B.Fab")
		)
		(fp_line
			(start 0.12065 -0.2794)
			(end -0.12065 -0.2794)
			(stroke
				(width 0.1)
				(type default)
			)
			(layer "B.Fab")
		)
		(fp_line
			(start -0.12065 -0.2794)
			(end -0.12065 -0.3048)
			(stroke
				(width 0.1)
				(type default)
			)
			(layer "B.Fab")
		)
		(fp_line
			(start 0.12065 0.2794)
			(end 0.12065 0.3048)
			(stroke
				(width 0.1)
				(type default)
			)
			(layer "B.Fab")
		)
		(fp_line
			(start -0.120396 0.2794)
			(end 0.12065 0.2794)
			(stroke
				(width 0.1)
				(type default)
			)
			(layer "B.Fab")
		)
		(fp_line
			(start 0.67945 0.3048)
			(end 0.67945 -0.305054)
			(stroke
				(width 0.1)
				(type default)
			)
			(layer "B.Fab")
		)
		(fp_line
			(start 0.12065 0.3048)
			(end 0.67945 0.3048)
			(stroke
				(width 0.1)
				(type default)
			)
			(layer "B.Fab")
		)
		(fp_line
			(start -0.120396 0.3048)
			(end -0.120396 0.2794)
			(stroke
				(width 0.1)
				(type default)
			)
			(layer "B.Fab")
		)
		(fp_line
			(start -0.67945 0.3048)
			(end -0.120396 0.3048)
			(stroke
				(width 0.1)
				(type default)
			)
			(layer "B.Fab")
		)
		(pad "1" smd circle
			(at 0.40005 0 270)
			(size 0 0)
			(layers "B.Cu" "B.Mask" "B.Paste")
			(net "SKU_ID_2")
		)
		(pad "2" smd circle
			(at -0.40005 0 270)
			(size 0 0)
			(layers "B.Cu" "B.Mask" "B.Paste")
			(net "GND")
		)
	)
	(footprint ""
		(layer "B.Cu")
		(at 146.685 -110.109 180)
		(property "Reference" "R168"
			(at 0 0 0)
			(layer "B.SilkS")
			(hide yes)
			(effects
				(font
					(size 1.27 1.27)
				)
				(justify mirror)
			)
		)
		(property "Value" ""
			(at 0 0 0)
			(layer "B.Fab")
			(effects
				(font
					(size 1.27 1.27)
				)
				(justify mirror)
			)
		)
		(duplicate_pad_numbers_are_jumpers no)
		(fp_line
			(start 0.7874 0.4064)
			(end 0.7874 -0.4064)
			(stroke
				(width 0.1524)
				(type default)
			)
			(layer "B.SilkS")
		)
		(fp_line
			(start 0.7874 -0.4064)
			(end -0.7874 -0.4064)
			(stroke
				(width 0.1524)
				(type default)
			)
			(layer "B.SilkS")
		)
		(fp_line
			(start -0.7874 0.4064)
			(end 0.7874 0.4064)
			(stroke
				(width 0.1524)
				(type default)
			)
			(layer "B.SilkS")
		)
		(fp_line
			(start -0.7874 -0.4064)
			(end -0.7874 0.4064)
			(stroke
				(width 0.1524)
				(type default)
			)
			(layer "B.SilkS")
		)
		(fp_line
			(start 0.67945 0.3048)
			(end 0.67945 -0.305054)
			(stroke
				(width 0.1)
				(type default)
			)
			(layer "B.Fab")
		)
		(fp_line
			(start 0.67945 -0.305054)
			(end 0.12065 -0.305054)
			(stroke
				(width 0.1)
				(type default)
			)
			(layer "B.Fab")
		)
		(fp_line
			(start 0.12065 0.3048)
			(end 0.67945 0.3048)
			(stroke
				(width 0.1)
				(type default)
			)
			(layer "B.Fab")
		)
		(fp_line
			(start 0.12065 0.2794)
			(end 0.12065 0.3048)
			(stroke
				(width 0.1)
				(type default)
			)
			(layer "B.Fab")
		)
		(fp_line
			(start 0.12065 -0.2794)
			(end -0.12065 -0.2794)
			(stroke
				(width 0.1)
				(type default)
			)
			(layer "B.Fab")
		)
		(fp_line
			(start 0.12065 -0.305054)
			(end 0.12065 -0.2794)
			(stroke
				(width 0.1)
				(type default)
			)
			(layer "B.Fab")
		)
		(fp_line
			(start -0.120396 0.3048)
			(end -0.120396 0.2794)
			(stroke
				(width 0.1)
				(type default)
			)
			(layer "B.Fab")
		)
		(fp_line
			(start -0.120396 0.2794)
			(end 0.12065 0.2794)
			(stroke
				(width 0.1)
				(type default)
			)
			(layer "B.Fab")
		)
		(fp_line
			(start -0.12065 -0.2794)
			(end -0.12065 -0.3048)
			(stroke
				(width 0.1)
				(type default)
			)
			(layer "B.Fab")
		)
		(fp_line
			(start -0.12065 -0.3048)
			(end -0.67945 -0.3048)
			(stroke
				(width 0.1)
				(type default)
			)
			(layer "B.Fab")
		)
		(fp_line
			(start -0.67945 0.3048)
			(end -0.120396 0.3048)
			(stroke
				(width 0.1)
				(type default)
			)
			(layer "B.Fab")
		)
		(fp_line
			(start -0.67945 -0.3048)
			(end -0.67945 0.3048)
			(stroke
				(width 0.1)
				(type default)
			)
			(layer "B.Fab")
		)
		(pad "1" smd circle
			(at 0.40005 0)
			(size 0 0)
			(layers "B.Cu" "B.Mask" "B.Paste")
			(net "P3V3_AUX")
		)
		(pad "2" smd circle
			(at -0.40005 0)
			(size 0 0)
			(layers "B.Cu" "B.Mask" "B.Paste")
			(net "BRICK_P12V0_EN_R_N")
		)
	)
	(footprint ""
		(layer "B.Cu")
		(at 240.538 -75.819 90)
		(property "Reference" "R74"
			(at 0 0 90)
			(layer "B.SilkS")
			(hide yes)
			(effects
				(font
					(size 1.27 1.27)
				)
				(justify mirror)
			)
		)
		(property "Value" ""
			(at 0 0 90)
			(layer "B.Fab")
			(effects
				(font
					(size 1.27 1.27)
				)
				(justify mirror)
			)
		)
		(duplicate_pad_numbers_are_jumpers no)
		(fp_line
			(start 0.7874 -0.4064)
			(end -0.7874 -0.4064)
			(stroke
				(width 0.1524)
				(type default)
			)
			(layer "B.SilkS")
		)
		(fp_line
			(start -0.7874 -0.4064)
			(end -0.7874 0.4064)
			(stroke
				(width 0.1524)
				(type default)
			)
			(layer "B.SilkS")
		)
		(fp_line
			(start 0.7874 0.4064)
			(end 0.7874 -0.4064)
			(stroke
				(width 0.1524)
				(type default)
			)
			(layer "B.SilkS")
		)
		(fp_line
			(start -0.7874 0.4064)
			(end 0.7874 0.4064)
			(stroke
				(width 0.1524)
				(type default)
			)
			(layer "B.SilkS")
		)
		(fp_line
			(start 0.67945 -0.305054)
			(end 0.12065 -0.305054)
			(stroke
				(width 0.1)
				(type default)
			)
			(layer "B.Fab")
		)
		(fp_line
			(start 0.12065 -0.305054)
			(end 0.12065 -0.2794)
			(stroke
				(width 0.1)
				(type default)
			)
			(layer "B.Fab")
		)
		(fp_line
			(start -0.12065 -0.3048)
			(end -0.67945 -0.3048)
			(stroke
				(width 0.1)
				(type default)
			)
			(layer "B.Fab")
		)
		(fp_line
			(start -0.67945 -0.3048)
			(end -0.67945 0.3048)
			(stroke
				(width 0.1)
				(type default)
			)
			(layer "B.Fab")
		)
		(fp_line
			(start 0.12065 -0.2794)
			(end -0.12065 -0.2794)
			(stroke
				(width 0.1)
				(type default)
			)
			(layer "B.Fab")
		)
		(fp_line
			(start -0.12065 -0.2794)
			(end -0.12065 -0.3048)
			(stroke
				(width 0.1)
				(type default)
			)
			(layer "B.Fab")
		)
		(fp_line
			(start 0.12065 0.2794)
			(end 0.12065 0.3048)
			(stroke
				(width 0.1)
				(type default)
			)
			(layer "B.Fab")
		)
		(fp_line
			(start -0.120396 0.2794)
			(end 0.12065 0.2794)
			(stroke
				(width 0.1)
				(type default)
			)
			(layer "B.Fab")
		)
		(fp_line
			(start 0.67945 0.3048)
			(end 0.67945 -0.305054)
			(stroke
				(width 0.1)
				(type default)
			)
			(layer "B.Fab")
		)
		(fp_line
			(start 0.12065 0.3048)
			(end 0.67945 0.3048)
			(stroke
				(width 0.1)
				(type default)
			)
			(layer "B.Fab")
		)
		(fp_line
			(start -0.120396 0.3048)
			(end -0.120396 0.2794)
			(stroke
				(width 0.1)
				(type default)
			)
			(layer "B.Fab")
		)
		(fp_line
			(start -0.67945 0.3048)
			(end -0.120396 0.3048)
			(stroke
				(width 0.1)
				(type default)
			)
			(layer "B.Fab")
		)
		(pad "1" smd circle
			(at 0.40005 0 270)
			(size 0 0)
			(layers "B.Cu" "B.Mask" "B.Paste")
			(net "P3V3_AUX")
		)
		(pad "2" smd circle
			(at -0.40005 0 270)
			(size 0 0)
			(layers "B.Cu" "B.Mask" "B.Paste")
			(net "SMB_MB_PDB_R_SCL")
		)
	)
	(footprint ""
		(layer "B.Cu")
		(at 291.592 -53.34 90)
		(property "Reference" "PR2"
			(at 0 0 90)
			(layer "B.SilkS")
			(hide yes)
			(effects
				(font
					(size 1.27 1.27)
				)
				(justify mirror)
			)
		)
		(property "Value" ""
			(at 0 0 90)
			(layer "B.Fab")
			(effects
				(font
					(size 1.27 1.27)
				)
				(justify mirror)
			)
		)
		(duplicate_pad_numbers_are_jumpers no)
		(fp_line
			(start 1.651 -0.8382)
			(end -1.651 -0.8382)
			(stroke
				(width 0.1524)
				(type default)
			)
			(layer "B.SilkS")
		)
		(fp_line
			(start -1.651 -0.8382)
			(end -1.651 0.8382)
			(stroke
				(width 0.1524)
				(type default)
			)
			(layer "B.SilkS")
		)
		(fp_line
			(start 1.651 0.8382)
			(end 1.651 -0.8382)
			(stroke
				(width 0.1524)
				(type default)
			)
			(layer "B.SilkS")
		)
		(fp_line
			(start -1.651 0.8382)
			(end 1.651 0.8382)
			(stroke
				(width 0.1524)
				(type default)
			)
			(layer "B.SilkS")
		)
		(fp_line
			(start 1.559814 -0.7366)
			(end 1.559814 0.7366)
			(stroke
				(width 0.1)
				(type default)
			)
			(layer "B.Fab")
		)
		(fp_line
			(start 1.524 -0.7366)
			(end 1.559814 -0.7366)
			(stroke
				(width 0.1)
				(type default)
			)
			(layer "B.Fab")
		)
		(fp_line
			(start -1.524 -0.7366)
			(end 1.524 -0.7366)
			(stroke
				(width 0.1)
				(type default)
			)
			(layer "B.Fab")
		)
		(fp_line
			(start -1.560576 -0.7366)
			(end -1.524 -0.7366)
			(stroke
				(width 0.1)
				(type default)
			)
			(layer "B.Fab")
		)
		(fp_line
			(start 1.559814 0.7366)
			(end 1.524 0.7366)
			(stroke
				(width 0.1)
				(type default)
			)
			(layer "B.Fab")
		)
		(fp_line
			(start 1.524 0.7366)
			(end -1.524 0.7366)
			(stroke
				(width 0.1)
				(type default)
			)
			(layer "B.Fab")
		)
		(fp_line
			(start -1.524 0.7366)
			(end -1.560576 0.7366)
			(stroke
				(width 0.1)
				(type default)
			)
			(layer "B.Fab")
		)
		(fp_line
			(start -1.560576 0.7366)
			(end -1.560576 -0.7366)
			(stroke
				(width 0.1)
				(type default)
			)
			(layer "B.Fab")
		)
		(pad "1" smd rect
			(at 0.94996 0 90)
			(size 1.1176 1.3716)
			(layers "B.Cu" "B.Mask" "B.Paste")
			(net "P52V_1")
		)
		(pad "2" smd rect
			(at -0.94996 0 90)
			(size 1.1176 1.3716)
			(layers "B.Cu" "B.Mask" "B.Paste")
			(net "P52V_HS1_OV")
		)
	)
	(footprint ""
		(layer "B.Cu")
		(at 106.684826 -110.109 180)
		(property "Reference" "R201"
			(at 0 0 0)
			(layer "B.SilkS")
			(hide yes)
			(effects
				(font
					(size 1.27 1.27)
				)
				(justify mirror)
			)
		)
		(property "Value" ""
			(at 0 0 0)
			(layer "B.Fab")
			(effects
				(font
					(size 1.27 1.27)
				)
				(justify mirror)
			)
		)
		(duplicate_pad_numbers_are_jumpers no)
		(fp_line
			(start 0.7874 0.4064)
			(end 0.7874 -0.4064)
			(stroke
				(width 0.1524)
				(type default)
			)
			(layer "B.SilkS")
		)
		(fp_line
			(start 0.7874 -0.4064)
			(end -0.7874 -0.4064)
			(stroke
				(width 0.1524)
				(type default)
			)
			(layer "B.SilkS")
		)
		(fp_line
			(start -0.7874 0.4064)
			(end 0.7874 0.4064)
			(stroke
				(width 0.1524)
				(type default)
			)
			(layer "B.SilkS")
		)
		(fp_line
			(start -0.7874 -0.4064)
			(end -0.7874 0.4064)
			(stroke
				(width 0.1524)
				(type default)
			)
			(layer "B.SilkS")
		)
		(fp_line
			(start 0.67945 0.3048)
			(end 0.67945 -0.305054)
			(stroke
				(width 0.1)
				(type default)
			)
			(layer "B.Fab")
		)
		(fp_line
			(start 0.67945 -0.305054)
			(end 0.12065 -0.305054)
			(stroke
				(width 0.1)
				(type default)
			)
			(layer "B.Fab")
		)
		(fp_line
			(start 0.12065 0.3048)
			(end 0.67945 0.3048)
			(stroke
				(width 0.1)
				(type default)
			)
			(layer "B.Fab")
		)
		(fp_line
			(start 0.12065 0.2794)
			(end 0.12065 0.3048)
			(stroke
				(width 0.1)
				(type default)
			)
			(layer "B.Fab")
		)
		(fp_line
			(start 0.12065 -0.2794)
			(end -0.12065 -0.2794)
			(stroke
				(width 0.1)
				(type default)
			)
			(layer "B.Fab")
		)
		(fp_line
			(start 0.12065 -0.305054)
			(end 0.12065 -0.2794)
			(stroke
				(width 0.1)
				(type default)
			)
			(layer "B.Fab")
		)
		(fp_line
			(start -0.120396 0.3048)
			(end -0.120396 0.2794)
			(stroke
				(width 0.1)
				(type default)
			)
			(layer "B.Fab")
		)
		(fp_line
			(start -0.120396 0.2794)
			(end 0.12065 0.2794)
			(stroke
				(width 0.1)
				(type default)
			)
			(layer "B.Fab")
		)
		(fp_line
			(start -0.12065 -0.2794)
			(end -0.12065 -0.3048)
			(stroke
				(width 0.1)
				(type default)
			)
			(layer "B.Fab")
		)
		(fp_line
			(start -0.12065 -0.3048)
			(end -0.67945 -0.3048)
			(stroke
				(width 0.1)
				(type default)
			)
			(layer "B.Fab")
		)
		(fp_line
			(start -0.67945 0.3048)
			(end -0.120396 0.3048)
			(stroke
				(width 0.1)
				(type default)
			)
			(layer "B.Fab")
		)
		(fp_line
			(start -0.67945 -0.3048)
			(end -0.67945 0.3048)
			(stroke
				(width 0.1)
				(type default)
			)
			(layer "B.Fab")
		)
		(pad "1" smd circle
			(at 0.40005 0)
			(size 0 0)
			(layers "B.Cu" "B.Mask" "B.Paste")
			(net "P3V3_AUX")
		)
		(pad "2" smd circle
			(at -0.40005 0)
			(size 0 0)
			(layers "B.Cu" "B.Mask" "B.Paste")
			(net "BRICK_P12V_EN_R_N")
		)
	)
	(footprint ""
		(layer "B.Cu")
		(at 292.227 -44.958)
		(property "Reference" "R5910"
			(at 0 0 0)
			(layer "B.SilkS")
			(hide yes)
			(effects
				(font
					(size 1.27 1.27)
				)
				(justify mirror)
			)
		)
		(property "Value" ""
			(at 0 0 0)
			(layer "B.Fab")
			(effects
				(font
					(size 1.27 1.27)
				)
				(justify mirror)
			)
		)
		(duplicate_pad_numbers_are_jumpers no)
		(fp_line
			(start -1.651 -0.8382)
			(end -1.651 0.8382)
			(stroke
				(width 0.1524)
				(type default)
			)
			(layer "B.SilkS")
		)
		(fp_line
			(start -1.651 0.8382)
			(end 1.651 0.8382)
			(stroke
				(width 0.1524)
				(type default)
			)
			(layer "B.SilkS")
		)
		(fp_line
			(start 1.651 -0.8382)
			(end -1.651 -0.8382)
			(stroke
				(width 0.1524)
				(type default)
			)
			(layer "B.SilkS")
		)
		(fp_line
			(start 1.651 0.8382)
			(end 1.651 -0.8382)
			(stroke
				(width 0.1524)
				(type default)
			)
			(layer "B.SilkS")
		)
		(fp_line
			(start -1.560576 -0.7366)
			(end -1.524 -0.7366)
			(stroke
				(width 0.1)
				(type default)
			)
			(layer "B.Fab")
		)
		(fp_line
			(start -1.560576 0.7366)
			(end -1.560576 -0.7366)
			(stroke
				(width 0.1)
				(type default)
			)
			(layer "B.Fab")
		)
		(fp_line
			(start -1.524 -0.7366)
			(end 1.524 -0.7366)
			(stroke
				(width 0.1)
				(type default)
			)
			(layer "B.Fab")
		)
		(fp_line
			(start -1.524 0.7366)
			(end -1.560576 0.7366)
			(stroke
				(width 0.1)
				(type default)
			)
			(layer "B.Fab")
		)
		(fp_line
			(start 1.524 -0.7366)
			(end 1.559814 -0.7366)
			(stroke
				(width 0.1)
				(type default)
			)
			(layer "B.Fab")
		)
		(fp_line
			(start 1.524 0.7366)
			(end -1.524 0.7366)
			(stroke
				(width 0.1)
				(type default)
			)
			(layer "B.Fab")
		)
		(fp_line
			(start 1.559814 -0.7366)
			(end 1.559814 0.7366)
			(stroke
				(width 0.1)
				(type default)
			)
			(layer "B.Fab")
		)
		(fp_line
			(start 1.559814 0.7366)
			(end 1.524 0.7366)
			(stroke
				(width 0.1)
				(type default)
			)
			(layer "B.Fab")
		)
		(pad "1" smd rect
			(at 0.94996 0)
			(size 1.1176 1.3716)
			(layers "B.Cu" "B.Mask" "B.Paste")
			(net "P52V_1_R")
		)
		(pad "2" smd rect
			(at -0.94996 0)
			(size 1.1176 1.3716)
			(layers "B.Cu" "B.Mask" "B.Paste")
			(net "FM_AC_PWR_CYCLE_N")
		)
	)
	(footprint ""
		(layer "B.Cu")
		(at 209.804 -69.723 -90)
		(property "Reference" "R18"
			(at 0 0 90)
			(layer "B.SilkS")
			(hide yes)
			(effects
				(font
					(size 1.27 1.27)
				)
				(justify mirror)
			)
		)
		(property "Value" ""
			(at 0 0 90)
			(layer "B.Fab")
			(effects
				(font
					(size 1.27 1.27)
				)
				(justify mirror)
			)
		)
		(duplicate_pad_numbers_are_jumpers no)
		(fp_line
			(start -0.7874 0.4064)
			(end 0.7874 0.4064)
			(stroke
				(width 0.1524)
				(type default)
			)
			(layer "B.SilkS")
		)
		(fp_line
			(start 0.7874 0.4064)
			(end 0.7874 -0.4064)
			(stroke
				(width 0.1524)
				(type default)
			)
			(layer "B.SilkS")
		)
		(fp_line
			(start -0.7874 -0.4064)
			(end -0.7874 0.4064)
			(stroke
				(width 0.1524)
				(type default)
			)
			(layer "B.SilkS")
		)
		(fp_line
			(start 0.7874 -0.4064)
			(end -0.7874 -0.4064)
			(stroke
				(width 0.1524)
				(type default)
			)
			(layer "B.SilkS")
		)
		(fp_line
			(start -0.67945 0.3048)
			(end -0.120396 0.3048)
			(stroke
				(width 0.1)
				(type default)
			)
			(layer "B.Fab")
		)
		(fp_line
			(start -0.120396 0.3048)
			(end -0.120396 0.2794)
			(stroke
				(width 0.1)
				(type default)
			)
			(layer "B.Fab")
		)
		(fp_line
			(start 0.12065 0.3048)
			(end 0.67945 0.3048)
			(stroke
				(width 0.1)
				(type default)
			)
			(layer "B.Fab")
		)
		(fp_line
			(start 0.67945 0.3048)
			(end 0.67945 -0.305054)
			(stroke
				(width 0.1)
				(type default)
			)
			(layer "B.Fab")
		)
		(fp_line
			(start -0.120396 0.2794)
			(end 0.12065 0.2794)
			(stroke
				(width 0.1)
				(type default)
			)
			(layer "B.Fab")
		)
		(fp_line
			(start 0.12065 0.2794)
			(end 0.12065 0.3048)
			(stroke
				(width 0.1)
				(type default)
			)
			(layer "B.Fab")
		)
		(fp_line
			(start -0.12065 -0.2794)
			(end -0.12065 -0.3048)
			(stroke
				(width 0.1)
				(type default)
			)
			(layer "B.Fab")
		)
		(fp_line
			(start 0.12065 -0.2794)
			(end -0.12065 -0.2794)
			(stroke
				(width 0.1)
				(type default)
			)
			(layer "B.Fab")
		)
		(fp_line
			(start -0.67945 -0.3048)
			(end -0.67945 0.3048)
			(stroke
				(width 0.1)
				(type default)
			)
			(layer "B.Fab")
		)
		(fp_line
			(start -0.12065 -0.3048)
			(end -0.67945 -0.3048)
			(stroke
				(width 0.1)
				(type default)
			)
			(layer "B.Fab")
		)
		(fp_line
			(start 0.12065 -0.305054)
			(end 0.12065 -0.2794)
			(stroke
				(width 0.1)
				(type default)
			)
			(layer "B.Fab")
		)
		(fp_line
			(start 0.67945 -0.305054)
			(end 0.12065 -0.305054)
			(stroke
				(width 0.1)
				(type default)
			)
			(layer "B.Fab")
		)
		(pad "1" smd circle
			(at 0.40005 0 90)
			(size 0 0)
			(layers "B.Cu" "B.Mask" "B.Paste")
			(net "P3V3_AUX")
		)
		(pad "2" smd circle
			(at -0.40005 0 90)
			(size 0 0)
			(layers "B.Cu" "B.Mask" "B.Paste")
			(net "PCA9555_A0")
		)
	)
	(footprint ""
		(layer "B.Cu")
		(at 136.779 -78.867)
		(property "Reference" "R162"
			(at 0 0 0)
			(layer "B.SilkS")
			(hide yes)
			(effects
				(font
					(size 1.27 1.27)
				)
				(justify mirror)
			)
		)
		(property "Value" ""
			(at 0 0 0)
			(layer "B.Fab")
			(effects
				(font
					(size 1.27 1.27)
				)
				(justify mirror)
			)
		)
		(duplicate_pad_numbers_are_jumpers no)
		(fp_line
			(start -0.7874 -0.4064)
			(end -0.7874 0.4064)
			(stroke
				(width 0.1524)
				(type default)
			)
			(layer "B.SilkS")
		)
		(fp_line
			(start -0.7874 0.4064)
			(end 0.7874 0.4064)
			(stroke
				(width 0.1524)
				(type default)
			)
			(layer "B.SilkS")
		)
		(fp_line
			(start 0.7874 -0.4064)
			(end -0.7874 -0.4064)
			(stroke
				(width 0.1524)
				(type default)
			)
			(layer "B.SilkS")
		)
		(fp_line
			(start 0.7874 0.4064)
			(end 0.7874 -0.4064)
			(stroke
				(width 0.1524)
				(type default)
			)
			(layer "B.SilkS")
		)
		(fp_line
			(start -0.67945 -0.3048)
			(end -0.67945 0.3048)
			(stroke
				(width 0.1)
				(type default)
			)
			(layer "B.Fab")
		)
		(fp_line
			(start -0.67945 0.3048)
			(end -0.120396 0.3048)
			(stroke
				(width 0.1)
				(type default)
			)
			(layer "B.Fab")
		)
		(fp_line
			(start -0.12065 -0.3048)
			(end -0.67945 -0.3048)
			(stroke
				(width 0.1)
				(type default)
			)
			(layer "B.Fab")
		)
		(fp_line
			(start -0.12065 -0.2794)
			(end -0.12065 -0.3048)
			(stroke
				(width 0.1)
				(type default)
			)
			(layer "B.Fab")
		)
		(fp_line
			(start -0.120396 0.2794)
			(end 0.12065 0.2794)
			(stroke
				(width 0.1)
				(type default)
			)
			(layer "B.Fab")
		)
		(fp_line
			(start -0.120396 0.3048)
			(end -0.120396 0.2794)
			(stroke
				(width 0.1)
				(type default)
			)
			(layer "B.Fab")
		)
		(fp_line
			(start 0.12065 -0.305054)
			(end 0.12065 -0.2794)
			(stroke
				(width 0.1)
				(type default)
			)
			(layer "B.Fab")
		)
		(fp_line
			(start 0.12065 -0.2794)
			(end -0.12065 -0.2794)
			(stroke
				(width 0.1)
				(type default)
			)
			(layer "B.Fab")
		)
		(fp_line
			(start 0.12065 0.2794)
			(end 0.12065 0.3048)
			(stroke
				(width 0.1)
				(type default)
			)
			(layer "B.Fab")
		)
		(fp_line
			(start 0.12065 0.3048)
			(end 0.67945 0.3048)
			(stroke
				(width 0.1)
				(type default)
			)
			(layer "B.Fab")
		)
		(fp_line
			(start 0.67945 -0.305054)
			(end 0.12065 -0.305054)
			(stroke
				(width 0.1)
				(type default)
			)
			(layer "B.Fab")
		)
		(fp_line
			(start 0.67945 0.3048)
			(end 0.67945 -0.305054)
			(stroke
				(width 0.1)
				(type default)
			)
			(layer "B.Fab")
		)
		(pad "1" smd circle
			(at 0.40005 0 180)
			(size 0 0)
			(layers "B.Cu" "B.Mask" "B.Paste")
			(net "P3V3_AUX")
		)
		(pad "2" smd circle
			(at -0.40005 0 180)
			(size 0 0)
			(layers "B.Cu" "B.Mask" "B.Paste")
			(net "P12V_BRICK0_ALERT_N")
		)
	)
	(footprint ""
		(layer "B.Cu")
		(at 179.065174 -78.867)
		(property "Reference" "R194"
			(at 0 0 0)
			(layer "B.SilkS")
			(hide yes)
			(effects
				(font
					(size 1.27 1.27)
				)
				(justify mirror)
			)
		)
		(property "Value" ""
			(at 0 0 0)
			(layer "B.Fab")
			(effects
				(font
					(size 1.27 1.27)
				)
				(justify mirror)
			)
		)
		(duplicate_pad_numbers_are_jumpers no)
		(fp_line
			(start -0.7874 -0.4064)
			(end -0.7874 0.4064)
			(stroke
				(width 0.1524)
				(type default)
			)
			(layer "B.SilkS")
		)
		(fp_line
			(start -0.7874 0.4064)
			(end 0.7874 0.4064)
			(stroke
				(width 0.1524)
				(type default)
			)
			(layer "B.SilkS")
		)
		(fp_line
			(start 0.7874 -0.4064)
			(end -0.7874 -0.4064)
			(stroke
				(width 0.1524)
				(type default)
			)
			(layer "B.SilkS")
		)
		(fp_line
			(start 0.7874 0.4064)
			(end 0.7874 -0.4064)
			(stroke
				(width 0.1524)
				(type default)
			)
			(layer "B.SilkS")
		)
		(fp_line
			(start -0.67945 -0.3048)
			(end -0.67945 0.3048)
			(stroke
				(width 0.1)
				(type default)
			)
			(layer "B.Fab")
		)
		(fp_line
			(start -0.67945 0.3048)
			(end -0.120396 0.3048)
			(stroke
				(width 0.1)
				(type default)
			)
			(layer "B.Fab")
		)
		(fp_line
			(start -0.12065 -0.3048)
			(end -0.67945 -0.3048)
			(stroke
				(width 0.1)
				(type default)
			)
			(layer "B.Fab")
		)
		(fp_line
			(start -0.12065 -0.2794)
			(end -0.12065 -0.3048)
			(stroke
				(width 0.1)
				(type default)
			)
			(layer "B.Fab")
		)
		(fp_line
			(start -0.120396 0.2794)
			(end 0.12065 0.2794)
			(stroke
				(width 0.1)
				(type default)
			)
			(layer "B.Fab")
		)
		(fp_line
			(start -0.120396 0.3048)
			(end -0.120396 0.2794)
			(stroke
				(width 0.1)
				(type default)
			)
			(layer "B.Fab")
		)
		(fp_line
			(start 0.12065 -0.305054)
			(end 0.12065 -0.2794)
			(stroke
				(width 0.1)
				(type default)
			)
			(layer "B.Fab")
		)
		(fp_line
			(start 0.12065 -0.2794)
			(end -0.12065 -0.2794)
			(stroke
				(width 0.1)
				(type default)
			)
			(layer "B.Fab")
		)
		(fp_line
			(start 0.12065 0.2794)
			(end 0.12065 0.3048)
			(stroke
				(width 0.1)
				(type default)
			)
			(layer "B.Fab")
		)
		(fp_line
			(start 0.12065 0.3048)
			(end 0.67945 0.3048)
			(stroke
				(width 0.1)
				(type default)
			)
			(layer "B.Fab")
		)
		(fp_line
			(start 0.67945 -0.305054)
			(end 0.12065 -0.305054)
			(stroke
				(width 0.1)
				(type default)
			)
			(layer "B.Fab")
		)
		(fp_line
			(start 0.67945 0.3048)
			(end 0.67945 -0.305054)
			(stroke
				(width 0.1)
				(type default)
			)
			(layer "B.Fab")
		)
		(pad "1" smd circle
			(at 0.40005 0 180)
			(size 0 0)
			(layers "B.Cu" "B.Mask" "B.Paste")
			(net "P3V3_AUX")
		)
		(pad "2" smd circle
			(at -0.40005 0 180)
			(size 0 0)
			(layers "B.Cu" "B.Mask" "B.Paste")
			(net "SMB_P52V_VPDB_SCL")
		)
	)
	(footprint ""
		(layer "B.Cu")
		(at 176.779174 -78.867)
		(property "Reference" "R193"
			(at 0 0 0)
			(layer "B.SilkS")
			(hide yes)
			(effects
				(font
					(size 1.27 1.27)
				)
				(justify mirror)
			)
		)
		(property "Value" ""
			(at 0 0 0)
			(layer "B.Fab")
			(effects
				(font
					(size 1.27 1.27)
				)
				(justify mirror)
			)
		)
		(duplicate_pad_numbers_are_jumpers no)
		(fp_line
			(start -0.7874 -0.4064)
			(end -0.7874 0.4064)
			(stroke
				(width 0.1524)
				(type default)
			)
			(layer "B.SilkS")
		)
		(fp_line
			(start -0.7874 0.4064)
			(end 0.7874 0.4064)
			(stroke
				(width 0.1524)
				(type default)
			)
			(layer "B.SilkS")
		)
		(fp_line
			(start 0.7874 -0.4064)
			(end -0.7874 -0.4064)
			(stroke
				(width 0.1524)
				(type default)
			)
			(layer "B.SilkS")
		)
		(fp_line
			(start 0.7874 0.4064)
			(end 0.7874 -0.4064)
			(stroke
				(width 0.1524)
				(type default)
			)
			(layer "B.SilkS")
		)
		(fp_line
			(start -0.67945 -0.3048)
			(end -0.67945 0.3048)
			(stroke
				(width 0.1)
				(type default)
			)
			(layer "B.Fab")
		)
		(fp_line
			(start -0.67945 0.3048)
			(end -0.120396 0.3048)
			(stroke
				(width 0.1)
				(type default)
			)
			(layer "B.Fab")
		)
		(fp_line
			(start -0.12065 -0.3048)
			(end -0.67945 -0.3048)
			(stroke
				(width 0.1)
				(type default)
			)
			(layer "B.Fab")
		)
		(fp_line
			(start -0.12065 -0.2794)
			(end -0.12065 -0.3048)
			(stroke
				(width 0.1)
				(type default)
			)
			(layer "B.Fab")
		)
		(fp_line
			(start -0.120396 0.2794)
			(end 0.12065 0.2794)
			(stroke
				(width 0.1)
				(type default)
			)
			(layer "B.Fab")
		)
		(fp_line
			(start -0.120396 0.3048)
			(end -0.120396 0.2794)
			(stroke
				(width 0.1)
				(type default)
			)
			(layer "B.Fab")
		)
		(fp_line
			(start 0.12065 -0.305054)
			(end 0.12065 -0.2794)
			(stroke
				(width 0.1)
				(type default)
			)
			(layer "B.Fab")
		)
		(fp_line
			(start 0.12065 -0.2794)
			(end -0.12065 -0.2794)
			(stroke
				(width 0.1)
				(type default)
			)
			(layer "B.Fab")
		)
		(fp_line
			(start 0.12065 0.2794)
			(end 0.12065 0.3048)
			(stroke
				(width 0.1)
				(type default)
			)
			(layer "B.Fab")
		)
		(fp_line
			(start 0.12065 0.3048)
			(end 0.67945 0.3048)
			(stroke
				(width 0.1)
				(type default)
			)
			(layer "B.Fab")
		)
		(fp_line
			(start 0.67945 -0.305054)
			(end 0.12065 -0.305054)
			(stroke
				(width 0.1)
				(type default)
			)
			(layer "B.Fab")
		)
		(fp_line
			(start 0.67945 0.3048)
			(end 0.67945 -0.305054)
			(stroke
				(width 0.1)
				(type default)
			)
			(layer "B.Fab")
		)
		(pad "1" smd circle
			(at 0.40005 0 180)
			(size 0 0)
			(layers "B.Cu" "B.Mask" "B.Paste")
			(net "P3V3_AUX")
		)
		(pad "2" smd circle
			(at -0.40005 0 180)
			(size 0 0)
			(layers "B.Cu" "B.Mask" "B.Paste")
			(net "P12V_BRICK2_ALERT_N")
		)
	)
	(footprint ""
		(layer "B.Cu")
		(at 279.908 -42.799)
		(property "Reference" "PR93"
			(at 0 0 0)
			(layer "B.SilkS")
			(hide yes)
			(effects
				(font
					(size 1.27 1.27)
				)
				(justify mirror)
			)
		)
		(property "Value" ""
			(at 0 0 0)
			(layer "B.Fab")
			(effects
				(font
					(size 1.27 1.27)
				)
				(justify mirror)
			)
		)
		(duplicate_pad_numbers_are_jumpers no)
		(fp_line
			(start -0.7874 -0.4064)
			(end -0.7874 0.4064)
			(stroke
				(width 0.1524)
				(type default)
			)
			(layer "B.SilkS")
		)
		(fp_line
			(start -0.7874 0.4064)
			(end 0.7874 0.4064)
			(stroke
				(width 0.1524)
				(type default)
			)
			(layer "B.SilkS")
		)
		(fp_line
			(start 0.7874 -0.4064)
			(end -0.7874 -0.4064)
			(stroke
				(width 0.1524)
				(type default)
			)
			(layer "B.SilkS")
		)
		(fp_line
			(start 0.7874 0.4064)
			(end 0.7874 -0.4064)
			(stroke
				(width 0.1524)
				(type default)
			)
			(layer "B.SilkS")
		)
		(fp_line
			(start -0.67945 -0.3048)
			(end -0.67945 0.3048)
			(stroke
				(width 0.1)
				(type default)
			)
			(layer "B.Fab")
		)
		(fp_line
			(start -0.67945 0.3048)
			(end -0.120396 0.3048)
			(stroke
				(width 0.1)
				(type default)
			)
			(layer "B.Fab")
		)
		(fp_line
			(start -0.12065 -0.3048)
			(end -0.67945 -0.3048)
			(stroke
				(width 0.1)
				(type default)
			)
			(layer "B.Fab")
		)
		(fp_line
			(start -0.12065 -0.2794)
			(end -0.12065 -0.3048)
			(stroke
				(width 0.1)
				(type default)
			)
			(layer "B.Fab")
		)
		(fp_line
			(start -0.120396 0.2794)
			(end 0.12065 0.2794)
			(stroke
				(width 0.1)
				(type default)
			)
			(layer "B.Fab")
		)
		(fp_line
			(start -0.120396 0.3048)
			(end -0.120396 0.2794)
			(stroke
				(width 0.1)
				(type default)
			)
			(layer "B.Fab")
		)
		(fp_line
			(start 0.12065 -0.305054)
			(end 0.12065 -0.2794)
			(stroke
				(width 0.1)
				(type default)
			)
			(layer "B.Fab")
		)
		(fp_line
			(start 0.12065 -0.2794)
			(end -0.12065 -0.2794)
			(stroke
				(width 0.1)
				(type default)
			)
			(layer "B.Fab")
		)
		(fp_line
			(start 0.12065 0.2794)
			(end 0.12065 0.3048)
			(stroke
				(width 0.1)
				(type default)
			)
			(layer "B.Fab")
		)
		(fp_line
			(start 0.12065 0.3048)
			(end 0.67945 0.3048)
			(stroke
				(width 0.1)
				(type default)
			)
			(layer "B.Fab")
		)
		(fp_line
			(start 0.67945 -0.305054)
			(end 0.12065 -0.305054)
			(stroke
				(width 0.1)
				(type default)
			)
			(layer "B.Fab")
		)
		(fp_line
			(start 0.67945 0.3048)
			(end 0.67945 -0.305054)
			(stroke
				(width 0.1)
				(type default)
			)
			(layer "B.Fab")
		)
		(pad "1" smd circle
			(at 0.40005 0 180)
			(size 0 0)
			(layers "B.Cu" "B.Mask" "B.Paste")
			(net "P52V_HS1_ESTART_R")
		)
		(pad "2" smd circle
			(at -0.40005 0 180)
			(size 0 0)
			(layers "B.Cu" "B.Mask" "B.Paste")
			(net "P52V_HS1_ESTART")
		)
	)
	(footprint ""
		(layer "B.Cu")
		(at 58.928 -77.47 180)
		(property "Reference" "C63"
			(at 0 0 0)
			(layer "B.SilkS")
			(hide yes)
			(effects
				(font
					(size 1.27 1.27)
				)
				(justify mirror)
			)
		)
		(property "Value" ""
			(at 0 0 0)
			(layer "B.Fab")
			(effects
				(font
					(size 1.27 1.27)
				)
				(justify mirror)
			)
		)
		(duplicate_pad_numbers_are_jumpers no)
		(fp_line
			(start 0.7874 0.4064)
			(end 0.7874 -0.4064)
			(stroke
				(width 0.1524)
				(type default)
			)
			(layer "B.SilkS")
		)
		(fp_line
			(start 0.7874 -0.4064)
			(end -0.7874 -0.4064)
			(stroke
				(width 0.1524)
				(type default)
			)
			(layer "B.SilkS")
		)
		(fp_line
			(start -0.7874 0.4064)
			(end 0.7874 0.4064)
			(stroke
				(width 0.1524)
				(type default)
			)
			(layer "B.SilkS")
		)
		(fp_line
			(start -0.7874 -0.4064)
			(end -0.7874 0.4064)
			(stroke
				(width 0.1524)
				(type default)
			)
			(layer "B.SilkS")
		)
		(fp_line
			(start 0.67945 0.3048)
			(end 0.67945 -0.305054)
			(stroke
				(width 0.1)
				(type default)
			)
			(layer "B.Fab")
		)
		(fp_line
			(start 0.67945 -0.305054)
			(end 0.12065 -0.305054)
			(stroke
				(width 0.1)
				(type default)
			)
			(layer "B.Fab")
		)
		(fp_line
			(start 0.12065 0.3048)
			(end 0.67945 0.3048)
			(stroke
				(width 0.1)
				(type default)
			)
			(layer "B.Fab")
		)
		(fp_line
			(start 0.12065 0.2794)
			(end 0.12065 0.3048)
			(stroke
				(width 0.1)
				(type default)
			)
			(layer "B.Fab")
		)
		(fp_line
			(start 0.12065 -0.2794)
			(end -0.12065 -0.2794)
			(stroke
				(width 0.1)
				(type default)
			)
			(layer "B.Fab")
		)
		(fp_line
			(start 0.12065 -0.305054)
			(end 0.12065 -0.2794)
			(stroke
				(width 0.1)
				(type default)
			)
			(layer "B.Fab")
		)
		(fp_line
			(start -0.120396 0.3048)
			(end -0.120396 0.2794)
			(stroke
				(width 0.1)
				(type default)
			)
			(layer "B.Fab")
		)
		(fp_line
			(start -0.120396 0.2794)
			(end 0.12065 0.2794)
			(stroke
				(width 0.1)
				(type default)
			)
			(layer "B.Fab")
		)
		(fp_line
			(start -0.12065 -0.2794)
			(end -0.12065 -0.3048)
			(stroke
				(width 0.1)
				(type default)
			)
			(layer "B.Fab")
		)
		(fp_line
			(start -0.12065 -0.3048)
			(end -0.67945 -0.3048)
			(stroke
				(width 0.1)
				(type default)
			)
			(layer "B.Fab")
		)
		(fp_line
			(start -0.67945 0.3048)
			(end -0.120396 0.3048)
			(stroke
				(width 0.1)
				(type default)
			)
			(layer "B.Fab")
		)
		(fp_line
			(start -0.67945 -0.3048)
			(end -0.67945 0.3048)
			(stroke
				(width 0.1)
				(type default)
			)
			(layer "B.Fab")
		)
		(pad "1" smd circle
			(at 0.40005 0)
			(size 0 0)
			(layers "B.Cu" "B.Mask" "B.Paste")
			(net "SMB_P52V_VPDB_SCL")
		)
		(pad "2" smd circle
			(at -0.40005 0)
			(size 0 0)
			(layers "B.Cu" "B.Mask" "B.Paste")
			(net "GND")
		)
	)
	(footprint ""
		(layer "B.Cu")
		(at 238.506 -77.851 180)
		(property "Reference" "R5"
			(at 0 0 0)
			(layer "B.SilkS")
			(hide yes)
			(effects
				(font
					(size 1.27 1.27)
				)
				(justify mirror)
			)
		)
		(property "Value" ""
			(at 0 0 0)
			(layer "B.Fab")
			(effects
				(font
					(size 1.27 1.27)
				)
				(justify mirror)
			)
		)
		(duplicate_pad_numbers_are_jumpers no)
		(fp_line
			(start 0.7874 0.4064)
			(end 0.7874 -0.4064)
			(stroke
				(width 0.1524)
				(type default)
			)
			(layer "B.SilkS")
		)
		(fp_line
			(start 0.7874 -0.4064)
			(end -0.7874 -0.4064)
			(stroke
				(width 0.1524)
				(type default)
			)
			(layer "B.SilkS")
		)
		(fp_line
			(start -0.7874 0.4064)
			(end 0.7874 0.4064)
			(stroke
				(width 0.1524)
				(type default)
			)
			(layer "B.SilkS")
		)
		(fp_line
			(start -0.7874 -0.4064)
			(end -0.7874 0.4064)
			(stroke
				(width 0.1524)
				(type default)
			)
			(layer "B.SilkS")
		)
		(fp_line
			(start 0.67945 0.3048)
			(end 0.67945 -0.305054)
			(stroke
				(width 0.1)
				(type default)
			)
			(layer "B.Fab")
		)
		(fp_line
			(start 0.67945 -0.305054)
			(end 0.12065 -0.305054)
			(stroke
				(width 0.1)
				(type default)
			)
			(layer "B.Fab")
		)
		(fp_line
			(start 0.12065 0.3048)
			(end 0.67945 0.3048)
			(stroke
				(width 0.1)
				(type default)
			)
			(layer "B.Fab")
		)
		(fp_line
			(start 0.12065 0.2794)
			(end 0.12065 0.3048)
			(stroke
				(width 0.1)
				(type default)
			)
			(layer "B.Fab")
		)
		(fp_line
			(start 0.12065 -0.2794)
			(end -0.12065 -0.2794)
			(stroke
				(width 0.1)
				(type default)
			)
			(layer "B.Fab")
		)
		(fp_line
			(start 0.12065 -0.305054)
			(end 0.12065 -0.2794)
			(stroke
				(width 0.1)
				(type default)
			)
			(layer "B.Fab")
		)
		(fp_line
			(start -0.120396 0.3048)
			(end -0.120396 0.2794)
			(stroke
				(width 0.1)
				(type default)
			)
			(layer "B.Fab")
		)
		(fp_line
			(start -0.120396 0.2794)
			(end 0.12065 0.2794)
			(stroke
				(width 0.1)
				(type default)
			)
			(layer "B.Fab")
		)
		(fp_line
			(start -0.12065 -0.2794)
			(end -0.12065 -0.3048)
			(stroke
				(width 0.1)
				(type default)
			)
			(layer "B.Fab")
		)
		(fp_line
			(start -0.12065 -0.3048)
			(end -0.67945 -0.3048)
			(stroke
				(width 0.1)
				(type default)
			)
			(layer "B.Fab")
		)
		(fp_line
			(start -0.67945 0.3048)
			(end -0.120396 0.3048)
			(stroke
				(width 0.1)
				(type default)
			)
			(layer "B.Fab")
		)
		(fp_line
			(start -0.67945 -0.3048)
			(end -0.67945 0.3048)
			(stroke
				(width 0.1)
				(type default)
			)
			(layer "B.Fab")
		)
		(pad "1" smd circle
			(at 0.40005 0)
			(size 0 0)
			(layers "B.Cu" "B.Mask" "B.Paste")
			(net "SMB_PDB_MISC_SDA_R")
		)
		(pad "2" smd circle
			(at -0.40005 0)
			(size 0 0)
			(layers "B.Cu" "B.Mask" "B.Paste")
			(net "SMB_PDB_MISC_SDA")
		)
	)
	(footprint ""
		(layer "B.Cu")
		(at 94.361 -76.327 180)
		(property "Reference" "R172"
			(at 0 0 0)
			(layer "B.SilkS")
			(hide yes)
			(effects
				(font
					(size 1.27 1.27)
				)
				(justify mirror)
			)
		)
		(property "Value" ""
			(at 0 0 0)
			(layer "B.Fab")
			(effects
				(font
					(size 1.27 1.27)
				)
				(justify mirror)
			)
		)
		(duplicate_pad_numbers_are_jumpers no)
		(fp_line
			(start 0.7874 0.4064)
			(end 0.7874 -0.4064)
			(stroke
				(width 0.1524)
				(type default)
			)
			(layer "B.SilkS")
		)
		(fp_line
			(start 0.7874 -0.4064)
			(end -0.7874 -0.4064)
			(stroke
				(width 0.1524)
				(type default)
			)
			(layer "B.SilkS")
		)
		(fp_line
			(start -0.7874 0.4064)
			(end 0.7874 0.4064)
			(stroke
				(width 0.1524)
				(type default)
			)
			(layer "B.SilkS")
		)
		(fp_line
			(start -0.7874 -0.4064)
			(end -0.7874 0.4064)
			(stroke
				(width 0.1524)
				(type default)
			)
			(layer "B.SilkS")
		)
		(fp_line
			(start 0.67945 0.3048)
			(end 0.67945 -0.305054)
			(stroke
				(width 0.1)
				(type default)
			)
			(layer "B.Fab")
		)
		(fp_line
			(start 0.67945 -0.305054)
			(end 0.12065 -0.305054)
			(stroke
				(width 0.1)
				(type default)
			)
			(layer "B.Fab")
		)
		(fp_line
			(start 0.12065 0.3048)
			(end 0.67945 0.3048)
			(stroke
				(width 0.1)
				(type default)
			)
			(layer "B.Fab")
		)
		(fp_line
			(start 0.12065 0.2794)
			(end 0.12065 0.3048)
			(stroke
				(width 0.1)
				(type default)
			)
			(layer "B.Fab")
		)
		(fp_line
			(start 0.12065 -0.2794)
			(end -0.12065 -0.2794)
			(stroke
				(width 0.1)
				(type default)
			)
			(layer "B.Fab")
		)
		(fp_line
			(start 0.12065 -0.305054)
			(end 0.12065 -0.2794)
			(stroke
				(width 0.1)
				(type default)
			)
			(layer "B.Fab")
		)
		(fp_line
			(start -0.120396 0.3048)
			(end -0.120396 0.2794)
			(stroke
				(width 0.1)
				(type default)
			)
			(layer "B.Fab")
		)
		(fp_line
			(start -0.120396 0.2794)
			(end 0.12065 0.2794)
			(stroke
				(width 0.1)
				(type default)
			)
			(layer "B.Fab")
		)
		(fp_line
			(start -0.12065 -0.2794)
			(end -0.12065 -0.3048)
			(stroke
				(width 0.1)
				(type default)
			)
			(layer "B.Fab")
		)
		(fp_line
			(start -0.12065 -0.3048)
			(end -0.67945 -0.3048)
			(stroke
				(width 0.1)
				(type default)
			)
			(layer "B.Fab")
		)
		(fp_line
			(start -0.67945 0.3048)
			(end -0.120396 0.3048)
			(stroke
				(width 0.1)
				(type default)
			)
			(layer "B.Fab")
		)
		(fp_line
			(start -0.67945 -0.3048)
			(end -0.67945 0.3048)
			(stroke
				(width 0.1)
				(type default)
			)
			(layer "B.Fab")
		)
		(pad "1" smd circle
			(at 0.40005 0)
			(size 0 0)
			(layers "B.Cu" "B.Mask" "B.Paste")
			(net "P12V_BRICK1_ALERT_N")
		)
		(pad "2" smd circle
			(at -0.40005 0)
			(size 0 0)
			(layers "B.Cu" "B.Mask" "B.Paste")
			(net "SMB_BRICK1_ALERT")
		)
	)
	(footprint ""
		(layer "B.Cu")
		(at 176.779174 -76.327 180)
		(property "Reference" "R197"
			(at 0 0 0)
			(layer "B.SilkS")
			(hide yes)
			(effects
				(font
					(size 1.27 1.27)
				)
				(justify mirror)
			)
		)
		(property "Value" ""
			(at 0 0 0)
			(layer "B.Fab")
			(effects
				(font
					(size 1.27 1.27)
				)
				(justify mirror)
			)
		)
		(duplicate_pad_numbers_are_jumpers no)
		(fp_line
			(start 0.7874 0.4064)
			(end 0.7874 -0.4064)
			(stroke
				(width 0.1524)
				(type default)
			)
			(layer "B.SilkS")
		)
		(fp_line
			(start 0.7874 -0.4064)
			(end -0.7874 -0.4064)
			(stroke
				(width 0.1524)
				(type default)
			)
			(layer "B.SilkS")
		)
		(fp_line
			(start -0.7874 0.4064)
			(end 0.7874 0.4064)
			(stroke
				(width 0.1524)
				(type default)
			)
			(layer "B.SilkS")
		)
		(fp_line
			(start -0.7874 -0.4064)
			(end -0.7874 0.4064)
			(stroke
				(width 0.1524)
				(type default)
			)
			(layer "B.SilkS")
		)
		(fp_line
			(start 0.67945 0.3048)
			(end 0.67945 -0.305054)
			(stroke
				(width 0.1)
				(type default)
			)
			(layer "B.Fab")
		)
		(fp_line
			(start 0.67945 -0.305054)
			(end 0.12065 -0.305054)
			(stroke
				(width 0.1)
				(type default)
			)
			(layer "B.Fab")
		)
		(fp_line
			(start 0.12065 0.3048)
			(end 0.67945 0.3048)
			(stroke
				(width 0.1)
				(type default)
			)
			(layer "B.Fab")
		)
		(fp_line
			(start 0.12065 0.2794)
			(end 0.12065 0.3048)
			(stroke
				(width 0.1)
				(type default)
			)
			(layer "B.Fab")
		)
		(fp_line
			(start 0.12065 -0.2794)
			(end -0.12065 -0.2794)
			(stroke
				(width 0.1)
				(type default)
			)
			(layer "B.Fab")
		)
		(fp_line
			(start 0.12065 -0.305054)
			(end 0.12065 -0.2794)
			(stroke
				(width 0.1)
				(type default)
			)
			(layer "B.Fab")
		)
		(fp_line
			(start -0.120396 0.3048)
			(end -0.120396 0.2794)
			(stroke
				(width 0.1)
				(type default)
			)
			(layer "B.Fab")
		)
		(fp_line
			(start -0.120396 0.2794)
			(end 0.12065 0.2794)
			(stroke
				(width 0.1)
				(type default)
			)
			(layer "B.Fab")
		)
		(fp_line
			(start -0.12065 -0.2794)
			(end -0.12065 -0.3048)
			(stroke
				(width 0.1)
				(type default)
			)
			(layer "B.Fab")
		)
		(fp_line
			(start -0.12065 -0.3048)
			(end -0.67945 -0.3048)
			(stroke
				(width 0.1)
				(type default)
			)
			(layer "B.Fab")
		)
		(fp_line
			(start -0.67945 0.3048)
			(end -0.120396 0.3048)
			(stroke
				(width 0.1)
				(type default)
			)
			(layer "B.Fab")
		)
		(fp_line
			(start -0.67945 -0.3048)
			(end -0.67945 0.3048)
			(stroke
				(width 0.1)
				(type default)
			)
			(layer "B.Fab")
		)
		(pad "1" smd circle
			(at 0.40005 0)
			(size 0 0)
			(layers "B.Cu" "B.Mask" "B.Paste")
			(net "P12V_BRICK2_ALERT_N")
		)
		(pad "2" smd circle
			(at -0.40005 0)
			(size 0 0)
			(layers "B.Cu" "B.Mask" "B.Paste")
			(net "SMB_BRICK2_ALERT")
		)
	)
	(footprint ""
		(layer "B.Cu")
		(at 202.946 -86.614 180)
		(property "Reference" "R101"
			(at 0 0 0)
			(layer "B.SilkS")
			(hide yes)
			(effects
				(font
					(size 1.27 1.27)
				)
				(justify mirror)
			)
		)
		(property "Value" ""
			(at 0 0 0)
			(layer "B.Fab")
			(effects
				(font
					(size 1.27 1.27)
				)
				(justify mirror)
			)
		)
		(duplicate_pad_numbers_are_jumpers no)
		(fp_line
			(start 0.7874 0.4064)
			(end 0.7874 -0.4064)
			(stroke
				(width 0.1524)
				(type default)
			)
			(layer "B.SilkS")
		)
		(fp_line
			(start 0.7874 -0.4064)
			(end -0.7874 -0.4064)
			(stroke
				(width 0.1524)
				(type default)
			)
			(layer "B.SilkS")
		)
		(fp_line
			(start -0.7874 0.4064)
			(end 0.7874 0.4064)
			(stroke
				(width 0.1524)
				(type default)
			)
			(layer "B.SilkS")
		)
		(fp_line
			(start -0.7874 -0.4064)
			(end -0.7874 0.4064)
			(stroke
				(width 0.1524)
				(type default)
			)
			(layer "B.SilkS")
		)
		(fp_line
			(start 0.67945 0.3048)
			(end 0.67945 -0.305054)
			(stroke
				(width 0.1)
				(type default)
			)
			(layer "B.Fab")
		)
		(fp_line
			(start 0.67945 -0.305054)
			(end 0.12065 -0.305054)
			(stroke
				(width 0.1)
				(type default)
			)
			(layer "B.Fab")
		)
		(fp_line
			(start 0.12065 0.3048)
			(end 0.67945 0.3048)
			(stroke
				(width 0.1)
				(type default)
			)
			(layer "B.Fab")
		)
		(fp_line
			(start 0.12065 0.2794)
			(end 0.12065 0.3048)
			(stroke
				(width 0.1)
				(type default)
			)
			(layer "B.Fab")
		)
		(fp_line
			(start 0.12065 -0.2794)
			(end -0.12065 -0.2794)
			(stroke
				(width 0.1)
				(type default)
			)
			(layer "B.Fab")
		)
		(fp_line
			(start 0.12065 -0.305054)
			(end 0.12065 -0.2794)
			(stroke
				(width 0.1)
				(type default)
			)
			(layer "B.Fab")
		)
		(fp_line
			(start -0.120396 0.3048)
			(end -0.120396 0.2794)
			(stroke
				(width 0.1)
				(type default)
			)
			(layer "B.Fab")
		)
		(fp_line
			(start -0.120396 0.2794)
			(end 0.12065 0.2794)
			(stroke
				(width 0.1)
				(type default)
			)
			(layer "B.Fab")
		)
		(fp_line
			(start -0.12065 -0.2794)
			(end -0.12065 -0.3048)
			(stroke
				(width 0.1)
				(type default)
			)
			(layer "B.Fab")
		)
		(fp_line
			(start -0.12065 -0.3048)
			(end -0.67945 -0.3048)
			(stroke
				(width 0.1)
				(type default)
			)
			(layer "B.Fab")
		)
		(fp_line
			(start -0.67945 0.3048)
			(end -0.120396 0.3048)
			(stroke
				(width 0.1)
				(type default)
			)
			(layer "B.Fab")
		)
		(fp_line
			(start -0.67945 -0.3048)
			(end -0.67945 0.3048)
			(stroke
				(width 0.1)
				(type default)
			)
			(layer "B.Fab")
		)
		(pad "1" smd circle
			(at 0.40005 0)
			(size 0 0)
			(layers "B.Cu" "B.Mask" "B.Paste")
			(net "PU_9543_0_INT1")
		)
		(pad "2" smd circle
			(at -0.40005 0)
			(size 0 0)
			(layers "B.Cu" "B.Mask" "B.Paste")
			(net "P3V3_AUX")
		)
	)
	(footprint ""
		(layer "B.Cu")
		(at 275.169122 -99.695)
		(property "Reference" "PC553"
			(at 0 0 0)
			(layer "B.SilkS")
			(hide yes)
			(effects
				(font
					(size 1.27 1.27)
				)
				(justify mirror)
			)
		)
		(property "Value" ""
			(at 0 0 0)
			(layer "B.Fab")
			(effects
				(font
					(size 1.27 1.27)
				)
				(justify mirror)
			)
		)
		(duplicate_pad_numbers_are_jumpers no)
		(fp_line
			(start -1.2954 -0.5842)
			(end -1.2954 0.5842)
			(stroke
				(width 0.1524)
				(type default)
			)
			(layer "B.SilkS")
		)
		(fp_line
			(start -1.2954 0.5842)
			(end 1.2954 0.5842)
			(stroke
				(width 0.1524)
				(type default)
			)
			(layer "B.SilkS")
		)
		(fp_line
			(start 1.2954 -0.5842)
			(end -1.2954 -0.5842)
			(stroke
				(width 0.1524)
				(type default)
			)
			(layer "B.SilkS")
		)
		(fp_line
			(start 1.2954 0.5842)
			(end 1.2954 -0.5842)
			(stroke
				(width 0.1524)
				(type default)
			)
			(layer "B.SilkS")
		)
		(fp_line
			(start -1.1938 -0.4064)
			(end -1.1938 0.4064)
			(stroke
				(width 0.1)
				(type default)
			)
			(layer "B.Fab")
		)
		(fp_line
			(start -1.1938 0.4064)
			(end -0.8636 0.4064)
			(stroke
				(width 0.1)
				(type default)
			)
			(layer "B.Fab")
		)
		(fp_line
			(start -0.8636 -0.4572)
			(end -0.8636 -0.4064)
			(stroke
				(width 0.1)
				(type default)
			)
			(layer "B.Fab")
		)
		(fp_line
			(start -0.8636 -0.4064)
			(end -1.1938 -0.4064)
			(stroke
				(width 0.1)
				(type default)
			)
			(layer "B.Fab")
		)
		(fp_line
			(start -0.8636 0.4064)
			(end -0.8636 0.4572)
			(stroke
				(width 0.1)
				(type default)
			)
			(layer "B.Fab")
		)
		(fp_line
			(start -0.8636 0.4572)
			(end 0.8636 0.4572)
			(stroke
				(width 0.1)
				(type default)
			)
			(layer "B.Fab")
		)
		(fp_line
			(start 0.8636 -0.4572)
			(end -0.8636 -0.4572)
			(stroke
				(width 0.1)
				(type default)
			)
			(layer "B.Fab")
		)
		(fp_line
			(start 0.8636 -0.4064)
			(end 0.8636 -0.4572)
			(stroke
				(width 0.1)
				(type default)
			)
			(layer "B.Fab")
		)
		(fp_line
			(start 0.8636 0.4064)
			(end 1.1938 0.4064)
			(stroke
				(width 0.1)
				(type default)
			)
			(layer "B.Fab")
		)
		(fp_line
			(start 0.8636 0.4572)
			(end 0.8636 0.4064)
			(stroke
				(width 0.1)
				(type default)
			)
			(layer "B.Fab")
		)
		(fp_line
			(start 1.1938 -0.4064)
			(end 0.8636 -0.4064)
			(stroke
				(width 0.1)
				(type default)
			)
			(layer "B.Fab")
		)
		(fp_line
			(start 1.1938 0.4064)
			(end 1.1938 -0.4064)
			(stroke
				(width 0.1)
				(type default)
			)
			(layer "B.Fab")
		)
		(pad "1" smd rect
			(at 0.7366 0 270)
			(size 0.7112 0.8128)
			(layers "B.Cu" "B.Mask" "B.Paste")
			(net "P52V_HS1_GATE_RC")
		)
		(pad "2" smd rect
			(at -0.7366 0 270)
			(size 0.7112 0.8128)
			(layers "B.Cu" "B.Mask" "B.Paste")
			(net "P52V_HS")
		)
	)
	(footprint ""
		(layer "B.Cu")
		(at 229.616 -95.504 90)
		(property "Reference" "C26"
			(at 0 0 90)
			(layer "B.SilkS")
			(hide yes)
			(effects
				(font
					(size 1.27 1.27)
				)
				(justify mirror)
			)
		)
		(property "Value" ""
			(at 0 0 90)
			(layer "B.Fab")
			(effects
				(font
					(size 1.27 1.27)
				)
				(justify mirror)
			)
		)
		(duplicate_pad_numbers_are_jumpers no)
		(fp_line
			(start 2.2098 -0.9398)
			(end -2.2098 -0.9398)
			(stroke
				(width 0.1524)
				(type default)
			)
			(layer "B.SilkS")
		)
		(fp_line
			(start -2.2098 -0.9398)
			(end -2.2098 0.9398)
			(stroke
				(width 0.1524)
				(type default)
			)
			(layer "B.SilkS")
		)
		(fp_line
			(start 2.2098 0.9398)
			(end 2.2098 -0.9398)
			(stroke
				(width 0.1524)
				(type default)
			)
			(layer "B.SilkS")
		)
		(fp_line
			(start -2.2098 0.9398)
			(end 2.2098 0.9398)
			(stroke
				(width 0.1524)
				(type default)
			)
			(layer "B.SilkS")
		)
		(fp_line
			(start 1.700022 -0.899922)
			(end -1.700022 -0.899922)
			(stroke
				(width 0.1)
				(type default)
			)
			(layer "B.Fab")
		)
		(fp_line
			(start -1.700022 -0.899922)
			(end -1.700022 0.899922)
			(stroke
				(width 0.1)
				(type default)
			)
			(layer "B.Fab")
		)
		(fp_line
			(start 1.700022 0.899922)
			(end 1.700022 -0.899922)
			(stroke
				(width 0.1)
				(type default)
			)
			(layer "B.Fab")
		)
		(fp_line
			(start -1.700022 0.899922)
			(end 1.700022 0.899922)
			(stroke
				(width 0.1)
				(type default)
			)
			(layer "B.Fab")
		)
		(pad "1" smd rect
			(at 1.4732 0 90)
			(size 1.1684 1.5748)
			(layers "B.Cu" "B.Mask" "B.Paste")
			(net "P52V_HS")
		)
		(pad "2" smd rect
			(at -1.4732 0 90)
			(size 1.1684 1.5748)
			(layers "B.Cu" "B.Mask" "B.Paste")
			(net "GND")
		)
	)
	(footprint ""
		(layer "B.Cu")
		(at 234.569 -95.504 90)
		(property "Reference" "C30"
			(at 0 0 90)
			(layer "B.SilkS")
			(hide yes)
			(effects
				(font
					(size 1.27 1.27)
				)
				(justify mirror)
			)
		)
		(property "Value" ""
			(at 0 0 90)
			(layer "B.Fab")
			(effects
				(font
					(size 1.27 1.27)
				)
				(justify mirror)
			)
		)
		(duplicate_pad_numbers_are_jumpers no)
		(fp_line
			(start 2.2098 -0.9398)
			(end -2.2098 -0.9398)
			(stroke
				(width 0.1524)
				(type default)
			)
			(layer "B.SilkS")
		)
		(fp_line
			(start -2.2098 -0.9398)
			(end -2.2098 0.9398)
			(stroke
				(width 0.1524)
				(type default)
			)
			(layer "B.SilkS")
		)
		(fp_line
			(start 2.2098 0.9398)
			(end 2.2098 -0.9398)
			(stroke
				(width 0.1524)
				(type default)
			)
			(layer "B.SilkS")
		)
		(fp_line
			(start -2.2098 0.9398)
			(end 2.2098 0.9398)
			(stroke
				(width 0.1524)
				(type default)
			)
			(layer "B.SilkS")
		)
		(fp_line
			(start 1.700022 -0.899922)
			(end -1.700022 -0.899922)
			(stroke
				(width 0.1)
				(type default)
			)
			(layer "B.Fab")
		)
		(fp_line
			(start -1.700022 -0.899922)
			(end -1.700022 0.899922)
			(stroke
				(width 0.1)
				(type default)
			)
			(layer "B.Fab")
		)
		(fp_line
			(start 1.700022 0.899922)
			(end 1.700022 -0.899922)
			(stroke
				(width 0.1)
				(type default)
			)
			(layer "B.Fab")
		)
		(fp_line
			(start -1.700022 0.899922)
			(end 1.700022 0.899922)
			(stroke
				(width 0.1)
				(type default)
			)
			(layer "B.Fab")
		)
		(pad "1" smd rect
			(at 1.4732 0 90)
			(size 1.1684 1.5748)
			(layers "B.Cu" "B.Mask" "B.Paste")
			(net "P52V_HS")
		)
		(pad "2" smd rect
			(at -1.4732 0 90)
			(size 1.1684 1.5748)
			(layers "B.Cu" "B.Mask" "B.Paste")
			(net "GND")
		)
	)
	(footprint ""
		(layer "B.Cu")
		(at 96.52 -78.613)
		(property "Reference" "R176"
			(at 0 0 0)
			(layer "B.SilkS")
			(hide yes)
			(effects
				(font
					(size 1.27 1.27)
				)
				(justify mirror)
			)
		)
		(property "Value" ""
			(at 0 0 0)
			(layer "B.Fab")
			(effects
				(font
					(size 1.27 1.27)
				)
				(justify mirror)
			)
		)
		(duplicate_pad_numbers_are_jumpers no)
		(fp_line
			(start -0.7874 -0.4064)
			(end -0.7874 0.4064)
			(stroke
				(width 0.1524)
				(type default)
			)
			(layer "B.SilkS")
		)
		(fp_line
			(start -0.7874 0.4064)
			(end 0.7874 0.4064)
			(stroke
				(width 0.1524)
				(type default)
			)
			(layer "B.SilkS")
		)
		(fp_line
			(start 0.7874 -0.4064)
			(end -0.7874 -0.4064)
			(stroke
				(width 0.1524)
				(type default)
			)
			(layer "B.SilkS")
		)
		(fp_line
			(start 0.7874 0.4064)
			(end 0.7874 -0.4064)
			(stroke
				(width 0.1524)
				(type default)
			)
			(layer "B.SilkS")
		)
		(fp_line
			(start -0.67945 -0.3048)
			(end -0.67945 0.3048)
			(stroke
				(width 0.1)
				(type default)
			)
			(layer "B.Fab")
		)
		(fp_line
			(start -0.67945 0.3048)
			(end -0.120396 0.3048)
			(stroke
				(width 0.1)
				(type default)
			)
			(layer "B.Fab")
		)
		(fp_line
			(start -0.12065 -0.3048)
			(end -0.67945 -0.3048)
			(stroke
				(width 0.1)
				(type default)
			)
			(layer "B.Fab")
		)
		(fp_line
			(start -0.12065 -0.2794)
			(end -0.12065 -0.3048)
			(stroke
				(width 0.1)
				(type default)
			)
			(layer "B.Fab")
		)
		(fp_line
			(start -0.120396 0.2794)
			(end 0.12065 0.2794)
			(stroke
				(width 0.1)
				(type default)
			)
			(layer "B.Fab")
		)
		(fp_line
			(start -0.120396 0.3048)
			(end -0.120396 0.2794)
			(stroke
				(width 0.1)
				(type default)
			)
			(layer "B.Fab")
		)
		(fp_line
			(start 0.12065 -0.305054)
			(end 0.12065 -0.2794)
			(stroke
				(width 0.1)
				(type default)
			)
			(layer "B.Fab")
		)
		(fp_line
			(start 0.12065 -0.2794)
			(end -0.12065 -0.2794)
			(stroke
				(width 0.1)
				(type default)
			)
			(layer "B.Fab")
		)
		(fp_line
			(start 0.12065 0.2794)
			(end 0.12065 0.3048)
			(stroke
				(width 0.1)
				(type default)
			)
			(layer "B.Fab")
		)
		(fp_line
			(start 0.12065 0.3048)
			(end 0.67945 0.3048)
			(stroke
				(width 0.1)
				(type default)
			)
			(layer "B.Fab")
		)
		(fp_line
			(start 0.67945 -0.305054)
			(end 0.12065 -0.305054)
			(stroke
				(width 0.1)
				(type default)
			)
			(layer "B.Fab")
		)
		(fp_line
			(start 0.67945 0.3048)
			(end 0.67945 -0.305054)
			(stroke
				(width 0.1)
				(type default)
			)
			(layer "B.Fab")
		)
		(pad "1" smd circle
			(at 0.40005 0 180)
			(size 0 0)
			(layers "B.Cu" "B.Mask" "B.Paste")
			(net "P3V3_AUX")
		)
		(pad "2" smd circle
			(at -0.40005 0 180)
			(size 0 0)
			(layers "B.Cu" "B.Mask" "B.Paste")
			(net "SMB_P52V_VPDB_SCL")
		)
	)
	(footprint ""
		(layer "B.Cu")
		(at 227.203 -70.993 -90)
		(property "Reference" "C47"
			(at 0 0 90)
			(layer "B.SilkS")
			(hide yes)
			(effects
				(font
					(size 1.27 1.27)
				)
				(justify mirror)
			)
		)
		(property "Value" ""
			(at 0 0 90)
			(layer "B.Fab")
			(effects
				(font
					(size 1.27 1.27)
				)
				(justify mirror)
			)
		)
		(duplicate_pad_numbers_are_jumpers no)
		(fp_line
			(start -0.7874 0.4064)
			(end 0.7874 0.4064)
			(stroke
				(width 0.1524)
				(type default)
			)
			(layer "B.SilkS")
		)
		(fp_line
			(start 0.7874 0.4064)
			(end 0.7874 -0.4064)
			(stroke
				(width 0.1524)
				(type default)
			)
			(layer "B.SilkS")
		)
		(fp_line
			(start -0.7874 -0.4064)
			(end -0.7874 0.4064)
			(stroke
				(width 0.1524)
				(type default)
			)
			(layer "B.SilkS")
		)
		(fp_line
			(start 0.7874 -0.4064)
			(end -0.7874 -0.4064)
			(stroke
				(width 0.1524)
				(type default)
			)
			(layer "B.SilkS")
		)
		(fp_line
			(start -0.67945 0.3048)
			(end -0.120396 0.3048)
			(stroke
				(width 0.1)
				(type default)
			)
			(layer "B.Fab")
		)
		(fp_line
			(start -0.120396 0.3048)
			(end -0.120396 0.2794)
			(stroke
				(width 0.1)
				(type default)
			)
			(layer "B.Fab")
		)
		(fp_line
			(start 0.12065 0.3048)
			(end 0.67945 0.3048)
			(stroke
				(width 0.1)
				(type default)
			)
			(layer "B.Fab")
		)
		(fp_line
			(start 0.67945 0.3048)
			(end 0.67945 -0.305054)
			(stroke
				(width 0.1)
				(type default)
			)
			(layer "B.Fab")
		)
		(fp_line
			(start -0.120396 0.2794)
			(end 0.12065 0.2794)
			(stroke
				(width 0.1)
				(type default)
			)
			(layer "B.Fab")
		)
		(fp_line
			(start 0.12065 0.2794)
			(end 0.12065 0.3048)
			(stroke
				(width 0.1)
				(type default)
			)
			(layer "B.Fab")
		)
		(fp_line
			(start -0.12065 -0.2794)
			(end -0.12065 -0.3048)
			(stroke
				(width 0.1)
				(type default)
			)
			(layer "B.Fab")
		)
		(fp_line
			(start 0.12065 -0.2794)
			(end -0.12065 -0.2794)
			(stroke
				(width 0.1)
				(type default)
			)
			(layer "B.Fab")
		)
		(fp_line
			(start -0.67945 -0.3048)
			(end -0.67945 0.3048)
			(stroke
				(width 0.1)
				(type default)
			)
			(layer "B.Fab")
		)
		(fp_line
			(start -0.12065 -0.3048)
			(end -0.67945 -0.3048)
			(stroke
				(width 0.1)
				(type default)
			)
			(layer "B.Fab")
		)
		(fp_line
			(start 0.12065 -0.305054)
			(end 0.12065 -0.2794)
			(stroke
				(width 0.1)
				(type default)
			)
			(layer "B.Fab")
		)
		(fp_line
			(start 0.67945 -0.305054)
			(end 0.12065 -0.305054)
			(stroke
				(width 0.1)
				(type default)
			)
			(layer "B.Fab")
		)
		(pad "1" smd circle
			(at 0.40005 0 90)
			(size 0 0)
			(layers "B.Cu" "B.Mask" "B.Paste")
			(net "P12V_BRICK_PWRGD_R_N")
		)
		(pad "2" smd circle
			(at -0.40005 0 90)
			(size 0 0)
			(layers "B.Cu" "B.Mask" "B.Paste")
			(net "GND")
		)
	)
	(footprint ""
		(layer "B.Cu")
		(at 239.395 -95.504 90)
		(property "Reference" "C34"
			(at 0 0 90)
			(layer "B.SilkS")
			(hide yes)
			(effects
				(font
					(size 1.27 1.27)
				)
				(justify mirror)
			)
		)
		(property "Value" ""
			(at 0 0 90)
			(layer "B.Fab")
			(effects
				(font
					(size 1.27 1.27)
				)
				(justify mirror)
			)
		)
		(duplicate_pad_numbers_are_jumpers no)
		(fp_line
			(start 2.2098 -0.9398)
			(end -2.2098 -0.9398)
			(stroke
				(width 0.1524)
				(type default)
			)
			(layer "B.SilkS")
		)
		(fp_line
			(start -2.2098 -0.9398)
			(end -2.2098 0.9398)
			(stroke
				(width 0.1524)
				(type default)
			)
			(layer "B.SilkS")
		)
		(fp_line
			(start 2.2098 0.9398)
			(end 2.2098 -0.9398)
			(stroke
				(width 0.1524)
				(type default)
			)
			(layer "B.SilkS")
		)
		(fp_line
			(start -2.2098 0.9398)
			(end 2.2098 0.9398)
			(stroke
				(width 0.1524)
				(type default)
			)
			(layer "B.SilkS")
		)
		(fp_line
			(start 1.700022 -0.899922)
			(end -1.700022 -0.899922)
			(stroke
				(width 0.1)
				(type default)
			)
			(layer "B.Fab")
		)
		(fp_line
			(start -1.700022 -0.899922)
			(end -1.700022 0.899922)
			(stroke
				(width 0.1)
				(type default)
			)
			(layer "B.Fab")
		)
		(fp_line
			(start 1.700022 0.899922)
			(end 1.700022 -0.899922)
			(stroke
				(width 0.1)
				(type default)
			)
			(layer "B.Fab")
		)
		(fp_line
			(start -1.700022 0.899922)
			(end 1.700022 0.899922)
			(stroke
				(width 0.1)
				(type default)
			)
			(layer "B.Fab")
		)
		(pad "1" smd rect
			(at 1.4732 0 90)
			(size 1.1684 1.5748)
			(layers "B.Cu" "B.Mask" "B.Paste")
			(net "P52V_HS")
		)
		(pad "2" smd rect
			(at -1.4732 0 90)
			(size 1.1684 1.5748)
			(layers "B.Cu" "B.Mask" "B.Paste")
			(net "GND")
		)
	)
	(footprint ""
		(layer "B.Cu")
		(at 174.493174 -77.597 180)
		(property "Reference" "C71"
			(at 0 0 0)
			(layer "B.SilkS")
			(hide yes)
			(effects
				(font
					(size 1.27 1.27)
				)
				(justify mirror)
			)
		)
		(property "Value" ""
			(at 0 0 0)
			(layer "B.Fab")
			(effects
				(font
					(size 1.27 1.27)
				)
				(justify mirror)
			)
		)
		(duplicate_pad_numbers_are_jumpers no)
		(fp_line
			(start 0.7874 0.4064)
			(end 0.7874 -0.4064)
			(stroke
				(width 0.1524)
				(type default)
			)
			(layer "B.SilkS")
		)
		(fp_line
			(start 0.7874 -0.4064)
			(end -0.7874 -0.4064)
			(stroke
				(width 0.1524)
				(type default)
			)
			(layer "B.SilkS")
		)
		(fp_line
			(start -0.7874 0.4064)
			(end 0.7874 0.4064)
			(stroke
				(width 0.1524)
				(type default)
			)
			(layer "B.SilkS")
		)
		(fp_line
			(start -0.7874 -0.4064)
			(end -0.7874 0.4064)
			(stroke
				(width 0.1524)
				(type default)
			)
			(layer "B.SilkS")
		)
		(fp_line
			(start 0.67945 0.3048)
			(end 0.67945 -0.305054)
			(stroke
				(width 0.1)
				(type default)
			)
			(layer "B.Fab")
		)
		(fp_line
			(start 0.67945 -0.305054)
			(end 0.12065 -0.305054)
			(stroke
				(width 0.1)
				(type default)
			)
			(layer "B.Fab")
		)
		(fp_line
			(start 0.12065 0.3048)
			(end 0.67945 0.3048)
			(stroke
				(width 0.1)
				(type default)
			)
			(layer "B.Fab")
		)
		(fp_line
			(start 0.12065 0.2794)
			(end 0.12065 0.3048)
			(stroke
				(width 0.1)
				(type default)
			)
			(layer "B.Fab")
		)
		(fp_line
			(start 0.12065 -0.2794)
			(end -0.12065 -0.2794)
			(stroke
				(width 0.1)
				(type default)
			)
			(layer "B.Fab")
		)
		(fp_line
			(start 0.12065 -0.305054)
			(end 0.12065 -0.2794)
			(stroke
				(width 0.1)
				(type default)
			)
			(layer "B.Fab")
		)
		(fp_line
			(start -0.120396 0.3048)
			(end -0.120396 0.2794)
			(stroke
				(width 0.1)
				(type default)
			)
			(layer "B.Fab")
		)
		(fp_line
			(start -0.120396 0.2794)
			(end 0.12065 0.2794)
			(stroke
				(width 0.1)
				(type default)
			)
			(layer "B.Fab")
		)
		(fp_line
			(start -0.12065 -0.2794)
			(end -0.12065 -0.3048)
			(stroke
				(width 0.1)
				(type default)
			)
			(layer "B.Fab")
		)
		(fp_line
			(start -0.12065 -0.3048)
			(end -0.67945 -0.3048)
			(stroke
				(width 0.1)
				(type default)
			)
			(layer "B.Fab")
		)
		(fp_line
			(start -0.67945 0.3048)
			(end -0.120396 0.3048)
			(stroke
				(width 0.1)
				(type default)
			)
			(layer "B.Fab")
		)
		(fp_line
			(start -0.67945 -0.3048)
			(end -0.67945 0.3048)
			(stroke
				(width 0.1)
				(type default)
			)
			(layer "B.Fab")
		)
		(pad "1" smd circle
			(at 0.40005 0)
			(size 0 0)
			(layers "B.Cu" "B.Mask" "B.Paste")
			(net "SMB_P52V_VPDB_SDA")
		)
		(pad "2" smd circle
			(at -0.40005 0)
			(size 0 0)
			(layers "B.Cu" "B.Mask" "B.Paste")
			(net "GND")
		)
	)
	(footprint ""
		(layer "B.Cu")
		(at 270.129 -30.734 -90)
		(property "Reference" "C101"
			(at 0 0 90)
			(layer "B.SilkS")
			(hide yes)
			(effects
				(font
					(size 1.27 1.27)
				)
				(justify mirror)
			)
		)
		(property "Value" ""
			(at 0 0 90)
			(layer "B.Fab")
			(effects
				(font
					(size 1.27 1.27)
				)
				(justify mirror)
			)
		)
		(duplicate_pad_numbers_are_jumpers no)
		(fp_line
			(start -1.524 0.762)
			(end 1.524 0.762)
			(stroke
				(width 0.1524)
				(type default)
			)
			(layer "B.SilkS")
		)
		(fp_line
			(start 1.524 0.762)
			(end 1.524 -0.762)
			(stroke
				(width 0.1524)
				(type default)
			)
			(layer "B.SilkS")
		)
		(fp_line
			(start -1.524 -0.762)
			(end -1.524 0.762)
			(stroke
				(width 0.1524)
				(type default)
			)
			(layer "B.SilkS")
		)
		(fp_line
			(start 1.524 -0.762)
			(end -1.524 -0.762)
			(stroke
				(width 0.1524)
				(type default)
			)
			(layer "B.SilkS")
		)
		(fp_line
			(start -1.1049 0.724916)
			(end -1.1049 -0.724916)
			(stroke
				(width 0.1)
				(type default)
			)
			(layer "B.Fab")
		)
		(fp_line
			(start 1.1049 0.724916)
			(end -1.1049 0.724916)
			(stroke
				(width 0.1)
				(type default)
			)
			(layer "B.Fab")
		)
		(fp_line
			(start -1.1049 -0.724916)
			(end 1.1049 -0.724916)
			(stroke
				(width 0.1)
				(type default)
			)
			(layer "B.Fab")
		)
		(fp_line
			(start 1.1049 -0.724916)
			(end 1.1049 0.724916)
			(stroke
				(width 0.1)
				(type default)
			)
			(layer "B.Fab")
		)
		(pad "1" smd rect
			(at 0.889 0 270)
			(size 1.016 1.27)
			(layers "B.Cu" "B.Mask" "B.Paste")
			(net "P52V_HS1_EN_DELAY")
		)
		(pad "2" smd rect
			(at -0.889 0 270)
			(size 1.016 1.27)
			(layers "B.Cu" "B.Mask" "B.Paste")
			(net "GND")
		)
	)
	(footprint ""
		(layer "B.Cu")
		(at 219.583 -90.043 -90)
		(property "Reference" "R41"
			(at 0 0 90)
			(layer "B.SilkS")
			(hide yes)
			(effects
				(font
					(size 1.27 1.27)
				)
				(justify mirror)
			)
		)
		(property "Value" ""
			(at 0 0 90)
			(layer "B.Fab")
			(effects
				(font
					(size 1.27 1.27)
				)
				(justify mirror)
			)
		)
		(duplicate_pad_numbers_are_jumpers no)
		(fp_line
			(start -0.7874 0.4064)
			(end 0.7874 0.4064)
			(stroke
				(width 0.1524)
				(type default)
			)
			(layer "B.SilkS")
		)
		(fp_line
			(start 0.7874 0.4064)
			(end 0.7874 -0.4064)
			(stroke
				(width 0.1524)
				(type default)
			)
			(layer "B.SilkS")
		)
		(fp_line
			(start -0.7874 -0.4064)
			(end -0.7874 0.4064)
			(stroke
				(width 0.1524)
				(type default)
			)
			(layer "B.SilkS")
		)
		(fp_line
			(start 0.7874 -0.4064)
			(end -0.7874 -0.4064)
			(stroke
				(width 0.1524)
				(type default)
			)
			(layer "B.SilkS")
		)
		(fp_line
			(start -0.67945 0.3048)
			(end -0.120396 0.3048)
			(stroke
				(width 0.1)
				(type default)
			)
			(layer "B.Fab")
		)
		(fp_line
			(start -0.120396 0.3048)
			(end -0.120396 0.2794)
			(stroke
				(width 0.1)
				(type default)
			)
			(layer "B.Fab")
		)
		(fp_line
			(start 0.12065 0.3048)
			(end 0.67945 0.3048)
			(stroke
				(width 0.1)
				(type default)
			)
			(layer "B.Fab")
		)
		(fp_line
			(start 0.67945 0.3048)
			(end 0.67945 -0.305054)
			(stroke
				(width 0.1)
				(type default)
			)
			(layer "B.Fab")
		)
		(fp_line
			(start -0.120396 0.2794)
			(end 0.12065 0.2794)
			(stroke
				(width 0.1)
				(type default)
			)
			(layer "B.Fab")
		)
		(fp_line
			(start 0.12065 0.2794)
			(end 0.12065 0.3048)
			(stroke
				(width 0.1)
				(type default)
			)
			(layer "B.Fab")
		)
		(fp_line
			(start -0.12065 -0.2794)
			(end -0.12065 -0.3048)
			(stroke
				(width 0.1)
				(type default)
			)
			(layer "B.Fab")
		)
		(fp_line
			(start 0.12065 -0.2794)
			(end -0.12065 -0.2794)
			(stroke
				(width 0.1)
				(type default)
			)
			(layer "B.Fab")
		)
		(fp_line
			(start -0.67945 -0.3048)
			(end -0.67945 0.3048)
			(stroke
				(width 0.1)
				(type default)
			)
			(layer "B.Fab")
		)
		(fp_line
			(start -0.12065 -0.3048)
			(end -0.67945 -0.3048)
			(stroke
				(width 0.1)
				(type default)
			)
			(layer "B.Fab")
		)
		(fp_line
			(start 0.12065 -0.305054)
			(end 0.12065 -0.2794)
			(stroke
				(width 0.1)
				(type default)
			)
			(layer "B.Fab")
		)
		(fp_line
			(start 0.67945 -0.305054)
			(end 0.12065 -0.305054)
			(stroke
				(width 0.1)
				(type default)
			)
			(layer "B.Fab")
		)
		(pad "1" smd circle
			(at 0.40005 0 90)
			(size 0 0)
			(layers "B.Cu" "B.Mask" "B.Paste")
			(net "SMB_FRU_DAT")
		)
		(pad "2" smd circle
			(at -0.40005 0 90)
			(size 0 0)
			(layers "B.Cu" "B.Mask" "B.Paste")
			(net "SMB_VPDB_MISC_SDA")
		)
	)
	(footprint ""
		(layer "B.Cu")
		(at 296.5704 -49.0982 90)
		(property "Reference" "R5890"
			(at 0 0 90)
			(layer "B.SilkS")
			(hide yes)
			(effects
				(font
					(size 1.27 1.27)
				)
				(justify mirror)
			)
		)
		(property "Value" ""
			(at 0 0 90)
			(layer "B.Fab")
			(effects
				(font
					(size 1.27 1.27)
				)
				(justify mirror)
			)
		)
		(duplicate_pad_numbers_are_jumpers no)
		(fp_line
			(start 1.651 -0.8382)
			(end -1.651 -0.8382)
			(stroke
				(width 0.1524)
				(type default)
			)
			(layer "B.SilkS")
		)
		(fp_line
			(start -1.651 -0.8382)
			(end -1.651 0.8382)
			(stroke
				(width 0.1524)
				(type default)
			)
			(layer "B.SilkS")
		)
		(fp_line
			(start 1.651 0.8382)
			(end 1.651 -0.8382)
			(stroke
				(width 0.1524)
				(type default)
			)
			(layer "B.SilkS")
		)
		(fp_line
			(start -1.651 0.8382)
			(end 1.651 0.8382)
			(stroke
				(width 0.1524)
				(type default)
			)
			(layer "B.SilkS")
		)
		(fp_line
			(start 1.559814 -0.7366)
			(end 1.559814 0.7366)
			(stroke
				(width 0.1)
				(type default)
			)
			(layer "B.Fab")
		)
		(fp_line
			(start 1.524 -0.7366)
			(end 1.559814 -0.7366)
			(stroke
				(width 0.1)
				(type default)
			)
			(layer "B.Fab")
		)
		(fp_line
			(start -1.524 -0.7366)
			(end 1.524 -0.7366)
			(stroke
				(width 0.1)
				(type default)
			)
			(layer "B.Fab")
		)
		(fp_line
			(start -1.560576 -0.7366)
			(end -1.524 -0.7366)
			(stroke
				(width 0.1)
				(type default)
			)
			(layer "B.Fab")
		)
		(fp_line
			(start 1.559814 0.7366)
			(end 1.524 0.7366)
			(stroke
				(width 0.1)
				(type default)
			)
			(layer "B.Fab")
		)
		(fp_line
			(start 1.524 0.7366)
			(end -1.524 0.7366)
			(stroke
				(width 0.1)
				(type default)
			)
			(layer "B.Fab")
		)
		(fp_line
			(start -1.524 0.7366)
			(end -1.560576 0.7366)
			(stroke
				(width 0.1)
				(type default)
			)
			(layer "B.Fab")
		)
		(fp_line
			(start -1.560576 0.7366)
			(end -1.560576 -0.7366)
			(stroke
				(width 0.1)
				(type default)
			)
			(layer "B.Fab")
		)
		(pad "1" smd rect
			(at 0.94996 0 90)
			(size 1.1176 1.3716)
			(layers "B.Cu" "B.Mask" "B.Paste")
			(net "P52V_1")
		)
		(pad "2" smd rect
			(at -0.94996 0 90)
			(size 1.1176 1.3716)
			(layers "B.Cu" "B.Mask" "B.Paste")
			(net "P52V_1_R")
		)
	)
	(footprint ""
		(layer "B.Cu")
		(at 229.489 -82.296 -90)
		(property "Reference" "R27"
			(at 0 0 90)
			(layer "B.SilkS")
			(hide yes)
			(effects
				(font
					(size 1.27 1.27)
				)
				(justify mirror)
			)
		)
		(property "Value" ""
			(at 0 0 90)
			(layer "B.Fab")
			(effects
				(font
					(size 1.27 1.27)
				)
				(justify mirror)
			)
		)
		(duplicate_pad_numbers_are_jumpers no)
		(fp_line
			(start -0.7874 0.4064)
			(end 0.7874 0.4064)
			(stroke
				(width 0.1524)
				(type default)
			)
			(layer "B.SilkS")
		)
		(fp_line
			(start 0.7874 0.4064)
			(end 0.7874 -0.4064)
			(stroke
				(width 0.1524)
				(type default)
			)
			(layer "B.SilkS")
		)
		(fp_line
			(start -0.7874 -0.4064)
			(end -0.7874 0.4064)
			(stroke
				(width 0.1524)
				(type default)
			)
			(layer "B.SilkS")
		)
		(fp_line
			(start 0.7874 -0.4064)
			(end -0.7874 -0.4064)
			(stroke
				(width 0.1524)
				(type default)
			)
			(layer "B.SilkS")
		)
		(fp_line
			(start -0.67945 0.3048)
			(end -0.120396 0.3048)
			(stroke
				(width 0.1)
				(type default)
			)
			(layer "B.Fab")
		)
		(fp_line
			(start -0.120396 0.3048)
			(end -0.120396 0.2794)
			(stroke
				(width 0.1)
				(type default)
			)
			(layer "B.Fab")
		)
		(fp_line
			(start 0.12065 0.3048)
			(end 0.67945 0.3048)
			(stroke
				(width 0.1)
				(type default)
			)
			(layer "B.Fab")
		)
		(fp_line
			(start 0.67945 0.3048)
			(end 0.67945 -0.305054)
			(stroke
				(width 0.1)
				(type default)
			)
			(layer "B.Fab")
		)
		(fp_line
			(start -0.120396 0.2794)
			(end 0.12065 0.2794)
			(stroke
				(width 0.1)
				(type default)
			)
			(layer "B.Fab")
		)
		(fp_line
			(start 0.12065 0.2794)
			(end 0.12065 0.3048)
			(stroke
				(width 0.1)
				(type default)
			)
			(layer "B.Fab")
		)
		(fp_line
			(start -0.12065 -0.2794)
			(end -0.12065 -0.3048)
			(stroke
				(width 0.1)
				(type default)
			)
			(layer "B.Fab")
		)
		(fp_line
			(start 0.12065 -0.2794)
			(end -0.12065 -0.2794)
			(stroke
				(width 0.1)
				(type default)
			)
			(layer "B.Fab")
		)
		(fp_line
			(start -0.67945 -0.3048)
			(end -0.67945 0.3048)
			(stroke
				(width 0.1)
				(type default)
			)
			(layer "B.Fab")
		)
		(fp_line
			(start -0.12065 -0.3048)
			(end -0.67945 -0.3048)
			(stroke
				(width 0.1)
				(type default)
			)
			(layer "B.Fab")
		)
		(fp_line
			(start 0.12065 -0.305054)
			(end 0.12065 -0.2794)
			(stroke
				(width 0.1)
				(type default)
			)
			(layer "B.Fab")
		)
		(fp_line
			(start 0.67945 -0.305054)
			(end 0.12065 -0.305054)
			(stroke
				(width 0.1)
				(type default)
			)
			(layer "B.Fab")
		)
		(pad "1" smd circle
			(at 0.40005 0 90)
			(size 0 0)
			(layers "B.Cu" "B.Mask" "B.Paste")
			(net "PWRGD_P3V3_AUX_MB_BUF_R")
		)
		(pad "2" smd circle
			(at -0.40005 0 90)
			(size 0 0)
			(layers "B.Cu" "B.Mask" "B.Paste")
			(net "PWRGD_P3V3_AUX_MB_BUF")
		)
	)
	(footprint ""
		(layer "B.Cu")
		(at 293.4589 -142.52956)
		(property "Reference" ""
			(at 0 0 0)
			(layer "B.SilkS")
			(hide yes)
			(effects
				(font
					(size 1.27 1.27)
				)
				(justify mirror)
			)
		)
		(property "Value" ""
			(at 0 0 0)
			(layer "B.Fab")
			(effects
				(font
					(size 1.27 1.27)
				)
				(justify mirror)
			)
		)
		(duplicate_pad_numbers_are_jumpers no)
		(pad "1" smd circle
			(at 0 0 180)
			(size 0.9906 0.9906)
			(layers "B.Cu" "B.Mask" "B.Paste")
			(net "Net_151")
		)
		(zone
			(layer "B.Cu")
			(hatch none 0.5)
			(connect_pads
				(clearance 0)
			)
			(min_thickness 0.25)
			(keepout
				(tracks not_allowed)
				(vias allowed)
				(pads allowed)
				(copperpour not_allowed)
				(footprints allowed)
			)
			(placement
				(enabled no)
				(sheetname "")
			)
			(fill
				(thermal_gap 0.5)
				(thermal_bridge_width 0.5)
				(island_removal_mode 0)
			)
			(polygon
				(pts
					(arc
						(start 295.0845 -142.52956)
						(mid 291.8333 -142.52956)
						(end 295.0845 -142.52956)
					)
				)
			)
		)
	)
	(footprint ""
		(layer "B.Cu")
		(at 274.3962 -103.759 90)
		(property "Reference" "R5862"
			(at 0 0 90)
			(layer "B.SilkS")
			(hide yes)
			(effects
				(font
					(size 1.27 1.27)
				)
				(justify mirror)
			)
		)
		(property "Value" ""
			(at 0 0 90)
			(layer "B.Fab")
			(effects
				(font
					(size 1.27 1.27)
				)
				(justify mirror)
			)
		)
		(duplicate_pad_numbers_are_jumpers no)
		(fp_line
			(start 0.7874 -0.4064)
			(end -0.7874 -0.4064)
			(stroke
				(width 0.1524)
				(type default)
			)
			(layer "B.SilkS")
		)
		(fp_line
			(start -0.7874 -0.4064)
			(end -0.7874 0.4064)
			(stroke
				(width 0.1524)
				(type default)
			)
			(layer "B.SilkS")
		)
		(fp_line
			(start 0.7874 0.4064)
			(end 0.7874 -0.4064)
			(stroke
				(width 0.1524)
				(type default)
			)
			(layer "B.SilkS")
		)
		(fp_line
			(start -0.7874 0.4064)
			(end 0.7874 0.4064)
			(stroke
				(width 0.1524)
				(type default)
			)
			(layer "B.SilkS")
		)
		(fp_line
			(start 0.67945 -0.305054)
			(end 0.12065 -0.305054)
			(stroke
				(width 0.1)
				(type default)
			)
			(layer "B.Fab")
		)
		(fp_line
			(start 0.12065 -0.305054)
			(end 0.12065 -0.2794)
			(stroke
				(width 0.1)
				(type default)
			)
			(layer "B.Fab")
		)
		(fp_line
			(start -0.12065 -0.3048)
			(end -0.67945 -0.3048)
			(stroke
				(width 0.1)
				(type default)
			)
			(layer "B.Fab")
		)
		(fp_line
			(start -0.67945 -0.3048)
			(end -0.67945 0.3048)
			(stroke
				(width 0.1)
				(type default)
			)
			(layer "B.Fab")
		)
		(fp_line
			(start 0.12065 -0.2794)
			(end -0.12065 -0.2794)
			(stroke
				(width 0.1)
				(type default)
			)
			(layer "B.Fab")
		)
		(fp_line
			(start -0.12065 -0.2794)
			(end -0.12065 -0.3048)
			(stroke
				(width 0.1)
				(type default)
			)
			(layer "B.Fab")
		)
		(fp_line
			(start 0.12065 0.2794)
			(end 0.12065 0.3048)
			(stroke
				(width 0.1)
				(type default)
			)
			(layer "B.Fab")
		)
		(fp_line
			(start -0.120396 0.2794)
			(end 0.12065 0.2794)
			(stroke
				(width 0.1)
				(type default)
			)
			(layer "B.Fab")
		)
		(fp_line
			(start 0.67945 0.3048)
			(end 0.67945 -0.305054)
			(stroke
				(width 0.1)
				(type default)
			)
			(layer "B.Fab")
		)
		(fp_line
			(start 0.12065 0.3048)
			(end 0.67945 0.3048)
			(stroke
				(width 0.1)
				(type default)
			)
			(layer "B.Fab")
		)
		(fp_line
			(start -0.120396 0.3048)
			(end -0.120396 0.2794)
			(stroke
				(width 0.1)
				(type default)
			)
			(layer "B.Fab")
		)
		(fp_line
			(start -0.67945 0.3048)
			(end -0.120396 0.3048)
			(stroke
				(width 0.1)
				(type default)
			)
			(layer "B.Fab")
		)
		(pad "1" smd circle
			(at 0.40005 0 270)
			(size 0 0)
			(layers "B.Cu" "B.Mask" "B.Paste")
			(net "P52V_HS1_GATE1_R")
		)
		(pad "2" smd circle
			(at -0.40005 0 270)
			(size 0 0)
			(layers "B.Cu" "B.Mask" "B.Paste")
			(net "P52V_HS1_4287_GATE_R")
		)
	)
	(footprint ""
		(layer "B.Cu")
		(at 189.611 -91.821)
		(property "Reference" "C48"
			(at 0 0 0)
			(layer "B.SilkS")
			(hide yes)
			(effects
				(font
					(size 1.27 1.27)
				)
				(justify mirror)
			)
		)
		(property "Value" ""
			(at 0 0 0)
			(layer "B.Fab")
			(effects
				(font
					(size 1.27 1.27)
				)
				(justify mirror)
			)
		)
		(duplicate_pad_numbers_are_jumpers no)
		(fp_line
			(start -0.7874 -0.4064)
			(end -0.7874 0.4064)
			(stroke
				(width 0.1524)
				(type default)
			)
			(layer "B.SilkS")
		)
		(fp_line
			(start -0.7874 0.4064)
			(end 0.7874 0.4064)
			(stroke
				(width 0.1524)
				(type default)
			)
			(layer "B.SilkS")
		)
		(fp_line
			(start 0.7874 -0.4064)
			(end -0.7874 -0.4064)
			(stroke
				(width 0.1524)
				(type default)
			)
			(layer "B.SilkS")
		)
		(fp_line
			(start 0.7874 0.4064)
			(end 0.7874 -0.4064)
			(stroke
				(width 0.1524)
				(type default)
			)
			(layer "B.SilkS")
		)
		(fp_line
			(start -0.67945 -0.3048)
			(end -0.67945 0.3048)
			(stroke
				(width 0.1)
				(type default)
			)
			(layer "B.Fab")
		)
		(fp_line
			(start -0.67945 0.3048)
			(end -0.120396 0.3048)
			(stroke
				(width 0.1)
				(type default)
			)
			(layer "B.Fab")
		)
		(fp_line
			(start -0.12065 -0.3048)
			(end -0.67945 -0.3048)
			(stroke
				(width 0.1)
				(type default)
			)
			(layer "B.Fab")
		)
		(fp_line
			(start -0.12065 -0.2794)
			(end -0.12065 -0.3048)
			(stroke
				(width 0.1)
				(type default)
			)
			(layer "B.Fab")
		)
		(fp_line
			(start -0.120396 0.2794)
			(end 0.12065 0.2794)
			(stroke
				(width 0.1)
				(type default)
			)
			(layer "B.Fab")
		)
		(fp_line
			(start -0.120396 0.3048)
			(end -0.120396 0.2794)
			(stroke
				(width 0.1)
				(type default)
			)
			(layer "B.Fab")
		)
		(fp_line
			(start 0.12065 -0.305054)
			(end 0.12065 -0.2794)
			(stroke
				(width 0.1)
				(type default)
			)
			(layer "B.Fab")
		)
		(fp_line
			(start 0.12065 -0.2794)
			(end -0.12065 -0.2794)
			(stroke
				(width 0.1)
				(type default)
			)
			(layer "B.Fab")
		)
		(fp_line
			(start 0.12065 0.2794)
			(end 0.12065 0.3048)
			(stroke
				(width 0.1)
				(type default)
			)
			(layer "B.Fab")
		)
		(fp_line
			(start 0.12065 0.3048)
			(end 0.67945 0.3048)
			(stroke
				(width 0.1)
				(type default)
			)
			(layer "B.Fab")
		)
		(fp_line
			(start 0.67945 -0.305054)
			(end 0.12065 -0.305054)
			(stroke
				(width 0.1)
				(type default)
			)
			(layer "B.Fab")
		)
		(fp_line
			(start 0.67945 0.3048)
			(end 0.67945 -0.305054)
			(stroke
				(width 0.1)
				(type default)
			)
			(layer "B.Fab")
		)
		(pad "1" smd circle
			(at 0.40005 0 180)
			(size 0 0)
			(layers "B.Cu" "B.Mask" "B.Paste")
			(net "P3V3_AUX")
		)
		(pad "2" smd circle
			(at -0.40005 0 180)
			(size 0 0)
			(layers "B.Cu" "B.Mask" "B.Paste")
			(net "GND")
		)
	)
	(footprint ""
		(layer "B.Cu")
		(at 277.876 -101.981)
		(property "Reference" "PR26"
			(at 0 0 0)
			(layer "B.SilkS")
			(hide yes)
			(effects
				(font
					(size 1.27 1.27)
				)
				(justify mirror)
			)
		)
		(property "Value" ""
			(at 0 0 0)
			(layer "B.Fab")
			(effects
				(font
					(size 1.27 1.27)
				)
				(justify mirror)
			)
		)
		(duplicate_pad_numbers_are_jumpers no)
		(fp_line
			(start -0.7874 -0.4064)
			(end -0.7874 0.4064)
			(stroke
				(width 0.1524)
				(type default)
			)
			(layer "B.SilkS")
		)
		(fp_line
			(start -0.7874 0.4064)
			(end 0.7874 0.4064)
			(stroke
				(width 0.1524)
				(type default)
			)
			(layer "B.SilkS")
		)
		(fp_line
			(start 0.7874 -0.4064)
			(end -0.7874 -0.4064)
			(stroke
				(width 0.1524)
				(type default)
			)
			(layer "B.SilkS")
		)
		(fp_line
			(start 0.7874 0.4064)
			(end 0.7874 -0.4064)
			(stroke
				(width 0.1524)
				(type default)
			)
			(layer "B.SilkS")
		)
		(fp_line
			(start -0.67945 -0.3048)
			(end -0.67945 0.3048)
			(stroke
				(width 0.1)
				(type default)
			)
			(layer "B.Fab")
		)
		(fp_line
			(start -0.67945 0.3048)
			(end -0.120396 0.3048)
			(stroke
				(width 0.1)
				(type default)
			)
			(layer "B.Fab")
		)
		(fp_line
			(start -0.12065 -0.3048)
			(end -0.67945 -0.3048)
			(stroke
				(width 0.1)
				(type default)
			)
			(layer "B.Fab")
		)
		(fp_line
			(start -0.12065 -0.2794)
			(end -0.12065 -0.3048)
			(stroke
				(width 0.1)
				(type default)
			)
			(layer "B.Fab")
		)
		(fp_line
			(start -0.120396 0.2794)
			(end 0.12065 0.2794)
			(stroke
				(width 0.1)
				(type default)
			)
			(layer "B.Fab")
		)
		(fp_line
			(start -0.120396 0.3048)
			(end -0.120396 0.2794)
			(stroke
				(width 0.1)
				(type default)
			)
			(layer "B.Fab")
		)
		(fp_line
			(start 0.12065 -0.305054)
			(end 0.12065 -0.2794)
			(stroke
				(width 0.1)
				(type default)
			)
			(layer "B.Fab")
		)
		(fp_line
			(start 0.12065 -0.2794)
			(end -0.12065 -0.2794)
			(stroke
				(width 0.1)
				(type default)
			)
			(layer "B.Fab")
		)
		(fp_line
			(start 0.12065 0.2794)
			(end 0.12065 0.3048)
			(stroke
				(width 0.1)
				(type default)
			)
			(layer "B.Fab")
		)
		(fp_line
			(start 0.12065 0.3048)
			(end 0.67945 0.3048)
			(stroke
				(width 0.1)
				(type default)
			)
			(layer "B.Fab")
		)
		(fp_line
			(start 0.67945 -0.305054)
			(end 0.12065 -0.305054)
			(stroke
				(width 0.1)
				(type default)
			)
			(layer "B.Fab")
		)
		(fp_line
			(start 0.67945 0.3048)
			(end 0.67945 -0.305054)
			(stroke
				(width 0.1)
				(type default)
			)
			(layer "B.Fab")
		)
		(pad "1" smd rect
			(at 0.40005 0)
			(size 0.4572 0.508)
			(layers "B.Cu" "B.Mask" "B.Paste")
			(net "P52V_HS1_GATE_R1")
		)
		(pad "2" smd rect
			(at -0.40005 0)
			(size 0.4572 0.508)
			(layers "B.Cu" "B.Mask" "B.Paste")
			(net "P52V_HS1_4287_GATE_R")
		)
	)
	(footprint ""
		(layer "B.Cu")
		(at 208.534 -69.723 -90)
		(property "Reference" "R118"
			(at 0 0 90)
			(layer "B.SilkS")
			(hide yes)
			(effects
				(font
					(size 1.27 1.27)
				)
				(justify mirror)
			)
		)
		(property "Value" ""
			(at 0 0 90)
			(layer "B.Fab")
			(effects
				(font
					(size 1.27 1.27)
				)
				(justify mirror)
			)
		)
		(duplicate_pad_numbers_are_jumpers no)
		(fp_line
			(start -0.7874 0.4064)
			(end 0.7874 0.4064)
			(stroke
				(width 0.1524)
				(type default)
			)
			(layer "B.SilkS")
		)
		(fp_line
			(start 0.7874 0.4064)
			(end 0.7874 -0.4064)
			(stroke
				(width 0.1524)
				(type default)
			)
			(layer "B.SilkS")
		)
		(fp_line
			(start -0.7874 -0.4064)
			(end -0.7874 0.4064)
			(stroke
				(width 0.1524)
				(type default)
			)
			(layer "B.SilkS")
		)
		(fp_line
			(start 0.7874 -0.4064)
			(end -0.7874 -0.4064)
			(stroke
				(width 0.1524)
				(type default)
			)
			(layer "B.SilkS")
		)
		(fp_line
			(start -0.67945 0.3048)
			(end -0.120396 0.3048)
			(stroke
				(width 0.1)
				(type default)
			)
			(layer "B.Fab")
		)
		(fp_line
			(start -0.120396 0.3048)
			(end -0.120396 0.2794)
			(stroke
				(width 0.1)
				(type default)
			)
			(layer "B.Fab")
		)
		(fp_line
			(start 0.12065 0.3048)
			(end 0.67945 0.3048)
			(stroke
				(width 0.1)
				(type default)
			)
			(layer "B.Fab")
		)
		(fp_line
			(start 0.67945 0.3048)
			(end 0.67945 -0.305054)
			(stroke
				(width 0.1)
				(type default)
			)
			(layer "B.Fab")
		)
		(fp_line
			(start -0.120396 0.2794)
			(end 0.12065 0.2794)
			(stroke
				(width 0.1)
				(type default)
			)
			(layer "B.Fab")
		)
		(fp_line
			(start 0.12065 0.2794)
			(end 0.12065 0.3048)
			(stroke
				(width 0.1)
				(type default)
			)
			(layer "B.Fab")
		)
		(fp_line
			(start -0.12065 -0.2794)
			(end -0.12065 -0.3048)
			(stroke
				(width 0.1)
				(type default)
			)
			(layer "B.Fab")
		)
		(fp_line
			(start 0.12065 -0.2794)
			(end -0.12065 -0.2794)
			(stroke
				(width 0.1)
				(type default)
			)
			(layer "B.Fab")
		)
		(fp_line
			(start -0.67945 -0.3048)
			(end -0.67945 0.3048)
			(stroke
				(width 0.1)
				(type default)
			)
			(layer "B.Fab")
		)
		(fp_line
			(start -0.12065 -0.3048)
			(end -0.67945 -0.3048)
			(stroke
				(width 0.1)
				(type default)
			)
			(layer "B.Fab")
		)
		(fp_line
			(start 0.12065 -0.305054)
			(end 0.12065 -0.2794)
			(stroke
				(width 0.1)
				(type default)
			)
			(layer "B.Fab")
		)
		(fp_line
			(start 0.67945 -0.305054)
			(end 0.12065 -0.305054)
			(stroke
				(width 0.1)
				(type default)
			)
			(layer "B.Fab")
		)
		(pad "1" smd circle
			(at 0.40005 0 90)
			(size 0 0)
			(layers "B.Cu" "B.Mask" "B.Paste")
			(net "SMB_VPDB_MISC_SCL")
		)
		(pad "2" smd circle
			(at -0.40005 0 90)
			(size 0 0)
			(layers "B.Cu" "B.Mask" "B.Paste")
			(net "SMB_VPDB_IOEXP_SCL")
		)
	)
	(footprint ""
		(layer "B.Cu")
		(at 217.424 -67.183 90)
		(property "Reference" "R138"
			(at 0 0 90)
			(layer "B.SilkS")
			(hide yes)
			(effects
				(font
					(size 1.27 1.27)
				)
				(justify mirror)
			)
		)
		(property "Value" ""
			(at 0 0 90)
			(layer "B.Fab")
			(effects
				(font
					(size 1.27 1.27)
				)
				(justify mirror)
			)
		)
		(duplicate_pad_numbers_are_jumpers no)
		(fp_line
			(start 0.7874 -0.4064)
			(end -0.7874 -0.4064)
			(stroke
				(width 0.1524)
				(type default)
			)
			(layer "B.SilkS")
		)
		(fp_line
			(start -0.7874 -0.4064)
			(end -0.7874 0.4064)
			(stroke
				(width 0.1524)
				(type default)
			)
			(layer "B.SilkS")
		)
		(fp_line
			(start 0.7874 0.4064)
			(end 0.7874 -0.4064)
			(stroke
				(width 0.1524)
				(type default)
			)
			(layer "B.SilkS")
		)
		(fp_line
			(start -0.7874 0.4064)
			(end 0.7874 0.4064)
			(stroke
				(width 0.1524)
				(type default)
			)
			(layer "B.SilkS")
		)
		(fp_line
			(start 0.67945 -0.305054)
			(end 0.12065 -0.305054)
			(stroke
				(width 0.1)
				(type default)
			)
			(layer "B.Fab")
		)
		(fp_line
			(start 0.12065 -0.305054)
			(end 0.12065 -0.2794)
			(stroke
				(width 0.1)
				(type default)
			)
			(layer "B.Fab")
		)
		(fp_line
			(start -0.12065 -0.3048)
			(end -0.67945 -0.3048)
			(stroke
				(width 0.1)
				(type default)
			)
			(layer "B.Fab")
		)
		(fp_line
			(start -0.67945 -0.3048)
			(end -0.67945 0.3048)
			(stroke
				(width 0.1)
				(type default)
			)
			(layer "B.Fab")
		)
		(fp_line
			(start 0.12065 -0.2794)
			(end -0.12065 -0.2794)
			(stroke
				(width 0.1)
				(type default)
			)
			(layer "B.Fab")
		)
		(fp_line
			(start -0.12065 -0.2794)
			(end -0.12065 -0.3048)
			(stroke
				(width 0.1)
				(type default)
			)
			(layer "B.Fab")
		)
		(fp_line
			(start 0.12065 0.2794)
			(end 0.12065 0.3048)
			(stroke
				(width 0.1)
				(type default)
			)
			(layer "B.Fab")
		)
		(fp_line
			(start -0.120396 0.2794)
			(end 0.12065 0.2794)
			(stroke
				(width 0.1)
				(type default)
			)
			(layer "B.Fab")
		)
		(fp_line
			(start 0.67945 0.3048)
			(end 0.67945 -0.305054)
			(stroke
				(width 0.1)
				(type default)
			)
			(layer "B.Fab")
		)
		(fp_line
			(start 0.12065 0.3048)
			(end 0.67945 0.3048)
			(stroke
				(width 0.1)
				(type default)
			)
			(layer "B.Fab")
		)
		(fp_line
			(start -0.120396 0.3048)
			(end -0.120396 0.2794)
			(stroke
				(width 0.1)
				(type default)
			)
			(layer "B.Fab")
		)
		(fp_line
			(start -0.67945 0.3048)
			(end -0.120396 0.3048)
			(stroke
				(width 0.1)
				(type default)
			)
			(layer "B.Fab")
		)
		(pad "1" smd circle
			(at 0.40005 0 270)
			(size 0 0)
			(layers "B.Cu" "B.Mask" "B.Paste")
			(net "BOARD_ID_0")
		)
		(pad "2" smd circle
			(at -0.40005 0 270)
			(size 0 0)
			(layers "B.Cu" "B.Mask" "B.Paste")
			(net "GND")
		)
	)
	(footprint ""
		(layer "B.Cu")
		(at 224.536 -70.993 -90)
		(property "Reference" "C18"
			(at 0 0 90)
			(layer "B.SilkS")
			(hide yes)
			(effects
				(font
					(size 1.27 1.27)
				)
				(justify mirror)
			)
		)
		(property "Value" ""
			(at 0 0 90)
			(layer "B.Fab")
			(effects
				(font
					(size 1.27 1.27)
				)
				(justify mirror)
			)
		)
		(duplicate_pad_numbers_are_jumpers no)
		(fp_line
			(start -0.7874 0.4064)
			(end 0.7874 0.4064)
			(stroke
				(width 0.1524)
				(type default)
			)
			(layer "B.SilkS")
		)
		(fp_line
			(start 0.7874 0.4064)
			(end 0.7874 -0.4064)
			(stroke
				(width 0.1524)
				(type default)
			)
			(layer "B.SilkS")
		)
		(fp_line
			(start -0.7874 -0.4064)
			(end -0.7874 0.4064)
			(stroke
				(width 0.1524)
				(type default)
			)
			(layer "B.SilkS")
		)
		(fp_line
			(start 0.7874 -0.4064)
			(end -0.7874 -0.4064)
			(stroke
				(width 0.1524)
				(type default)
			)
			(layer "B.SilkS")
		)
		(fp_line
			(start -0.67945 0.3048)
			(end -0.120396 0.3048)
			(stroke
				(width 0.1)
				(type default)
			)
			(layer "B.Fab")
		)
		(fp_line
			(start -0.120396 0.3048)
			(end -0.120396 0.2794)
			(stroke
				(width 0.1)
				(type default)
			)
			(layer "B.Fab")
		)
		(fp_line
			(start 0.12065 0.3048)
			(end 0.67945 0.3048)
			(stroke
				(width 0.1)
				(type default)
			)
			(layer "B.Fab")
		)
		(fp_line
			(start 0.67945 0.3048)
			(end 0.67945 -0.305054)
			(stroke
				(width 0.1)
				(type default)
			)
			(layer "B.Fab")
		)
		(fp_line
			(start -0.120396 0.2794)
			(end 0.12065 0.2794)
			(stroke
				(width 0.1)
				(type default)
			)
			(layer "B.Fab")
		)
		(fp_line
			(start 0.12065 0.2794)
			(end 0.12065 0.3048)
			(stroke
				(width 0.1)
				(type default)
			)
			(layer "B.Fab")
		)
		(fp_line
			(start -0.12065 -0.2794)
			(end -0.12065 -0.3048)
			(stroke
				(width 0.1)
				(type default)
			)
			(layer "B.Fab")
		)
		(fp_line
			(start 0.12065 -0.2794)
			(end -0.12065 -0.2794)
			(stroke
				(width 0.1)
				(type default)
			)
			(layer "B.Fab")
		)
		(fp_line
			(start -0.67945 -0.3048)
			(end -0.67945 0.3048)
			(stroke
				(width 0.1)
				(type default)
			)
			(layer "B.Fab")
		)
		(fp_line
			(start -0.12065 -0.3048)
			(end -0.67945 -0.3048)
			(stroke
				(width 0.1)
				(type default)
			)
			(layer "B.Fab")
		)
		(fp_line
			(start 0.12065 -0.305054)
			(end 0.12065 -0.2794)
			(stroke
				(width 0.1)
				(type default)
			)
			(layer "B.Fab")
		)
		(fp_line
			(start 0.67945 -0.305054)
			(end 0.12065 -0.305054)
			(stroke
				(width 0.1)
				(type default)
			)
			(layer "B.Fab")
		)
		(pad "1" smd circle
			(at 0.40005 0 90)
			(size 0 0)
			(layers "B.Cu" "B.Mask" "B.Paste")
			(net "GPU_HSC_R_EN")
		)
		(pad "2" smd circle
			(at -0.40005 0 90)
			(size 0 0)
			(layers "B.Cu" "B.Mask" "B.Paste")
			(net "GND")
		)
	)
	(footprint ""
		(layer "B.Cu")
		(at 267.716 -25.527 180)
		(property "Reference" "D12"
			(at 1.1811 -2.32537 0)
			(unlocked yes)
			(layer "B.SilkS")
			(effects
				(font
					(size 0.7874 0.5842)
					(thickness 0.1524)
				)
				(justify left mirror)
			)
		)
		(property "Value" ""
			(at 0 0 0)
			(layer "B.Fab")
			(effects
				(font
					(size 1.27 1.27)
				)
				(justify mirror)
			)
		)
		(duplicate_pad_numbers_are_jumpers no)
		(fp_line
			(start 3.400044 1.459992)
			(end 3.400044 -1.459992)
			(stroke
				(width 0.1524)
				(type default)
			)
			(layer "B.SilkS")
		)
		(fp_line
			(start 3.400044 -1.459992)
			(end -4.107942 -1.459992)
			(stroke
				(width 0.1524)
				(type default)
			)
			(layer "B.SilkS")
		)
		(fp_line
			(start -4.107942 1.459992)
			(end 3.400044 1.459992)
			(stroke
				(width 0.1524)
				(type default)
			)
			(layer "B.SilkS")
		)
		(fp_line
			(start -4.107942 -1.459992)
			(end -4.107942 1.459992)
			(stroke
				(width 0.1524)
				(type default)
			)
			(layer "B.SilkS")
		)
		(fp_poly
			(pts
				(xy -4.107942 -1.459992) (xy -4.107942 1.459992) (xy -3.308096 1.459992) (xy -3.308096 -1.459992)
			)
			(stroke
				(width 0)
				(type default)
			)
			(fill yes)
			(layer "B.SilkS")
		)
		(fp_line
			(start 2.29997 1.459992)
			(end 2.29997 -1.459992)
			(stroke
				(width 0.1)
				(type default)
			)
			(layer "B.Fab")
		)
		(fp_line
			(start 2.29997 -1.459992)
			(end -2.29997 -1.459992)
			(stroke
				(width 0.1)
				(type default)
			)
			(layer "B.Fab")
		)
		(fp_line
			(start -2.29997 1.459992)
			(end 2.29997 1.459992)
			(stroke
				(width 0.1)
				(type default)
			)
			(layer "B.Fab")
		)
		(fp_line
			(start -2.29997 -1.459992)
			(end -2.29997 1.459992)
			(stroke
				(width 0.1)
				(type default)
			)
			(layer "B.Fab")
		)
		(fp_text user "+"
			(at 4.7752 -0.12065 180)
			(unlocked yes)
			(layer "B.SilkS")
			(effects
				(font
					(size 1.905 1.4224)
					(thickness 0.1524)
				)
				(justify left mirror)
			)
		)
		(fp_text user "-"
			(at -5.4102 0.29845 0)
			(unlocked yes)
			(layer "B.SilkS")
			(effects
				(font
					(size 1.905 1.4224)
					(thickness 0.1524)
				)
				(justify left mirror)
			)
		)
		(fp_text user "+"
			(at 4.7752 -0.12065 180)
			(unlocked yes)
			(layer "B.Fab")
			(effects
				(font
					(size 1.905 1.4224)
					(thickness 0.1524)
				)
				(justify left mirror)
			)
		)
		(fp_text user "-"
			(at -5.4102 0.29845 0)
			(unlocked yes)
			(layer "B.Fab")
			(effects
				(font
					(size 1.905 1.4224)
					(thickness 0.1524)
				)
				(justify left mirror)
			)
		)
		(pad "A" smd rect
			(at 1.999996 0 270)
			(size 1.7018 2.5146)
			(layers "B.Cu" "B.Mask" "B.Paste")
			(net "P52V_HS1_EN_DELAY")
		)
		(pad "C" smd rect
			(at -1.999996 0 270)
			(size 1.7018 2.5146)
			(layers "B.Cu" "B.Mask" "B.Paste")
			(net "P52V_HS1_EN")
		)
	)
	(footprint ""
		(layer "B.Cu")
		(at 94.361 -77.47 180)
		(property "Reference" "C58"
			(at 0 0 0)
			(layer "B.SilkS")
			(hide yes)
			(effects
				(font
					(size 1.27 1.27)
				)
				(justify mirror)
			)
		)
		(property "Value" ""
			(at 0 0 0)
			(layer "B.Fab")
			(effects
				(font
					(size 1.27 1.27)
				)
				(justify mirror)
			)
		)
		(duplicate_pad_numbers_are_jumpers no)
		(fp_line
			(start 0.7874 0.4064)
			(end 0.7874 -0.4064)
			(stroke
				(width 0.1524)
				(type default)
			)
			(layer "B.SilkS")
		)
		(fp_line
			(start 0.7874 -0.4064)
			(end -0.7874 -0.4064)
			(stroke
				(width 0.1524)
				(type default)
			)
			(layer "B.SilkS")
		)
		(fp_line
			(start -0.7874 0.4064)
			(end 0.7874 0.4064)
			(stroke
				(width 0.1524)
				(type default)
			)
			(layer "B.SilkS")
		)
		(fp_line
			(start -0.7874 -0.4064)
			(end -0.7874 0.4064)
			(stroke
				(width 0.1524)
				(type default)
			)
			(layer "B.SilkS")
		)
		(fp_line
			(start 0.67945 0.3048)
			(end 0.67945 -0.305054)
			(stroke
				(width 0.1)
				(type default)
			)
			(layer "B.Fab")
		)
		(fp_line
			(start 0.67945 -0.305054)
			(end 0.12065 -0.305054)
			(stroke
				(width 0.1)
				(type default)
			)
			(layer "B.Fab")
		)
		(fp_line
			(start 0.12065 0.3048)
			(end 0.67945 0.3048)
			(stroke
				(width 0.1)
				(type default)
			)
			(layer "B.Fab")
		)
		(fp_line
			(start 0.12065 0.2794)
			(end 0.12065 0.3048)
			(stroke
				(width 0.1)
				(type default)
			)
			(layer "B.Fab")
		)
		(fp_line
			(start 0.12065 -0.2794)
			(end -0.12065 -0.2794)
			(stroke
				(width 0.1)
				(type default)
			)
			(layer "B.Fab")
		)
		(fp_line
			(start 0.12065 -0.305054)
			(end 0.12065 -0.2794)
			(stroke
				(width 0.1)
				(type default)
			)
			(layer "B.Fab")
		)
		(fp_line
			(start -0.120396 0.3048)
			(end -0.120396 0.2794)
			(stroke
				(width 0.1)
				(type default)
			)
			(layer "B.Fab")
		)
		(fp_line
			(start -0.120396 0.2794)
			(end 0.12065 0.2794)
			(stroke
				(width 0.1)
				(type default)
			)
			(layer "B.Fab")
		)
		(fp_line
			(start -0.12065 -0.2794)
			(end -0.12065 -0.3048)
			(stroke
				(width 0.1)
				(type default)
			)
			(layer "B.Fab")
		)
		(fp_line
			(start -0.12065 -0.3048)
			(end -0.67945 -0.3048)
			(stroke
				(width 0.1)
				(type default)
			)
			(layer "B.Fab")
		)
		(fp_line
			(start -0.67945 0.3048)
			(end -0.120396 0.3048)
			(stroke
				(width 0.1)
				(type default)
			)
			(layer "B.Fab")
		)
		(fp_line
			(start -0.67945 -0.3048)
			(end -0.67945 0.3048)
			(stroke
				(width 0.1)
				(type default)
			)
			(layer "B.Fab")
		)
		(pad "1" smd circle
			(at 0.40005 0)
			(size 0 0)
			(layers "B.Cu" "B.Mask" "B.Paste")
			(net "P12V_BRICK1_ALERT_N")
		)
		(pad "2" smd circle
			(at -0.40005 0)
			(size 0 0)
			(layers "B.Cu" "B.Mask" "B.Paste")
			(net "GND")
		)
	)
	(footprint ""
		(layer "B.Cu")
		(at 209.804 -67.183 90)
		(property "Reference" "R21"
			(at 0 0 90)
			(layer "B.SilkS")
			(hide yes)
			(effects
				(font
					(size 1.27 1.27)
				)
				(justify mirror)
			)
		)
		(property "Value" ""
			(at 0 0 90)
			(layer "B.Fab")
			(effects
				(font
					(size 1.27 1.27)
				)
				(justify mirror)
			)
		)
		(duplicate_pad_numbers_are_jumpers no)
		(fp_line
			(start 0.7874 -0.4064)
			(end -0.7874 -0.4064)
			(stroke
				(width 0.1524)
				(type default)
			)
			(layer "B.SilkS")
		)
		(fp_line
			(start -0.7874 -0.4064)
			(end -0.7874 0.4064)
			(stroke
				(width 0.1524)
				(type default)
			)
			(layer "B.SilkS")
		)
		(fp_line
			(start 0.7874 0.4064)
			(end 0.7874 -0.4064)
			(stroke
				(width 0.1524)
				(type default)
			)
			(layer "B.SilkS")
		)
		(fp_line
			(start -0.7874 0.4064)
			(end 0.7874 0.4064)
			(stroke
				(width 0.1524)
				(type default)
			)
			(layer "B.SilkS")
		)
		(fp_line
			(start 0.67945 -0.305054)
			(end 0.12065 -0.305054)
			(stroke
				(width 0.1)
				(type default)
			)
			(layer "B.Fab")
		)
		(fp_line
			(start 0.12065 -0.305054)
			(end 0.12065 -0.2794)
			(stroke
				(width 0.1)
				(type default)
			)
			(layer "B.Fab")
		)
		(fp_line
			(start -0.12065 -0.3048)
			(end -0.67945 -0.3048)
			(stroke
				(width 0.1)
				(type default)
			)
			(layer "B.Fab")
		)
		(fp_line
			(start -0.67945 -0.3048)
			(end -0.67945 0.3048)
			(stroke
				(width 0.1)
				(type default)
			)
			(layer "B.Fab")
		)
		(fp_line
			(start 0.12065 -0.2794)
			(end -0.12065 -0.2794)
			(stroke
				(width 0.1)
				(type default)
			)
			(layer "B.Fab")
		)
		(fp_line
			(start -0.12065 -0.2794)
			(end -0.12065 -0.3048)
			(stroke
				(width 0.1)
				(type default)
			)
			(layer "B.Fab")
		)
		(fp_line
			(start 0.12065 0.2794)
			(end 0.12065 0.3048)
			(stroke
				(width 0.1)
				(type default)
			)
			(layer "B.Fab")
		)
		(fp_line
			(start -0.120396 0.2794)
			(end 0.12065 0.2794)
			(stroke
				(width 0.1)
				(type default)
			)
			(layer "B.Fab")
		)
		(fp_line
			(start 0.67945 0.3048)
			(end 0.67945 -0.305054)
			(stroke
				(width 0.1)
				(type default)
			)
			(layer "B.Fab")
		)
		(fp_line
			(start 0.12065 0.3048)
			(end 0.67945 0.3048)
			(stroke
				(width 0.1)
				(type default)
			)
			(layer "B.Fab")
		)
		(fp_line
			(start -0.120396 0.3048)
			(end -0.120396 0.2794)
			(stroke
				(width 0.1)
				(type default)
			)
			(layer "B.Fab")
		)
		(fp_line
			(start -0.67945 0.3048)
			(end -0.120396 0.3048)
			(stroke
				(width 0.1)
				(type default)
			)
			(layer "B.Fab")
		)
		(pad "1" smd circle
			(at 0.40005 0 270)
			(size 0 0)
			(layers "B.Cu" "B.Mask" "B.Paste")
			(net "PCA9555_A0")
		)
		(pad "2" smd circle
			(at -0.40005 0 270)
			(size 0 0)
			(layers "B.Cu" "B.Mask" "B.Paste")
			(net "GND")
		)
	)
	(footprint ""
		(layer "B.Cu")
		(at 143.002 -114.173 -90)
		(property "Reference" "R398"
			(at 0 0 90)
			(layer "B.SilkS")
			(hide yes)
			(effects
				(font
					(size 1.27 1.27)
				)
				(justify mirror)
			)
		)
		(property "Value" ""
			(at 0 0 90)
			(layer "B.Fab")
			(effects
				(font
					(size 1.27 1.27)
				)
				(justify mirror)
			)
		)
		(duplicate_pad_numbers_are_jumpers no)
		(fp_line
			(start -1.651 0.8382)
			(end 1.651 0.8382)
			(stroke
				(width 0.1524)
				(type default)
			)
			(layer "B.SilkS")
		)
		(fp_line
			(start 1.651 0.8382)
			(end 1.651 -0.8382)
			(stroke
				(width 0.1524)
				(type default)
			)
			(layer "B.SilkS")
		)
		(fp_line
			(start -1.651 -0.8382)
			(end -1.651 0.8382)
			(stroke
				(width 0.1524)
				(type default)
			)
			(layer "B.SilkS")
		)
		(fp_line
			(start 1.651 -0.8382)
			(end -1.651 -0.8382)
			(stroke
				(width 0.1524)
				(type default)
			)
			(layer "B.SilkS")
		)
		(fp_line
			(start -1.560576 0.7366)
			(end -1.560576 -0.7366)
			(stroke
				(width 0.1)
				(type default)
			)
			(layer "B.Fab")
		)
		(fp_line
			(start -1.524 0.7366)
			(end -1.560576 0.7366)
			(stroke
				(width 0.1)
				(type default)
			)
			(layer "B.Fab")
		)
		(fp_line
			(start 1.524 0.7366)
			(end -1.524 0.7366)
			(stroke
				(width 0.1)
				(type default)
			)
			(layer "B.Fab")
		)
		(fp_line
			(start 1.559814 0.7366)
			(end 1.524 0.7366)
			(stroke
				(width 0.1)
				(type default)
			)
			(layer "B.Fab")
		)
		(fp_line
			(start -1.560576 -0.7366)
			(end -1.524 -0.7366)
			(stroke
				(width 0.1)
				(type default)
			)
			(layer "B.Fab")
		)
		(fp_line
			(start -1.524 -0.7366)
			(end 1.524 -0.7366)
			(stroke
				(width 0.1)
				(type default)
			)
			(layer "B.Fab")
		)
		(fp_line
			(start 1.524 -0.7366)
			(end 1.559814 -0.7366)
			(stroke
				(width 0.1)
				(type default)
			)
			(layer "B.Fab")
		)
		(fp_line
			(start 1.559814 -0.7366)
			(end 1.559814 0.7366)
			(stroke
				(width 0.1)
				(type default)
			)
			(layer "B.Fab")
		)
		(pad "1" smd rect
			(at 0.94996 0 270)
			(size 1.1176 1.3716)
			(layers "B.Cu" "B.Mask" "B.Paste")
			(net "P52V_HS")
		)
		(pad "2" smd rect
			(at -0.94996 0 270)
			(size 1.1176 1.3716)
			(layers "B.Cu" "B.Mask" "B.Paste")
			(net "BRICK_P12V0_EN_N")
		)
	)
	(footprint ""
		(layer "B.Cu")
		(at 271.145 -40.132 90)
		(property "Reference" "R5933"
			(at 0 0 90)
			(layer "B.SilkS")
			(hide yes)
			(effects
				(font
					(size 1.27 1.27)
				)
				(justify mirror)
			)
		)
		(property "Value" ""
			(at 0 0 90)
			(layer "B.Fab")
			(effects
				(font
					(size 1.27 1.27)
				)
				(justify mirror)
			)
		)
		(duplicate_pad_numbers_are_jumpers no)
		(fp_line
			(start 0.7874 -0.4064)
			(end -0.7874 -0.4064)
			(stroke
				(width 0.1524)
				(type default)
			)
			(layer "B.SilkS")
		)
		(fp_line
			(start -0.7874 -0.4064)
			(end -0.7874 0.4064)
			(stroke
				(width 0.1524)
				(type default)
			)
			(layer "B.SilkS")
		)
		(fp_line
			(start 0.7874 0.4064)
			(end 0.7874 -0.4064)
			(stroke
				(width 0.1524)
				(type default)
			)
			(layer "B.SilkS")
		)
		(fp_line
			(start -0.7874 0.4064)
			(end 0.7874 0.4064)
			(stroke
				(width 0.1524)
				(type default)
			)
			(layer "B.SilkS")
		)
		(fp_line
			(start 0.67945 -0.305054)
			(end 0.12065 -0.305054)
			(stroke
				(width 0.1)
				(type default)
			)
			(layer "B.Fab")
		)
		(fp_line
			(start 0.12065 -0.305054)
			(end 0.12065 -0.2794)
			(stroke
				(width 0.1)
				(type default)
			)
			(layer "B.Fab")
		)
		(fp_line
			(start -0.12065 -0.3048)
			(end -0.67945 -0.3048)
			(stroke
				(width 0.1)
				(type default)
			)
			(layer "B.Fab")
		)
		(fp_line
			(start -0.67945 -0.3048)
			(end -0.67945 0.3048)
			(stroke
				(width 0.1)
				(type default)
			)
			(layer "B.Fab")
		)
		(fp_line
			(start 0.12065 -0.2794)
			(end -0.12065 -0.2794)
			(stroke
				(width 0.1)
				(type default)
			)
			(layer "B.Fab")
		)
		(fp_line
			(start -0.12065 -0.2794)
			(end -0.12065 -0.3048)
			(stroke
				(width 0.1)
				(type default)
			)
			(layer "B.Fab")
		)
		(fp_line
			(start 0.12065 0.2794)
			(end 0.12065 0.3048)
			(stroke
				(width 0.1)
				(type default)
			)
			(layer "B.Fab")
		)
		(fp_line
			(start -0.120396 0.2794)
			(end 0.12065 0.2794)
			(stroke
				(width 0.1)
				(type default)
			)
			(layer "B.Fab")
		)
		(fp_line
			(start 0.67945 0.3048)
			(end 0.67945 -0.305054)
			(stroke
				(width 0.1)
				(type default)
			)
			(layer "B.Fab")
		)
		(fp_line
			(start 0.12065 0.3048)
			(end 0.67945 0.3048)
			(stroke
				(width 0.1)
				(type default)
			)
			(layer "B.Fab")
		)
		(fp_line
			(start -0.120396 0.3048)
			(end -0.120396 0.2794)
			(stroke
				(width 0.1)
				(type default)
			)
			(layer "B.Fab")
		)
		(fp_line
			(start -0.67945 0.3048)
			(end -0.120396 0.3048)
			(stroke
				(width 0.1)
				(type default)
			)
			(layer "B.Fab")
		)
		(pad "1" smd circle
			(at 0.40005 0 270)
			(size 0 0)
			(layers "B.Cu" "B.Mask" "B.Paste")
			(net "P52V_HS1_EN_BUF_DELAY")
		)
		(pad "2" smd circle
			(at -0.40005 0 270)
			(size 0 0)
			(layers "B.Cu" "B.Mask" "B.Paste")
			(net "GND")
		)
	)
	(footprint ""
		(layer "B.Cu")
		(at 204.851 -71.374 -90)
		(property "Reference" "R5909"
			(at 0 0 90)
			(layer "B.SilkS")
			(hide yes)
			(effects
				(font
					(size 1.27 1.27)
				)
				(justify mirror)
			)
		)
		(property "Value" ""
			(at 0 0 90)
			(layer "B.Fab")
			(effects
				(font
					(size 1.27 1.27)
				)
				(justify mirror)
			)
		)
		(duplicate_pad_numbers_are_jumpers no)
		(fp_line
			(start -0.7874 0.4064)
			(end 0.7874 0.4064)
			(stroke
				(width 0.1524)
				(type default)
			)
			(layer "B.SilkS")
		)
		(fp_line
			(start 0.7874 0.4064)
			(end 0.7874 -0.4064)
			(stroke
				(width 0.1524)
				(type default)
			)
			(layer "B.SilkS")
		)
		(fp_line
			(start -0.7874 -0.4064)
			(end -0.7874 0.4064)
			(stroke
				(width 0.1524)
				(type default)
			)
			(layer "B.SilkS")
		)
		(fp_line
			(start 0.7874 -0.4064)
			(end -0.7874 -0.4064)
			(stroke
				(width 0.1524)
				(type default)
			)
			(layer "B.SilkS")
		)
		(fp_line
			(start -0.67945 0.3048)
			(end -0.120396 0.3048)
			(stroke
				(width 0.1)
				(type default)
			)
			(layer "B.Fab")
		)
		(fp_line
			(start -0.120396 0.3048)
			(end -0.120396 0.2794)
			(stroke
				(width 0.1)
				(type default)
			)
			(layer "B.Fab")
		)
		(fp_line
			(start 0.12065 0.3048)
			(end 0.67945 0.3048)
			(stroke
				(width 0.1)
				(type default)
			)
			(layer "B.Fab")
		)
		(fp_line
			(start 0.67945 0.3048)
			(end 0.67945 -0.305054)
			(stroke
				(width 0.1)
				(type default)
			)
			(layer "B.Fab")
		)
		(fp_line
			(start -0.120396 0.2794)
			(end 0.12065 0.2794)
			(stroke
				(width 0.1)
				(type default)
			)
			(layer "B.Fab")
		)
		(fp_line
			(start 0.12065 0.2794)
			(end 0.12065 0.3048)
			(stroke
				(width 0.1)
				(type default)
			)
			(layer "B.Fab")
		)
		(fp_line
			(start -0.12065 -0.2794)
			(end -0.12065 -0.3048)
			(stroke
				(width 0.1)
				(type default)
			)
			(layer "B.Fab")
		)
		(fp_line
			(start 0.12065 -0.2794)
			(end -0.12065 -0.2794)
			(stroke
				(width 0.1)
				(type default)
			)
			(layer "B.Fab")
		)
		(fp_line
			(start -0.67945 -0.3048)
			(end -0.67945 0.3048)
			(stroke
				(width 0.1)
				(type default)
			)
			(layer "B.Fab")
		)
		(fp_line
			(start -0.12065 -0.3048)
			(end -0.67945 -0.3048)
			(stroke
				(width 0.1)
				(type default)
			)
			(layer "B.Fab")
		)
		(fp_line
			(start 0.12065 -0.305054)
			(end 0.12065 -0.2794)
			(stroke
				(width 0.1)
				(type default)
			)
			(layer "B.Fab")
		)
		(fp_line
			(start 0.67945 -0.305054)
			(end 0.12065 -0.305054)
			(stroke
				(width 0.1)
				(type default)
			)
			(layer "B.Fab")
		)
		(pad "1" smd circle
			(at 0.40005 0 90)
			(size 0 0)
			(layers "B.Cu" "B.Mask" "B.Paste")
			(net "P3V3_AUX")
		)
		(pad "2" smd circle
			(at -0.40005 0 90)
			(size 0 0)
			(layers "B.Cu" "B.Mask" "B.Paste")
			(net "PRSNT_HPDB_N")
		)
	)
	(footprint ""
		(layer "B.Cu")
		(at 136.779 -76.327 180)
		(property "Reference" "R165"
			(at 0 0 0)
			(layer "B.SilkS")
			(hide yes)
			(effects
				(font
					(size 1.27 1.27)
				)
				(justify mirror)
			)
		)
		(property "Value" ""
			(at 0 0 0)
			(layer "B.Fab")
			(effects
				(font
					(size 1.27 1.27)
				)
				(justify mirror)
			)
		)
		(duplicate_pad_numbers_are_jumpers no)
		(fp_line
			(start 0.7874 0.4064)
			(end 0.7874 -0.4064)
			(stroke
				(width 0.1524)
				(type default)
			)
			(layer "B.SilkS")
		)
		(fp_line
			(start 0.7874 -0.4064)
			(end -0.7874 -0.4064)
			(stroke
				(width 0.1524)
				(type default)
			)
			(layer "B.SilkS")
		)
		(fp_line
			(start -0.7874 0.4064)
			(end 0.7874 0.4064)
			(stroke
				(width 0.1524)
				(type default)
			)
			(layer "B.SilkS")
		)
		(fp_line
			(start -0.7874 -0.4064)
			(end -0.7874 0.4064)
			(stroke
				(width 0.1524)
				(type default)
			)
			(layer "B.SilkS")
		)
		(fp_line
			(start 0.67945 0.3048)
			(end 0.67945 -0.305054)
			(stroke
				(width 0.1)
				(type default)
			)
			(layer "B.Fab")
		)
		(fp_line
			(start 0.67945 -0.305054)
			(end 0.12065 -0.305054)
			(stroke
				(width 0.1)
				(type default)
			)
			(layer "B.Fab")
		)
		(fp_line
			(start 0.12065 0.3048)
			(end 0.67945 0.3048)
			(stroke
				(width 0.1)
				(type default)
			)
			(layer "B.Fab")
		)
		(fp_line
			(start 0.12065 0.2794)
			(end 0.12065 0.3048)
			(stroke
				(width 0.1)
				(type default)
			)
			(layer "B.Fab")
		)
		(fp_line
			(start 0.12065 -0.2794)
			(end -0.12065 -0.2794)
			(stroke
				(width 0.1)
				(type default)
			)
			(layer "B.Fab")
		)
		(fp_line
			(start 0.12065 -0.305054)
			(end 0.12065 -0.2794)
			(stroke
				(width 0.1)
				(type default)
			)
			(layer "B.Fab")
		)
		(fp_line
			(start -0.120396 0.3048)
			(end -0.120396 0.2794)
			(stroke
				(width 0.1)
				(type default)
			)
			(layer "B.Fab")
		)
		(fp_line
			(start -0.120396 0.2794)
			(end 0.12065 0.2794)
			(stroke
				(width 0.1)
				(type default)
			)
			(layer "B.Fab")
		)
		(fp_line
			(start -0.12065 -0.2794)
			(end -0.12065 -0.3048)
			(stroke
				(width 0.1)
				(type default)
			)
			(layer "B.Fab")
		)
		(fp_line
			(start -0.12065 -0.3048)
			(end -0.67945 -0.3048)
			(stroke
				(width 0.1)
				(type default)
			)
			(layer "B.Fab")
		)
		(fp_line
			(start -0.67945 0.3048)
			(end -0.120396 0.3048)
			(stroke
				(width 0.1)
				(type default)
			)
			(layer "B.Fab")
		)
		(fp_line
			(start -0.67945 -0.3048)
			(end -0.67945 0.3048)
			(stroke
				(width 0.1)
				(type default)
			)
			(layer "B.Fab")
		)
		(pad "1" smd circle
			(at 0.40005 0)
			(size 0 0)
			(layers "B.Cu" "B.Mask" "B.Paste")
			(net "P12V_BRICK0_ALERT_N")
		)
		(pad "2" smd circle
			(at -0.40005 0)
			(size 0 0)
			(layers "B.Cu" "B.Mask" "B.Paste")
			(net "SMB_BRICK0_ALERT")
		)
	)
	(footprint ""
		(layer "B.Cu")
		(at 274.026122 -92.314522)
		(property "Reference" "R5861"
			(at 0 0 0)
			(layer "B.SilkS")
			(hide yes)
			(effects
				(font
					(size 1.27 1.27)
				)
				(justify mirror)
			)
		)
		(property "Value" ""
			(at 0 0 0)
			(layer "B.Fab")
			(effects
				(font
					(size 1.27 1.27)
				)
				(justify mirror)
			)
		)
		(duplicate_pad_numbers_are_jumpers no)
		(fp_line
			(start -0.7874 -0.4064)
			(end -0.7874 0.4064)
			(stroke
				(width 0.1524)
				(type default)
			)
			(layer "B.SilkS")
		)
		(fp_line
			(start -0.7874 0.4064)
			(end 0.7874 0.4064)
			(stroke
				(width 0.1524)
				(type default)
			)
			(layer "B.SilkS")
		)
		(fp_line
			(start 0.7874 -0.4064)
			(end -0.7874 -0.4064)
			(stroke
				(width 0.1524)
				(type default)
			)
			(layer "B.SilkS")
		)
		(fp_line
			(start 0.7874 0.4064)
			(end 0.7874 -0.4064)
			(stroke
				(width 0.1524)
				(type default)
			)
			(layer "B.SilkS")
		)
		(fp_line
			(start -0.67945 -0.3048)
			(end -0.67945 0.3048)
			(stroke
				(width 0.1)
				(type default)
			)
			(layer "B.Fab")
		)
		(fp_line
			(start -0.67945 0.3048)
			(end -0.120396 0.3048)
			(stroke
				(width 0.1)
				(type default)
			)
			(layer "B.Fab")
		)
		(fp_line
			(start -0.12065 -0.3048)
			(end -0.67945 -0.3048)
			(stroke
				(width 0.1)
				(type default)
			)
			(layer "B.Fab")
		)
		(fp_line
			(start -0.12065 -0.2794)
			(end -0.12065 -0.3048)
			(stroke
				(width 0.1)
				(type default)
			)
			(layer "B.Fab")
		)
		(fp_line
			(start -0.120396 0.2794)
			(end 0.12065 0.2794)
			(stroke
				(width 0.1)
				(type default)
			)
			(layer "B.Fab")
		)
		(fp_line
			(start -0.120396 0.3048)
			(end -0.120396 0.2794)
			(stroke
				(width 0.1)
				(type default)
			)
			(layer "B.Fab")
		)
		(fp_line
			(start 0.12065 -0.305054)
			(end 0.12065 -0.2794)
			(stroke
				(width 0.1)
				(type default)
			)
			(layer "B.Fab")
		)
		(fp_line
			(start 0.12065 -0.2794)
			(end -0.12065 -0.2794)
			(stroke
				(width 0.1)
				(type default)
			)
			(layer "B.Fab")
		)
		(fp_line
			(start 0.12065 0.2794)
			(end 0.12065 0.3048)
			(stroke
				(width 0.1)
				(type default)
			)
			(layer "B.Fab")
		)
		(fp_line
			(start 0.12065 0.3048)
			(end 0.67945 0.3048)
			(stroke
				(width 0.1)
				(type default)
			)
			(layer "B.Fab")
		)
		(fp_line
			(start 0.67945 -0.305054)
			(end 0.12065 -0.305054)
			(stroke
				(width 0.1)
				(type default)
			)
			(layer "B.Fab")
		)
		(fp_line
			(start 0.67945 0.3048)
			(end 0.67945 -0.305054)
			(stroke
				(width 0.1)
				(type default)
			)
			(layer "B.Fab")
		)
		(pad "1" smd circle
			(at 0.40005 0 180)
			(size 0 0)
			(layers "B.Cu" "B.Mask" "B.Paste")
			(net "P52V_HS1_1272_GATE")
		)
		(pad "2" smd circle
			(at -0.40005 0 180)
			(size 0 0)
			(layers "B.Cu" "B.Mask" "B.Paste")
			(net "P52V_HS1_GATE2_R")
		)
	)
	(footprint ""
		(layer "B.Cu")
		(at 224.282 -90.043 90)
		(property "Reference" "C10"
			(at 0 0 90)
			(layer "B.SilkS")
			(hide yes)
			(effects
				(font
					(size 1.27 1.27)
				)
				(justify mirror)
			)
		)
		(property "Value" ""
			(at 0 0 90)
			(layer "B.Fab")
			(effects
				(font
					(size 1.27 1.27)
				)
				(justify mirror)
			)
		)
		(duplicate_pad_numbers_are_jumpers no)
		(fp_line
			(start 0.7874 -0.4064)
			(end -0.7874 -0.4064)
			(stroke
				(width 0.1524)
				(type default)
			)
			(layer "B.SilkS")
		)
		(fp_line
			(start -0.7874 -0.4064)
			(end -0.7874 0.4064)
			(stroke
				(width 0.1524)
				(type default)
			)
			(layer "B.SilkS")
		)
		(fp_line
			(start 0.7874 0.4064)
			(end 0.7874 -0.4064)
			(stroke
				(width 0.1524)
				(type default)
			)
			(layer "B.SilkS")
		)
		(fp_line
			(start -0.7874 0.4064)
			(end 0.7874 0.4064)
			(stroke
				(width 0.1524)
				(type default)
			)
			(layer "B.SilkS")
		)
		(fp_line
			(start 0.67945 -0.305054)
			(end 0.12065 -0.305054)
			(stroke
				(width 0.1)
				(type default)
			)
			(layer "B.Fab")
		)
		(fp_line
			(start 0.12065 -0.305054)
			(end 0.12065 -0.2794)
			(stroke
				(width 0.1)
				(type default)
			)
			(layer "B.Fab")
		)
		(fp_line
			(start -0.12065 -0.3048)
			(end -0.67945 -0.3048)
			(stroke
				(width 0.1)
				(type default)
			)
			(layer "B.Fab")
		)
		(fp_line
			(start -0.67945 -0.3048)
			(end -0.67945 0.3048)
			(stroke
				(width 0.1)
				(type default)
			)
			(layer "B.Fab")
		)
		(fp_line
			(start 0.12065 -0.2794)
			(end -0.12065 -0.2794)
			(stroke
				(width 0.1)
				(type default)
			)
			(layer "B.Fab")
		)
		(fp_line
			(start -0.12065 -0.2794)
			(end -0.12065 -0.3048)
			(stroke
				(width 0.1)
				(type default)
			)
			(layer "B.Fab")
		)
		(fp_line
			(start 0.12065 0.2794)
			(end 0.12065 0.3048)
			(stroke
				(width 0.1)
				(type default)
			)
			(layer "B.Fab")
		)
		(fp_line
			(start -0.120396 0.2794)
			(end 0.12065 0.2794)
			(stroke
				(width 0.1)
				(type default)
			)
			(layer "B.Fab")
		)
		(fp_line
			(start 0.67945 0.3048)
			(end 0.67945 -0.305054)
			(stroke
				(width 0.1)
				(type default)
			)
			(layer "B.Fab")
		)
		(fp_line
			(start 0.12065 0.3048)
			(end 0.67945 0.3048)
			(stroke
				(width 0.1)
				(type default)
			)
			(layer "B.Fab")
		)
		(fp_line
			(start -0.120396 0.3048)
			(end -0.120396 0.2794)
			(stroke
				(width 0.1)
				(type default)
			)
			(layer "B.Fab")
		)
		(fp_line
			(start -0.67945 0.3048)
			(end -0.120396 0.3048)
			(stroke
				(width 0.1)
				(type default)
			)
			(layer "B.Fab")
		)
		(pad "1" smd circle
			(at 0.40005 0 270)
			(size 0 0)
			(layers "B.Cu" "B.Mask" "B.Paste")
			(net "GND")
		)
		(pad "2" smd circle
			(at -0.40005 0 270)
			(size 0 0)
			(layers "B.Cu" "B.Mask" "B.Paste")
			(net "P3V3_AUX")
		)
	)
	(footprint ""
		(layer "B.Cu")
		(at 289.306 -50.927)
		(property "Reference" "PC2"
			(at 0 0 0)
			(layer "B.SilkS")
			(hide yes)
			(effects
				(font
					(size 1.27 1.27)
				)
				(justify mirror)
			)
		)
		(property "Value" ""
			(at 0 0 0)
			(layer "B.Fab")
			(effects
				(font
					(size 1.27 1.27)
				)
				(justify mirror)
			)
		)
		(duplicate_pad_numbers_are_jumpers no)
		(fp_line
			(start -0.7874 -0.4064)
			(end -0.7874 0.4064)
			(stroke
				(width 0.1524)
				(type default)
			)
			(layer "B.SilkS")
		)
		(fp_line
			(start -0.7874 0.4064)
			(end 0.7874 0.4064)
			(stroke
				(width 0.1524)
				(type default)
			)
			(layer "B.SilkS")
		)
		(fp_line
			(start 0.7874 -0.4064)
			(end -0.7874 -0.4064)
			(stroke
				(width 0.1524)
				(type default)
			)
			(layer "B.SilkS")
		)
		(fp_line
			(start 0.7874 0.4064)
			(end 0.7874 -0.4064)
			(stroke
				(width 0.1524)
				(type default)
			)
			(layer "B.SilkS")
		)
		(fp_line
			(start -0.67945 -0.3048)
			(end -0.67945 0.3048)
			(stroke
				(width 0.1)
				(type default)
			)
			(layer "B.Fab")
		)
		(fp_line
			(start -0.67945 0.3048)
			(end -0.120396 0.3048)
			(stroke
				(width 0.1)
				(type default)
			)
			(layer "B.Fab")
		)
		(fp_line
			(start -0.12065 -0.3048)
			(end -0.67945 -0.3048)
			(stroke
				(width 0.1)
				(type default)
			)
			(layer "B.Fab")
		)
		(fp_line
			(start -0.12065 -0.2794)
			(end -0.12065 -0.3048)
			(stroke
				(width 0.1)
				(type default)
			)
			(layer "B.Fab")
		)
		(fp_line
			(start -0.120396 0.2794)
			(end 0.12065 0.2794)
			(stroke
				(width 0.1)
				(type default)
			)
			(layer "B.Fab")
		)
		(fp_line
			(start -0.120396 0.3048)
			(end -0.120396 0.2794)
			(stroke
				(width 0.1)
				(type default)
			)
			(layer "B.Fab")
		)
		(fp_line
			(start 0.12065 -0.305054)
			(end 0.12065 -0.2794)
			(stroke
				(width 0.1)
				(type default)
			)
			(layer "B.Fab")
		)
		(fp_line
			(start 0.12065 -0.2794)
			(end -0.12065 -0.2794)
			(stroke
				(width 0.1)
				(type default)
			)
			(layer "B.Fab")
		)
		(fp_line
			(start 0.12065 0.2794)
			(end 0.12065 0.3048)
			(stroke
				(width 0.1)
				(type default)
			)
			(layer "B.Fab")
		)
		(fp_line
			(start 0.12065 0.3048)
			(end 0.67945 0.3048)
			(stroke
				(width 0.1)
				(type default)
			)
			(layer "B.Fab")
		)
		(fp_line
			(start 0.67945 -0.305054)
			(end 0.12065 -0.305054)
			(stroke
				(width 0.1)
				(type default)
			)
			(layer "B.Fab")
		)
		(fp_line
			(start 0.67945 0.3048)
			(end 0.67945 -0.305054)
			(stroke
				(width 0.1)
				(type default)
			)
			(layer "B.Fab")
		)
		(pad "1" smd circle
			(at 0.40005 0 180)
			(size 0 0)
			(layers "B.Cu" "B.Mask" "B.Paste")
			(net "P52V_HS1_UVLO_EN")
		)
		(pad "2" smd circle
			(at -0.40005 0 180)
			(size 0 0)
			(layers "B.Cu" "B.Mask" "B.Paste")
			(net "GND_FIELD_SIGNAL")
		)
	)
	(footprint ""
		(layer "B.Cu")
		(at 221.996 -90.043 90)
		(property "Reference" "R36"
			(at 0 0 90)
			(layer "B.SilkS")
			(hide yes)
			(effects
				(font
					(size 1.27 1.27)
				)
				(justify mirror)
			)
		)
		(property "Value" ""
			(at 0 0 90)
			(layer "B.Fab")
			(effects
				(font
					(size 1.27 1.27)
				)
				(justify mirror)
			)
		)
		(duplicate_pad_numbers_are_jumpers no)
		(fp_line
			(start 0.7874 -0.4064)
			(end -0.7874 -0.4064)
			(stroke
				(width 0.1524)
				(type default)
			)
			(layer "B.SilkS")
		)
		(fp_line
			(start -0.7874 -0.4064)
			(end -0.7874 0.4064)
			(stroke
				(width 0.1524)
				(type default)
			)
			(layer "B.SilkS")
		)
		(fp_line
			(start 0.7874 0.4064)
			(end 0.7874 -0.4064)
			(stroke
				(width 0.1524)
				(type default)
			)
			(layer "B.SilkS")
		)
		(fp_line
			(start -0.7874 0.4064)
			(end 0.7874 0.4064)
			(stroke
				(width 0.1524)
				(type default)
			)
			(layer "B.SilkS")
		)
		(fp_line
			(start 0.67945 -0.305054)
			(end 0.12065 -0.305054)
			(stroke
				(width 0.1)
				(type default)
			)
			(layer "B.Fab")
		)
		(fp_line
			(start 0.12065 -0.305054)
			(end 0.12065 -0.2794)
			(stroke
				(width 0.1)
				(type default)
			)
			(layer "B.Fab")
		)
		(fp_line
			(start -0.12065 -0.3048)
			(end -0.67945 -0.3048)
			(stroke
				(width 0.1)
				(type default)
			)
			(layer "B.Fab")
		)
		(fp_line
			(start -0.67945 -0.3048)
			(end -0.67945 0.3048)
			(stroke
				(width 0.1)
				(type default)
			)
			(layer "B.Fab")
		)
		(fp_line
			(start 0.12065 -0.2794)
			(end -0.12065 -0.2794)
			(stroke
				(width 0.1)
				(type default)
			)
			(layer "B.Fab")
		)
		(fp_line
			(start -0.12065 -0.2794)
			(end -0.12065 -0.3048)
			(stroke
				(width 0.1)
				(type default)
			)
			(layer "B.Fab")
		)
		(fp_line
			(start 0.12065 0.2794)
			(end 0.12065 0.3048)
			(stroke
				(width 0.1)
				(type default)
			)
			(layer "B.Fab")
		)
		(fp_line
			(start -0.120396 0.2794)
			(end 0.12065 0.2794)
			(stroke
				(width 0.1)
				(type default)
			)
			(layer "B.Fab")
		)
		(fp_line
			(start 0.67945 0.3048)
			(end 0.67945 -0.305054)
			(stroke
				(width 0.1)
				(type default)
			)
			(layer "B.Fab")
		)
		(fp_line
			(start 0.12065 0.3048)
			(end 0.67945 0.3048)
			(stroke
				(width 0.1)
				(type default)
			)
			(layer "B.Fab")
		)
		(fp_line
			(start -0.120396 0.3048)
			(end -0.120396 0.2794)
			(stroke
				(width 0.1)
				(type default)
			)
			(layer "B.Fab")
		)
		(fp_line
			(start -0.67945 0.3048)
			(end -0.120396 0.3048)
			(stroke
				(width 0.1)
				(type default)
			)
			(layer "B.Fab")
		)
		(pad "1" smd circle
			(at 0.40005 0 270)
			(size 0 0)
			(layers "B.Cu" "B.Mask" "B.Paste")
			(net "P3V3_AUX")
		)
		(pad "2" smd circle
			(at -0.40005 0 270)
			(size 0 0)
			(layers "B.Cu" "B.Mask" "B.Paste")
			(net "FRU_WP_N")
		)
	)
	(footprint ""
		(layer "B.Cu")
		(at 291.27704 -43.13428 90)
		(property "Reference" "R5911"
			(at 0 0 90)
			(layer "B.SilkS")
			(hide yes)
			(effects
				(font
					(size 1.27 1.27)
				)
				(justify mirror)
			)
		)
		(property "Value" ""
			(at 0 0 90)
			(layer "B.Fab")
			(effects
				(font
					(size 1.27 1.27)
				)
				(justify mirror)
			)
		)
		(duplicate_pad_numbers_are_jumpers no)
		(fp_line
			(start 0.7874 -0.4064)
			(end -0.7874 -0.4064)
			(stroke
				(width 0.1524)
				(type default)
			)
			(layer "B.SilkS")
		)
		(fp_line
			(start -0.7874 -0.4064)
			(end -0.7874 0.4064)
			(stroke
				(width 0.1524)
				(type default)
			)
			(layer "B.SilkS")
		)
		(fp_line
			(start 0.7874 0.4064)
			(end 0.7874 -0.4064)
			(stroke
				(width 0.1524)
				(type default)
			)
			(layer "B.SilkS")
		)
		(fp_line
			(start -0.7874 0.4064)
			(end 0.7874 0.4064)
			(stroke
				(width 0.1524)
				(type default)
			)
			(layer "B.SilkS")
		)
		(fp_line
			(start 0.67945 -0.305054)
			(end 0.12065 -0.305054)
			(stroke
				(width 0.1)
				(type default)
			)
			(layer "B.Fab")
		)
		(fp_line
			(start 0.12065 -0.305054)
			(end 0.12065 -0.2794)
			(stroke
				(width 0.1)
				(type default)
			)
			(layer "B.Fab")
		)
		(fp_line
			(start -0.12065 -0.3048)
			(end -0.67945 -0.3048)
			(stroke
				(width 0.1)
				(type default)
			)
			(layer "B.Fab")
		)
		(fp_line
			(start -0.67945 -0.3048)
			(end -0.67945 0.3048)
			(stroke
				(width 0.1)
				(type default)
			)
			(layer "B.Fab")
		)
		(fp_line
			(start 0.12065 -0.2794)
			(end -0.12065 -0.2794)
			(stroke
				(width 0.1)
				(type default)
			)
			(layer "B.Fab")
		)
		(fp_line
			(start -0.12065 -0.2794)
			(end -0.12065 -0.3048)
			(stroke
				(width 0.1)
				(type default)
			)
			(layer "B.Fab")
		)
		(fp_line
			(start 0.12065 0.2794)
			(end 0.12065 0.3048)
			(stroke
				(width 0.1)
				(type default)
			)
			(layer "B.Fab")
		)
		(fp_line
			(start -0.120396 0.2794)
			(end 0.12065 0.2794)
			(stroke
				(width 0.1)
				(type default)
			)
			(layer "B.Fab")
		)
		(fp_line
			(start 0.67945 0.3048)
			(end 0.67945 -0.305054)
			(stroke
				(width 0.1)
				(type default)
			)
			(layer "B.Fab")
		)
		(fp_line
			(start 0.12065 0.3048)
			(end 0.67945 0.3048)
			(stroke
				(width 0.1)
				(type default)
			)
			(layer "B.Fab")
		)
		(fp_line
			(start -0.120396 0.3048)
			(end -0.120396 0.2794)
			(stroke
				(width 0.1)
				(type default)
			)
			(layer "B.Fab")
		)
		(fp_line
			(start -0.67945 0.3048)
			(end -0.120396 0.3048)
			(stroke
				(width 0.1)
				(type default)
			)
			(layer "B.Fab")
		)
		(pad "1" smd circle
			(at 0.40005 0 270)
			(size 0 0)
			(layers "B.Cu" "B.Mask" "B.Paste")
			(net "FM_AC_PWR_CYCLE_N")
		)
		(pad "2" smd circle
			(at -0.40005 0 270)
			(size 0 0)
			(layers "B.Cu" "B.Mask" "B.Paste")
			(net "GND")
		)
	)
	(footprint ""
		(layer "B.Cu")
		(at 228.219 -70.993 -90)
		(property "Reference" "R96"
			(at 0 0 90)
			(layer "B.SilkS")
			(hide yes)
			(effects
				(font
					(size 1.27 1.27)
				)
				(justify mirror)
			)
		)
		(property "Value" ""
			(at 0 0 90)
			(layer "B.Fab")
			(effects
				(font
					(size 1.27 1.27)
				)
				(justify mirror)
			)
		)
		(duplicate_pad_numbers_are_jumpers no)
		(fp_line
			(start -0.7874 0.4064)
			(end 0.7874 0.4064)
			(stroke
				(width 0.1524)
				(type default)
			)
			(layer "B.SilkS")
		)
		(fp_line
			(start 0.7874 0.4064)
			(end 0.7874 -0.4064)
			(stroke
				(width 0.1524)
				(type default)
			)
			(layer "B.SilkS")
		)
		(fp_line
			(start -0.7874 -0.4064)
			(end -0.7874 0.4064)
			(stroke
				(width 0.1524)
				(type default)
			)
			(layer "B.SilkS")
		)
		(fp_line
			(start 0.7874 -0.4064)
			(end -0.7874 -0.4064)
			(stroke
				(width 0.1524)
				(type default)
			)
			(layer "B.SilkS")
		)
		(fp_line
			(start -0.67945 0.3048)
			(end -0.120396 0.3048)
			(stroke
				(width 0.1)
				(type default)
			)
			(layer "B.Fab")
		)
		(fp_line
			(start -0.120396 0.3048)
			(end -0.120396 0.2794)
			(stroke
				(width 0.1)
				(type default)
			)
			(layer "B.Fab")
		)
		(fp_line
			(start 0.12065 0.3048)
			(end 0.67945 0.3048)
			(stroke
				(width 0.1)
				(type default)
			)
			(layer "B.Fab")
		)
		(fp_line
			(start 0.67945 0.3048)
			(end 0.67945 -0.305054)
			(stroke
				(width 0.1)
				(type default)
			)
			(layer "B.Fab")
		)
		(fp_line
			(start -0.120396 0.2794)
			(end 0.12065 0.2794)
			(stroke
				(width 0.1)
				(type default)
			)
			(layer "B.Fab")
		)
		(fp_line
			(start 0.12065 0.2794)
			(end 0.12065 0.3048)
			(stroke
				(width 0.1)
				(type default)
			)
			(layer "B.Fab")
		)
		(fp_line
			(start -0.12065 -0.2794)
			(end -0.12065 -0.3048)
			(stroke
				(width 0.1)
				(type default)
			)
			(layer "B.Fab")
		)
		(fp_line
			(start 0.12065 -0.2794)
			(end -0.12065 -0.2794)
			(stroke
				(width 0.1)
				(type default)
			)
			(layer "B.Fab")
		)
		(fp_line
			(start -0.67945 -0.3048)
			(end -0.67945 0.3048)
			(stroke
				(width 0.1)
				(type default)
			)
			(layer "B.Fab")
		)
		(fp_line
			(start -0.12065 -0.3048)
			(end -0.67945 -0.3048)
			(stroke
				(width 0.1)
				(type default)
			)
			(layer "B.Fab")
		)
		(fp_line
			(start 0.12065 -0.305054)
			(end 0.12065 -0.2794)
			(stroke
				(width 0.1)
				(type default)
			)
			(layer "B.Fab")
		)
		(fp_line
			(start 0.67945 -0.305054)
			(end 0.12065 -0.305054)
			(stroke
				(width 0.1)
				(type default)
			)
			(layer "B.Fab")
		)
		(pad "1" smd circle
			(at 0.40005 0 90)
			(size 0 0)
			(layers "B.Cu" "B.Mask" "B.Paste")
			(net "P12V_BRICK_PWRGD_R_N")
		)
		(pad "2" smd circle
			(at -0.40005 0 90)
			(size 0 0)
			(layers "B.Cu" "B.Mask" "B.Paste")
			(net "P12V_BRICK_PWRGD_N")
		)
	)
	(footprint ""
		(layer "B.Cu")
		(at 289.306 -49.911)
		(property "Reference" "PR10"
			(at 0 0 0)
			(layer "B.SilkS")
			(hide yes)
			(effects
				(font
					(size 1.27 1.27)
				)
				(justify mirror)
			)
		)
		(property "Value" ""
			(at 0 0 0)
			(layer "B.Fab")
			(effects
				(font
					(size 1.27 1.27)
				)
				(justify mirror)
			)
		)
		(duplicate_pad_numbers_are_jumpers no)
		(fp_line
			(start -0.7874 -0.4064)
			(end -0.7874 0.4064)
			(stroke
				(width 0.1524)
				(type default)
			)
			(layer "B.SilkS")
		)
		(fp_line
			(start -0.7874 0.4064)
			(end 0.7874 0.4064)
			(stroke
				(width 0.1524)
				(type default)
			)
			(layer "B.SilkS")
		)
		(fp_line
			(start 0.7874 -0.4064)
			(end -0.7874 -0.4064)
			(stroke
				(width 0.1524)
				(type default)
			)
			(layer "B.SilkS")
		)
		(fp_line
			(start 0.7874 0.4064)
			(end 0.7874 -0.4064)
			(stroke
				(width 0.1524)
				(type default)
			)
			(layer "B.SilkS")
		)
		(fp_line
			(start -0.67945 -0.3048)
			(end -0.67945 0.3048)
			(stroke
				(width 0.1)
				(type default)
			)
			(layer "B.Fab")
		)
		(fp_line
			(start -0.67945 0.3048)
			(end -0.120396 0.3048)
			(stroke
				(width 0.1)
				(type default)
			)
			(layer "B.Fab")
		)
		(fp_line
			(start -0.12065 -0.3048)
			(end -0.67945 -0.3048)
			(stroke
				(width 0.1)
				(type default)
			)
			(layer "B.Fab")
		)
		(fp_line
			(start -0.12065 -0.2794)
			(end -0.12065 -0.3048)
			(stroke
				(width 0.1)
				(type default)
			)
			(layer "B.Fab")
		)
		(fp_line
			(start -0.120396 0.2794)
			(end 0.12065 0.2794)
			(stroke
				(width 0.1)
				(type default)
			)
			(layer "B.Fab")
		)
		(fp_line
			(start -0.120396 0.3048)
			(end -0.120396 0.2794)
			(stroke
				(width 0.1)
				(type default)
			)
			(layer "B.Fab")
		)
		(fp_line
			(start 0.12065 -0.305054)
			(end 0.12065 -0.2794)
			(stroke
				(width 0.1)
				(type default)
			)
			(layer "B.Fab")
		)
		(fp_line
			(start 0.12065 -0.2794)
			(end -0.12065 -0.2794)
			(stroke
				(width 0.1)
				(type default)
			)
			(layer "B.Fab")
		)
		(fp_line
			(start 0.12065 0.2794)
			(end 0.12065 0.3048)
			(stroke
				(width 0.1)
				(type default)
			)
			(layer "B.Fab")
		)
		(fp_line
			(start 0.12065 0.3048)
			(end 0.67945 0.3048)
			(stroke
				(width 0.1)
				(type default)
			)
			(layer "B.Fab")
		)
		(fp_line
			(start 0.67945 -0.305054)
			(end 0.12065 -0.305054)
			(stroke
				(width 0.1)
				(type default)
			)
			(layer "B.Fab")
		)
		(fp_line
			(start 0.67945 0.3048)
			(end 0.67945 -0.305054)
			(stroke
				(width 0.1)
				(type default)
			)
			(layer "B.Fab")
		)
		(pad "1" smd circle
			(at 0.40005 0 180)
			(size 0 0)
			(layers "B.Cu" "B.Mask" "B.Paste")
			(net "P52V_HS1_UVLO_EN")
		)
		(pad "2" smd circle
			(at -0.40005 0 180)
			(size 0 0)
			(layers "B.Cu" "B.Mask" "B.Paste")
			(net "GND_FIELD_SIGNAL")
		)
	)
	(footprint ""
		(layer "B.Cu")
		(at 179.065174 -77.597 180)
		(property "Reference" "C73"
			(at 0 0 0)
			(layer "B.SilkS")
			(hide yes)
			(effects
				(font
					(size 1.27 1.27)
				)
				(justify mirror)
			)
		)
		(property "Value" ""
			(at 0 0 0)
			(layer "B.Fab")
			(effects
				(font
					(size 1.27 1.27)
				)
				(justify mirror)
			)
		)
		(duplicate_pad_numbers_are_jumpers no)
		(fp_line
			(start 0.7874 0.4064)
			(end 0.7874 -0.4064)
			(stroke
				(width 0.1524)
				(type default)
			)
			(layer "B.SilkS")
		)
		(fp_line
			(start 0.7874 -0.4064)
			(end -0.7874 -0.4064)
			(stroke
				(width 0.1524)
				(type default)
			)
			(layer "B.SilkS")
		)
		(fp_line
			(start -0.7874 0.4064)
			(end 0.7874 0.4064)
			(stroke
				(width 0.1524)
				(type default)
			)
			(layer "B.SilkS")
		)
		(fp_line
			(start -0.7874 -0.4064)
			(end -0.7874 0.4064)
			(stroke
				(width 0.1524)
				(type default)
			)
			(layer "B.SilkS")
		)
		(fp_line
			(start 0.67945 0.3048)
			(end 0.67945 -0.305054)
			(stroke
				(width 0.1)
				(type default)
			)
			(layer "B.Fab")
		)
		(fp_line
			(start 0.67945 -0.305054)
			(end 0.12065 -0.305054)
			(stroke
				(width 0.1)
				(type default)
			)
			(layer "B.Fab")
		)
		(fp_line
			(start 0.12065 0.3048)
			(end 0.67945 0.3048)
			(stroke
				(width 0.1)
				(type default)
			)
			(layer "B.Fab")
		)
		(fp_line
			(start 0.12065 0.2794)
			(end 0.12065 0.3048)
			(stroke
				(width 0.1)
				(type default)
			)
			(layer "B.Fab")
		)
		(fp_line
			(start 0.12065 -0.2794)
			(end -0.12065 -0.2794)
			(stroke
				(width 0.1)
				(type default)
			)
			(layer "B.Fab")
		)
		(fp_line
			(start 0.12065 -0.305054)
			(end 0.12065 -0.2794)
			(stroke
				(width 0.1)
				(type default)
			)
			(layer "B.Fab")
		)
		(fp_line
			(start -0.120396 0.3048)
			(end -0.120396 0.2794)
			(stroke
				(width 0.1)
				(type default)
			)
			(layer "B.Fab")
		)
		(fp_line
			(start -0.120396 0.2794)
			(end 0.12065 0.2794)
			(stroke
				(width 0.1)
				(type default)
			)
			(layer "B.Fab")
		)
		(fp_line
			(start -0.12065 -0.2794)
			(end -0.12065 -0.3048)
			(stroke
				(width 0.1)
				(type default)
			)
			(layer "B.Fab")
		)
		(fp_line
			(start -0.12065 -0.3048)
			(end -0.67945 -0.3048)
			(stroke
				(width 0.1)
				(type default)
			)
			(layer "B.Fab")
		)
		(fp_line
			(start -0.67945 0.3048)
			(end -0.120396 0.3048)
			(stroke
				(width 0.1)
				(type default)
			)
			(layer "B.Fab")
		)
		(fp_line
			(start -0.67945 -0.3048)
			(end -0.67945 0.3048)
			(stroke
				(width 0.1)
				(type default)
			)
			(layer "B.Fab")
		)
		(pad "1" smd circle
			(at 0.40005 0)
			(size 0 0)
			(layers "B.Cu" "B.Mask" "B.Paste")
			(net "SMB_P52V_VPDB_SCL")
		)
		(pad "2" smd circle
			(at -0.40005 0)
			(size 0 0)
			(layers "B.Cu" "B.Mask" "B.Paste")
			(net "GND")
		)
	)
	(footprint ""
		(layer "B.Cu")
		(at 275.169122 -87.361522)
		(property "Reference" "PC565"
			(at 0 0 0)
			(layer "B.SilkS")
			(hide yes)
			(effects
				(font
					(size 1.27 1.27)
				)
				(justify mirror)
			)
		)
		(property "Value" ""
			(at 0 0 0)
			(layer "B.Fab")
			(effects
				(font
					(size 1.27 1.27)
				)
				(justify mirror)
			)
		)
		(duplicate_pad_numbers_are_jumpers no)
		(fp_line
			(start -1.2954 -0.5842)
			(end -1.2954 0.5842)
			(stroke
				(width 0.1524)
				(type default)
			)
			(layer "B.SilkS")
		)
		(fp_line
			(start -1.2954 0.5842)
			(end 1.2954 0.5842)
			(stroke
				(width 0.1524)
				(type default)
			)
			(layer "B.SilkS")
		)
		(fp_line
			(start 1.2954 -0.5842)
			(end -1.2954 -0.5842)
			(stroke
				(width 0.1524)
				(type default)
			)
			(layer "B.SilkS")
		)
		(fp_line
			(start 1.2954 0.5842)
			(end 1.2954 -0.5842)
			(stroke
				(width 0.1524)
				(type default)
			)
			(layer "B.SilkS")
		)
		(fp_line
			(start -1.1938 -0.4064)
			(end -1.1938 0.4064)
			(stroke
				(width 0.1)
				(type default)
			)
			(layer "B.Fab")
		)
		(fp_line
			(start -1.1938 0.4064)
			(end -0.8636 0.4064)
			(stroke
				(width 0.1)
				(type default)
			)
			(layer "B.Fab")
		)
		(fp_line
			(start -0.8636 -0.4572)
			(end -0.8636 -0.4064)
			(stroke
				(width 0.1)
				(type default)
			)
			(layer "B.Fab")
		)
		(fp_line
			(start -0.8636 -0.4064)
			(end -1.1938 -0.4064)
			(stroke
				(width 0.1)
				(type default)
			)
			(layer "B.Fab")
		)
		(fp_line
			(start -0.8636 0.4064)
			(end -0.8636 0.4572)
			(stroke
				(width 0.1)
				(type default)
			)
			(layer "B.Fab")
		)
		(fp_line
			(start -0.8636 0.4572)
			(end 0.8636 0.4572)
			(stroke
				(width 0.1)
				(type default)
			)
			(layer "B.Fab")
		)
		(fp_line
			(start 0.8636 -0.4572)
			(end -0.8636 -0.4572)
			(stroke
				(width 0.1)
				(type default)
			)
			(layer "B.Fab")
		)
		(fp_line
			(start 0.8636 -0.4064)
			(end 0.8636 -0.4572)
			(stroke
				(width 0.1)
				(type default)
			)
			(layer "B.Fab")
		)
		(fp_line
			(start 0.8636 0.4064)
			(end 1.1938 0.4064)
			(stroke
				(width 0.1)
				(type default)
			)
			(layer "B.Fab")
		)
		(fp_line
			(start 0.8636 0.4572)
			(end 0.8636 0.4064)
			(stroke
				(width 0.1)
				(type default)
			)
			(layer "B.Fab")
		)
		(fp_line
			(start 1.1938 -0.4064)
			(end 0.8636 -0.4064)
			(stroke
				(width 0.1)
				(type default)
			)
			(layer "B.Fab")
		)
		(fp_line
			(start 1.1938 0.4064)
			(end 1.1938 -0.4064)
			(stroke
				(width 0.1)
				(type default)
			)
			(layer "B.Fab")
		)
		(pad "1" smd rect
			(at 0.7366 0 270)
			(size 0.7112 0.8128)
			(layers "B.Cu" "B.Mask" "B.Paste")
			(net "P52V_HS1_4287_GATE2_RC")
		)
		(pad "2" smd rect
			(at -0.7366 0 270)
			(size 0.7112 0.8128)
			(layers "B.Cu" "B.Mask" "B.Paste")
			(net "P52V_HS")
		)
	)
	(footprint ""
		(layer "B.Cu")
		(at 281.94 -39.243)
		(property "Reference" "U39"
			(at 3.3909 -2.11963 0)
			(unlocked yes)
			(layer "B.SilkS")
			(effects
				(font
					(size 0.7874 0.5842)
					(thickness 0.1524)
				)
				(justify left mirror)
			)
		)
		(property "Value" ""
			(at 0 0 0)
			(layer "B.Fab")
			(effects
				(font
					(size 1.27 1.27)
				)
				(justify mirror)
			)
		)
		(duplicate_pad_numbers_are_jumpers no)
		(fp_line
			(start -1.603248 -1.500124)
			(end -1.603248 1.500124)
			(stroke
				(width 0.1524)
				(type default)
			)
			(layer "B.SilkS")
		)
		(fp_line
			(start -1.603248 1.500124)
			(end 1.603248 1.500124)
			(stroke
				(width 0.1524)
				(type default)
			)
			(layer "B.SilkS")
		)
		(fp_line
			(start 1.603248 -1.500124)
			(end -1.603248 -1.500124)
			(stroke
				(width 0.1524)
				(type default)
			)
			(layer "B.SilkS")
		)
		(fp_line
			(start 1.603248 1.500124)
			(end 1.603248 -1.500124)
			(stroke
				(width 0.1524)
				(type default)
			)
			(layer "B.SilkS")
		)
		(fp_line
			(start -1.249934 -0.219964)
			(end -0.700024 -0.219964)
			(stroke
				(width 0.1)
				(type default)
			)
			(layer "B.Fab")
		)
		(fp_line
			(start -1.249934 0.219964)
			(end -1.249934 -0.219964)
			(stroke
				(width 0.1)
				(type default)
			)
			(layer "B.Fab")
		)
		(fp_line
			(start -0.700024 -1.500124)
			(end 0.700024 -1.500124)
			(stroke
				(width 0.1)
				(type default)
			)
			(layer "B.Fab")
		)
		(fp_line
			(start -0.700024 -0.219964)
			(end -0.700024 -1.500124)
			(stroke
				(width 0.1)
				(type default)
			)
			(layer "B.Fab")
		)
		(fp_line
			(start -0.700024 0.219964)
			(end -1.249934 0.219964)
			(stroke
				(width 0.1)
				(type default)
			)
			(layer "B.Fab")
		)
		(fp_line
			(start -0.700024 1.500124)
			(end -0.700024 0.219964)
			(stroke
				(width 0.1)
				(type default)
			)
			(layer "B.Fab")
		)
		(fp_line
			(start 0.6985 -0.729996)
			(end 0.6985 0.729996)
			(stroke
				(width 0.1)
				(type default)
			)
			(layer "B.Fab")
		)
		(fp_line
			(start 0.6985 0.729996)
			(end 1.249934 0.729996)
			(stroke
				(width 0.1)
				(type default)
			)
			(layer "B.Fab")
		)
		(fp_line
			(start 0.700024 -1.500124)
			(end 0.700024 -1.169924)
			(stroke
				(width 0.1)
				(type default)
			)
			(layer "B.Fab")
		)
		(fp_line
			(start 0.700024 -1.169924)
			(end 1.249934 -1.169924)
			(stroke
				(width 0.1)
				(type default)
			)
			(layer "B.Fab")
		)
		(fp_line
			(start 0.700024 1.169924)
			(end 0.700024 1.500124)
			(stroke
				(width 0.1)
				(type default)
			)
			(layer "B.Fab")
		)
		(fp_line
			(start 0.700024 1.500124)
			(end -0.700024 1.500124)
			(stroke
				(width 0.1)
				(type default)
			)
			(layer "B.Fab")
		)
		(fp_line
			(start 1.249934 -1.169924)
			(end 1.249934 -0.729996)
			(stroke
				(width 0.1)
				(type default)
			)
			(layer "B.Fab")
		)
		(fp_line
			(start 1.249934 -0.729996)
			(end 0.6985 -0.729996)
			(stroke
				(width 0.1)
				(type default)
			)
			(layer "B.Fab")
		)
		(fp_line
			(start 1.249934 0.729996)
			(end 1.249934 1.169924)
			(stroke
				(width 0.1)
				(type default)
			)
			(layer "B.Fab")
		)
		(fp_line
			(start 1.249934 1.169924)
			(end 0.700024 1.169924)
			(stroke
				(width 0.1)
				(type default)
			)
			(layer "B.Fab")
		)
		(fp_rect
			(start 0.700024 1.500124)
			(end -0.700024 -1.500124)
			(stroke
				(width 0)
				(type default)
			)
			(fill no)
			(layer "B.Fab")
		)
		(pad "D" smd rect
			(at -0.999998 0 270)
			(size 0.8128 0.9144)
			(layers "B.Cu" "B.Mask" "B.Paste")
			(net "P52V_HS1_EN_DELAY_N")
		)
		(pad "G" smd rect
			(at 0.999998 -0.94996 270)
			(size 0.8128 0.9144)
			(layers "B.Cu" "B.Mask" "B.Paste")
			(net "P52V_HS1_EN_DELAY")
		)
		(pad "S" smd rect
			(at 0.999998 0.94996 270)
			(size 0.8128 0.9144)
			(layers "B.Cu" "B.Mask" "B.Paste")
			(net "GND")
		)
	)
	(footprint ""
		(layer "B.Cu")
		(at 56.642 -76.327 180)
		(property "Reference" "R179"
			(at 0 0 0)
			(layer "B.SilkS")
			(hide yes)
			(effects
				(font
					(size 1.27 1.27)
				)
				(justify mirror)
			)
		)
		(property "Value" ""
			(at 0 0 0)
			(layer "B.Fab")
			(effects
				(font
					(size 1.27 1.27)
				)
				(justify mirror)
			)
		)
		(duplicate_pad_numbers_are_jumpers no)
		(fp_line
			(start 0.7874 0.4064)
			(end 0.7874 -0.4064)
			(stroke
				(width 0.1524)
				(type default)
			)
			(layer "B.SilkS")
		)
		(fp_line
			(start 0.7874 -0.4064)
			(end -0.7874 -0.4064)
			(stroke
				(width 0.1524)
				(type default)
			)
			(layer "B.SilkS")
		)
		(fp_line
			(start -0.7874 0.4064)
			(end 0.7874 0.4064)
			(stroke
				(width 0.1524)
				(type default)
			)
			(layer "B.SilkS")
		)
		(fp_line
			(start -0.7874 -0.4064)
			(end -0.7874 0.4064)
			(stroke
				(width 0.1524)
				(type default)
			)
			(layer "B.SilkS")
		)
		(fp_line
			(start 0.67945 0.3048)
			(end 0.67945 -0.305054)
			(stroke
				(width 0.1)
				(type default)
			)
			(layer "B.Fab")
		)
		(fp_line
			(start 0.67945 -0.305054)
			(end 0.12065 -0.305054)
			(stroke
				(width 0.1)
				(type default)
			)
			(layer "B.Fab")
		)
		(fp_line
			(start 0.12065 0.3048)
			(end 0.67945 0.3048)
			(stroke
				(width 0.1)
				(type default)
			)
			(layer "B.Fab")
		)
		(fp_line
			(start 0.12065 0.2794)
			(end 0.12065 0.3048)
			(stroke
				(width 0.1)
				(type default)
			)
			(layer "B.Fab")
		)
		(fp_line
			(start 0.12065 -0.2794)
			(end -0.12065 -0.2794)
			(stroke
				(width 0.1)
				(type default)
			)
			(layer "B.Fab")
		)
		(fp_line
			(start 0.12065 -0.305054)
			(end 0.12065 -0.2794)
			(stroke
				(width 0.1)
				(type default)
			)
			(layer "B.Fab")
		)
		(fp_line
			(start -0.120396 0.3048)
			(end -0.120396 0.2794)
			(stroke
				(width 0.1)
				(type default)
			)
			(layer "B.Fab")
		)
		(fp_line
			(start -0.120396 0.2794)
			(end 0.12065 0.2794)
			(stroke
				(width 0.1)
				(type default)
			)
			(layer "B.Fab")
		)
		(fp_line
			(start -0.12065 -0.2794)
			(end -0.12065 -0.3048)
			(stroke
				(width 0.1)
				(type default)
			)
			(layer "B.Fab")
		)
		(fp_line
			(start -0.12065 -0.3048)
			(end -0.67945 -0.3048)
			(stroke
				(width 0.1)
				(type default)
			)
			(layer "B.Fab")
		)
		(fp_line
			(start -0.67945 0.3048)
			(end -0.120396 0.3048)
			(stroke
				(width 0.1)
				(type default)
			)
			(layer "B.Fab")
		)
		(fp_line
			(start -0.67945 -0.3048)
			(end -0.67945 0.3048)
			(stroke
				(width 0.1)
				(type default)
			)
			(layer "B.Fab")
		)
		(pad "1" smd circle
			(at 0.40005 0)
			(size 0 0)
			(layers "B.Cu" "B.Mask" "B.Paste")
			(net "P12V_BRICK3_ALERT_N")
		)
		(pad "2" smd circle
			(at -0.40005 0)
			(size 0 0)
			(layers "B.Cu" "B.Mask" "B.Paste")
			(net "SMB_BRICK3_ALERT")
		)
	)
	(footprint ""
		(layer "B.Cu")
		(at 263.144 -35.433)
		(property "Reference" "PC4"
			(at 0 0 0)
			(layer "B.SilkS")
			(hide yes)
			(effects
				(font
					(size 1.27 1.27)
				)
				(justify mirror)
			)
		)
		(property "Value" ""
			(at 0 0 0)
			(layer "B.Fab")
			(effects
				(font
					(size 1.27 1.27)
				)
				(justify mirror)
			)
		)
		(duplicate_pad_numbers_are_jumpers no)
		(fp_line
			(start -0.7874 -0.4064)
			(end -0.7874 0.4064)
			(stroke
				(width 0.1524)
				(type default)
			)
			(layer "B.SilkS")
		)
		(fp_line
			(start -0.7874 0.4064)
			(end 0.7874 0.4064)
			(stroke
				(width 0.1524)
				(type default)
			)
			(layer "B.SilkS")
		)
		(fp_line
			(start 0.7874 -0.4064)
			(end -0.7874 -0.4064)
			(stroke
				(width 0.1524)
				(type default)
			)
			(layer "B.SilkS")
		)
		(fp_line
			(start 0.7874 0.4064)
			(end 0.7874 -0.4064)
			(stroke
				(width 0.1524)
				(type default)
			)
			(layer "B.SilkS")
		)
		(fp_line
			(start -0.67945 -0.3048)
			(end -0.67945 0.3048)
			(stroke
				(width 0.1)
				(type default)
			)
			(layer "B.Fab")
		)
		(fp_line
			(start -0.67945 0.3048)
			(end -0.120396 0.3048)
			(stroke
				(width 0.1)
				(type default)
			)
			(layer "B.Fab")
		)
		(fp_line
			(start -0.12065 -0.3048)
			(end -0.67945 -0.3048)
			(stroke
				(width 0.1)
				(type default)
			)
			(layer "B.Fab")
		)
		(fp_line
			(start -0.12065 -0.2794)
			(end -0.12065 -0.3048)
			(stroke
				(width 0.1)
				(type default)
			)
			(layer "B.Fab")
		)
		(fp_line
			(start -0.120396 0.2794)
			(end 0.12065 0.2794)
			(stroke
				(width 0.1)
				(type default)
			)
			(layer "B.Fab")
		)
		(fp_line
			(start -0.120396 0.3048)
			(end -0.120396 0.2794)
			(stroke
				(width 0.1)
				(type default)
			)
			(layer "B.Fab")
		)
		(fp_line
			(start 0.12065 -0.305054)
			(end 0.12065 -0.2794)
			(stroke
				(width 0.1)
				(type default)
			)
			(layer "B.Fab")
		)
		(fp_line
			(start 0.12065 -0.2794)
			(end -0.12065 -0.2794)
			(stroke
				(width 0.1)
				(type default)
			)
			(layer "B.Fab")
		)
		(fp_line
			(start 0.12065 0.2794)
			(end 0.12065 0.3048)
			(stroke
				(width 0.1)
				(type default)
			)
			(layer "B.Fab")
		)
		(fp_line
			(start 0.12065 0.3048)
			(end 0.67945 0.3048)
			(stroke
				(width 0.1)
				(type default)
			)
			(layer "B.Fab")
		)
		(fp_line
			(start 0.67945 -0.305054)
			(end 0.12065 -0.305054)
			(stroke
				(width 0.1)
				(type default)
			)
			(layer "B.Fab")
		)
		(fp_line
			(start 0.67945 0.3048)
			(end 0.67945 -0.305054)
			(stroke
				(width 0.1)
				(type default)
			)
			(layer "B.Fab")
		)
		(pad "1" smd circle
			(at 0.40005 0 180)
			(size 0 0)
			(layers "B.Cu" "B.Mask" "B.Paste")
			(net "P52V_HS1_INTVCC")
		)
		(pad "2" smd circle
			(at -0.40005 0 180)
			(size 0 0)
			(layers "B.Cu" "B.Mask" "B.Paste")
			(net "GND")
		)
	)
	(footprint ""
		(layer "B.Cu")
		(at 213.614 -67.183 90)
		(property "Reference" "R95"
			(at 0 0 90)
			(layer "B.SilkS")
			(hide yes)
			(effects
				(font
					(size 1.27 1.27)
				)
				(justify mirror)
			)
		)
		(property "Value" ""
			(at 0 0 90)
			(layer "B.Fab")
			(effects
				(font
					(size 1.27 1.27)
				)
				(justify mirror)
			)
		)
		(duplicate_pad_numbers_are_jumpers no)
		(fp_line
			(start 0.7874 -0.4064)
			(end -0.7874 -0.4064)
			(stroke
				(width 0.1524)
				(type default)
			)
			(layer "B.SilkS")
		)
		(fp_line
			(start -0.7874 -0.4064)
			(end -0.7874 0.4064)
			(stroke
				(width 0.1524)
				(type default)
			)
			(layer "B.SilkS")
		)
		(fp_line
			(start 0.7874 0.4064)
			(end 0.7874 -0.4064)
			(stroke
				(width 0.1524)
				(type default)
			)
			(layer "B.SilkS")
		)
		(fp_line
			(start -0.7874 0.4064)
			(end 0.7874 0.4064)
			(stroke
				(width 0.1524)
				(type default)
			)
			(layer "B.SilkS")
		)
		(fp_line
			(start 0.67945 -0.305054)
			(end 0.12065 -0.305054)
			(stroke
				(width 0.1)
				(type default)
			)
			(layer "B.Fab")
		)
		(fp_line
			(start 0.12065 -0.305054)
			(end 0.12065 -0.2794)
			(stroke
				(width 0.1)
				(type default)
			)
			(layer "B.Fab")
		)
		(fp_line
			(start -0.12065 -0.3048)
			(end -0.67945 -0.3048)
			(stroke
				(width 0.1)
				(type default)
			)
			(layer "B.Fab")
		)
		(fp_line
			(start -0.67945 -0.3048)
			(end -0.67945 0.3048)
			(stroke
				(width 0.1)
				(type default)
			)
			(layer "B.Fab")
		)
		(fp_line
			(start 0.12065 -0.2794)
			(end -0.12065 -0.2794)
			(stroke
				(width 0.1)
				(type default)
			)
			(layer "B.Fab")
		)
		(fp_line
			(start -0.12065 -0.2794)
			(end -0.12065 -0.3048)
			(stroke
				(width 0.1)
				(type default)
			)
			(layer "B.Fab")
		)
		(fp_line
			(start 0.12065 0.2794)
			(end 0.12065 0.3048)
			(stroke
				(width 0.1)
				(type default)
			)
			(layer "B.Fab")
		)
		(fp_line
			(start -0.120396 0.2794)
			(end 0.12065 0.2794)
			(stroke
				(width 0.1)
				(type default)
			)
			(layer "B.Fab")
		)
		(fp_line
			(start 0.67945 0.3048)
			(end 0.67945 -0.305054)
			(stroke
				(width 0.1)
				(type default)
			)
			(layer "B.Fab")
		)
		(fp_line
			(start 0.12065 0.3048)
			(end 0.67945 0.3048)
			(stroke
				(width 0.1)
				(type default)
			)
			(layer "B.Fab")
		)
		(fp_line
			(start -0.120396 0.3048)
			(end -0.120396 0.2794)
			(stroke
				(width 0.1)
				(type default)
			)
			(layer "B.Fab")
		)
		(fp_line
			(start -0.67945 0.3048)
			(end -0.120396 0.3048)
			(stroke
				(width 0.1)
				(type default)
			)
			(layer "B.Fab")
		)
		(pad "1" smd circle
			(at 0.40005 0 270)
			(size 0 0)
			(layers "B.Cu" "B.Mask" "B.Paste")
			(net "SKU_ID_0")
		)
		(pad "2" smd circle
			(at -0.40005 0 270)
			(size 0 0)
			(layers "B.Cu" "B.Mask" "B.Paste")
			(net "GND")
		)
	)
	(footprint ""
		(layer "B.Cu")
		(at 91.694 -76.708 90)
		(property "Reference" "R203"
			(at 0 0 90)
			(layer "B.SilkS")
			(hide yes)
			(effects
				(font
					(size 1.27 1.27)
				)
				(justify mirror)
			)
		)
		(property "Value" ""
			(at 0 0 90)
			(layer "B.Fab")
			(effects
				(font
					(size 1.27 1.27)
				)
				(justify mirror)
			)
		)
		(duplicate_pad_numbers_are_jumpers no)
		(fp_line
			(start 0.7874 -0.4064)
			(end -0.7874 -0.4064)
			(stroke
				(width 0.1524)
				(type default)
			)
			(layer "B.SilkS")
		)
		(fp_line
			(start -0.7874 -0.4064)
			(end -0.7874 0.4064)
			(stroke
				(width 0.1524)
				(type default)
			)
			(layer "B.SilkS")
		)
		(fp_line
			(start 0.7874 0.4064)
			(end 0.7874 -0.4064)
			(stroke
				(width 0.1524)
				(type default)
			)
			(layer "B.SilkS")
		)
		(fp_line
			(start -0.7874 0.4064)
			(end 0.7874 0.4064)
			(stroke
				(width 0.1524)
				(type default)
			)
			(layer "B.SilkS")
		)
		(fp_line
			(start 0.67945 -0.305054)
			(end 0.12065 -0.305054)
			(stroke
				(width 0.1)
				(type default)
			)
			(layer "B.Fab")
		)
		(fp_line
			(start 0.12065 -0.305054)
			(end 0.12065 -0.2794)
			(stroke
				(width 0.1)
				(type default)
			)
			(layer "B.Fab")
		)
		(fp_line
			(start -0.12065 -0.3048)
			(end -0.67945 -0.3048)
			(stroke
				(width 0.1)
				(type default)
			)
			(layer "B.Fab")
		)
		(fp_line
			(start -0.67945 -0.3048)
			(end -0.67945 0.3048)
			(stroke
				(width 0.1)
				(type default)
			)
			(layer "B.Fab")
		)
		(fp_line
			(start 0.12065 -0.2794)
			(end -0.12065 -0.2794)
			(stroke
				(width 0.1)
				(type default)
			)
			(layer "B.Fab")
		)
		(fp_line
			(start -0.12065 -0.2794)
			(end -0.12065 -0.3048)
			(stroke
				(width 0.1)
				(type default)
			)
			(layer "B.Fab")
		)
		(fp_line
			(start 0.12065 0.2794)
			(end 0.12065 0.3048)
			(stroke
				(width 0.1)
				(type default)
			)
			(layer "B.Fab")
		)
		(fp_line
			(start -0.120396 0.2794)
			(end 0.12065 0.2794)
			(stroke
				(width 0.1)
				(type default)
			)
			(layer "B.Fab")
		)
		(fp_line
			(start 0.67945 0.3048)
			(end 0.67945 -0.305054)
			(stroke
				(width 0.1)
				(type default)
			)
			(layer "B.Fab")
		)
		(fp_line
			(start 0.12065 0.3048)
			(end 0.67945 0.3048)
			(stroke
				(width 0.1)
				(type default)
			)
			(layer "B.Fab")
		)
		(fp_line
			(start -0.120396 0.3048)
			(end -0.120396 0.2794)
			(stroke
				(width 0.1)
				(type default)
			)
			(layer "B.Fab")
		)
		(fp_line
			(start -0.67945 0.3048)
			(end -0.120396 0.3048)
			(stroke
				(width 0.1)
				(type default)
			)
			(layer "B.Fab")
		)
		(pad "1" smd circle
			(at 0.40005 0 270)
			(size 0 0)
			(layers "B.Cu" "B.Mask" "B.Paste")
			(net "P3V3_AUX")
		)
		(pad "2" smd circle
			(at -0.40005 0 270)
			(size 0 0)
			(layers "B.Cu" "B.Mask" "B.Paste")
			(net "P12V_BRICK_PWRGD")
		)
	)
	(footprint ""
		(layer "B.Cu")
		(at 96.849946 -116.078 -90)
		(property "Reference" "R170"
			(at 0 0 90)
			(layer "B.SilkS")
			(hide yes)
			(effects
				(font
					(size 1.27 1.27)
				)
				(justify mirror)
			)
		)
		(property "Value" ""
			(at 0 0 90)
			(layer "B.Fab")
			(effects
				(font
					(size 1.27 1.27)
				)
				(justify mirror)
			)
		)
		(duplicate_pad_numbers_are_jumpers no)
		(fp_line
			(start -0.7874 0.4064)
			(end 0.7874 0.4064)
			(stroke
				(width 0.1524)
				(type default)
			)
			(layer "B.SilkS")
		)
		(fp_line
			(start 0.7874 0.4064)
			(end 0.7874 -0.4064)
			(stroke
				(width 0.1524)
				(type default)
			)
			(layer "B.SilkS")
		)
		(fp_line
			(start -0.7874 -0.4064)
			(end -0.7874 0.4064)
			(stroke
				(width 0.1524)
				(type default)
			)
			(layer "B.SilkS")
		)
		(fp_line
			(start 0.7874 -0.4064)
			(end -0.7874 -0.4064)
			(stroke
				(width 0.1524)
				(type default)
			)
			(layer "B.SilkS")
		)
		(fp_line
			(start -0.67945 0.3048)
			(end -0.120396 0.3048)
			(stroke
				(width 0.1)
				(type default)
			)
			(layer "B.Fab")
		)
		(fp_line
			(start -0.120396 0.3048)
			(end -0.120396 0.2794)
			(stroke
				(width 0.1)
				(type default)
			)
			(layer "B.Fab")
		)
		(fp_line
			(start 0.12065 0.3048)
			(end 0.67945 0.3048)
			(stroke
				(width 0.1)
				(type default)
			)
			(layer "B.Fab")
		)
		(fp_line
			(start 0.67945 0.3048)
			(end 0.67945 -0.305054)
			(stroke
				(width 0.1)
				(type default)
			)
			(layer "B.Fab")
		)
		(fp_line
			(start -0.120396 0.2794)
			(end 0.12065 0.2794)
			(stroke
				(width 0.1)
				(type default)
			)
			(layer "B.Fab")
		)
		(fp_line
			(start 0.12065 0.2794)
			(end 0.12065 0.3048)
			(stroke
				(width 0.1)
				(type default)
			)
			(layer "B.Fab")
		)
		(fp_line
			(start -0.12065 -0.2794)
			(end -0.12065 -0.3048)
			(stroke
				(width 0.1)
				(type default)
			)
			(layer "B.Fab")
		)
		(fp_line
			(start 0.12065 -0.2794)
			(end -0.12065 -0.2794)
			(stroke
				(width 0.1)
				(type default)
			)
			(layer "B.Fab")
		)
		(fp_line
			(start -0.67945 -0.3048)
			(end -0.67945 0.3048)
			(stroke
				(width 0.1)
				(type default)
			)
			(layer "B.Fab")
		)
		(fp_line
			(start -0.12065 -0.3048)
			(end -0.67945 -0.3048)
			(stroke
				(width 0.1)
				(type default)
			)
			(layer "B.Fab")
		)
		(fp_line
			(start 0.12065 -0.305054)
			(end 0.12065 -0.2794)
			(stroke
				(width 0.1)
				(type default)
			)
			(layer "B.Fab")
		)
		(fp_line
			(start 0.67945 -0.305054)
			(end 0.12065 -0.305054)
			(stroke
				(width 0.1)
				(type default)
			)
			(layer "B.Fab")
		)
		(pad "1" smd circle
			(at 0.40005 0 90)
			(size 0 0)
			(layers "B.Cu" "B.Mask" "B.Paste")
			(net "BRICK_P12V_1_EN_N")
		)
		(pad "2" smd circle
			(at -0.40005 0 90)
			(size 0 0)
			(layers "B.Cu" "B.Mask" "B.Paste")
			(net "BRICK_P12V1_ON_OFF_R")
		)
	)
	(footprint ""
		(layer "B.Cu")
		(at 271.78 -47.625 -90)
		(property "Reference" "R159"
			(at 0 0 90)
			(layer "B.SilkS")
			(hide yes)
			(effects
				(font
					(size 1.27 1.27)
				)
				(justify mirror)
			)
		)
		(property "Value" ""
			(at 0 0 90)
			(layer "B.Fab")
			(effects
				(font
					(size 1.27 1.27)
				)
				(justify mirror)
			)
		)
		(duplicate_pad_numbers_are_jumpers no)
		(fp_line
			(start -0.7874 0.4064)
			(end 0.7874 0.4064)
			(stroke
				(width 0.1524)
				(type default)
			)
			(layer "B.SilkS")
		)
		(fp_line
			(start 0.7874 0.4064)
			(end 0.7874 -0.4064)
			(stroke
				(width 0.1524)
				(type default)
			)
			(layer "B.SilkS")
		)
		(fp_line
			(start -0.7874 -0.4064)
			(end -0.7874 0.4064)
			(stroke
				(width 0.1524)
				(type default)
			)
			(layer "B.SilkS")
		)
		(fp_line
			(start 0.7874 -0.4064)
			(end -0.7874 -0.4064)
			(stroke
				(width 0.1524)
				(type default)
			)
			(layer "B.SilkS")
		)
		(fp_line
			(start -0.67945 0.3048)
			(end -0.120396 0.3048)
			(stroke
				(width 0.1)
				(type default)
			)
			(layer "B.Fab")
		)
		(fp_line
			(start -0.120396 0.3048)
			(end -0.120396 0.2794)
			(stroke
				(width 0.1)
				(type default)
			)
			(layer "B.Fab")
		)
		(fp_line
			(start 0.12065 0.3048)
			(end 0.67945 0.3048)
			(stroke
				(width 0.1)
				(type default)
			)
			(layer "B.Fab")
		)
		(fp_line
			(start 0.67945 0.3048)
			(end 0.67945 -0.305054)
			(stroke
				(width 0.1)
				(type default)
			)
			(layer "B.Fab")
		)
		(fp_line
			(start -0.120396 0.2794)
			(end 0.12065 0.2794)
			(stroke
				(width 0.1)
				(type default)
			)
			(layer "B.Fab")
		)
		(fp_line
			(start 0.12065 0.2794)
			(end 0.12065 0.3048)
			(stroke
				(width 0.1)
				(type default)
			)
			(layer "B.Fab")
		)
		(fp_line
			(start -0.12065 -0.2794)
			(end -0.12065 -0.3048)
			(stroke
				(width 0.1)
				(type default)
			)
			(layer "B.Fab")
		)
		(fp_line
			(start 0.12065 -0.2794)
			(end -0.12065 -0.2794)
			(stroke
				(width 0.1)
				(type default)
			)
			(layer "B.Fab")
		)
		(fp_line
			(start -0.67945 -0.3048)
			(end -0.67945 0.3048)
			(stroke
				(width 0.1)
				(type default)
			)
			(layer "B.Fab")
		)
		(fp_line
			(start -0.12065 -0.3048)
			(end -0.67945 -0.3048)
			(stroke
				(width 0.1)
				(type default)
			)
			(layer "B.Fab")
		)
		(fp_line
			(start 0.12065 -0.305054)
			(end 0.12065 -0.2794)
			(stroke
				(width 0.1)
				(type default)
			)
			(layer "B.Fab")
		)
		(fp_line
			(start 0.67945 -0.305054)
			(end 0.12065 -0.305054)
			(stroke
				(width 0.1)
				(type default)
			)
			(layer "B.Fab")
		)
		(pad "1" smd circle
			(at 0.40005 0 90)
			(size 0 0)
			(layers "B.Cu" "B.Mask" "B.Paste")
			(net "P52V_HS1_ADR1")
		)
		(pad "2" smd circle
			(at -0.40005 0 90)
			(size 0 0)
			(layers "B.Cu" "B.Mask" "B.Paste")
			(net "GND_FIELD_SIGNAL")
		)
	)
	(footprint ""
		(layer "B.Cu")
		(at 285.496 -54.483)
		(property "Reference" "PR18"
			(at 0 0 0)
			(layer "B.SilkS")
			(hide yes)
			(effects
				(font
					(size 1.27 1.27)
				)
				(justify mirror)
			)
		)
		(property "Value" ""
			(at 0 0 0)
			(layer "B.Fab")
			(effects
				(font
					(size 1.27 1.27)
				)
				(justify mirror)
			)
		)
		(duplicate_pad_numbers_are_jumpers no)
		(fp_line
			(start -1.651 -0.8382)
			(end -1.651 0.8382)
			(stroke
				(width 0.1524)
				(type default)
			)
			(layer "B.SilkS")
		)
		(fp_line
			(start -1.651 0.8382)
			(end 1.651 0.8382)
			(stroke
				(width 0.1524)
				(type default)
			)
			(layer "B.SilkS")
		)
		(fp_line
			(start 1.651 -0.8382)
			(end -1.651 -0.8382)
			(stroke
				(width 0.1524)
				(type default)
			)
			(layer "B.SilkS")
		)
		(fp_line
			(start 1.651 0.8382)
			(end 1.651 -0.8382)
			(stroke
				(width 0.1524)
				(type default)
			)
			(layer "B.SilkS")
		)
		(fp_line
			(start -1.560576 -0.7366)
			(end -1.524 -0.7366)
			(stroke
				(width 0.1)
				(type default)
			)
			(layer "B.Fab")
		)
		(fp_line
			(start -1.560576 0.7366)
			(end -1.560576 -0.7366)
			(stroke
				(width 0.1)
				(type default)
			)
			(layer "B.Fab")
		)
		(fp_line
			(start -1.524 -0.7366)
			(end 1.524 -0.7366)
			(stroke
				(width 0.1)
				(type default)
			)
			(layer "B.Fab")
		)
		(fp_line
			(start -1.524 0.7366)
			(end -1.560576 0.7366)
			(stroke
				(width 0.1)
				(type default)
			)
			(layer "B.Fab")
		)
		(fp_line
			(start 1.524 -0.7366)
			(end 1.559814 -0.7366)
			(stroke
				(width 0.1)
				(type default)
			)
			(layer "B.Fab")
		)
		(fp_line
			(start 1.524 0.7366)
			(end -1.524 0.7366)
			(stroke
				(width 0.1)
				(type default)
			)
			(layer "B.Fab")
		)
		(fp_line
			(start 1.559814 -0.7366)
			(end 1.559814 0.7366)
			(stroke
				(width 0.1)
				(type default)
			)
			(layer "B.Fab")
		)
		(fp_line
			(start 1.559814 0.7366)
			(end 1.524 0.7366)
			(stroke
				(width 0.1)
				(type default)
			)
			(layer "B.Fab")
		)
		(pad "1" smd rect
			(at 0.94996 0)
			(size 1.1176 1.3716)
			(layers "B.Cu" "B.Mask" "B.Paste")
			(net "P52V_1")
		)
		(pad "2" smd rect
			(at -0.94996 0)
			(size 1.1176 1.3716)
			(layers "B.Cu" "B.Mask" "B.Paste")
			(net "P52V_HS1_ISET")
		)
	)
	(footprint ""
		(layer "B.Cu")
		(at 146.558 -116.205)
		(property "Reference" "R167"
			(at 0 0 0)
			(layer "B.SilkS")
			(hide yes)
			(effects
				(font
					(size 1.27 1.27)
				)
				(justify mirror)
			)
		)
		(property "Value" ""
			(at 0 0 0)
			(layer "B.Fab")
			(effects
				(font
					(size 1.27 1.27)
				)
				(justify mirror)
			)
		)
		(duplicate_pad_numbers_are_jumpers no)
		(fp_line
			(start -0.7874 -0.4064)
			(end -0.7874 0.4064)
			(stroke
				(width 0.1524)
				(type default)
			)
			(layer "B.SilkS")
		)
		(fp_line
			(start -0.7874 0.4064)
			(end 0.7874 0.4064)
			(stroke
				(width 0.1524)
				(type default)
			)
			(layer "B.SilkS")
		)
		(fp_line
			(start 0.7874 -0.4064)
			(end -0.7874 -0.4064)
			(stroke
				(width 0.1524)
				(type default)
			)
			(layer "B.SilkS")
		)
		(fp_line
			(start 0.7874 0.4064)
			(end 0.7874 -0.4064)
			(stroke
				(width 0.1524)
				(type default)
			)
			(layer "B.SilkS")
		)
		(fp_line
			(start -0.67945 -0.3048)
			(end -0.67945 0.3048)
			(stroke
				(width 0.1)
				(type default)
			)
			(layer "B.Fab")
		)
		(fp_line
			(start -0.67945 0.3048)
			(end -0.120396 0.3048)
			(stroke
				(width 0.1)
				(type default)
			)
			(layer "B.Fab")
		)
		(fp_line
			(start -0.12065 -0.3048)
			(end -0.67945 -0.3048)
			(stroke
				(width 0.1)
				(type default)
			)
			(layer "B.Fab")
		)
		(fp_line
			(start -0.12065 -0.2794)
			(end -0.12065 -0.3048)
			(stroke
				(width 0.1)
				(type default)
			)
			(layer "B.Fab")
		)
		(fp_line
			(start -0.120396 0.2794)
			(end 0.12065 0.2794)
			(stroke
				(width 0.1)
				(type default)
			)
			(layer "B.Fab")
		)
		(fp_line
			(start -0.120396 0.3048)
			(end -0.120396 0.2794)
			(stroke
				(width 0.1)
				(type default)
			)
			(layer "B.Fab")
		)
		(fp_line
			(start 0.12065 -0.305054)
			(end 0.12065 -0.2794)
			(stroke
				(width 0.1)
				(type default)
			)
			(layer "B.Fab")
		)
		(fp_line
			(start 0.12065 -0.2794)
			(end -0.12065 -0.2794)
			(stroke
				(width 0.1)
				(type default)
			)
			(layer "B.Fab")
		)
		(fp_line
			(start 0.12065 0.2794)
			(end 0.12065 0.3048)
			(stroke
				(width 0.1)
				(type default)
			)
			(layer "B.Fab")
		)
		(fp_line
			(start 0.12065 0.3048)
			(end 0.67945 0.3048)
			(stroke
				(width 0.1)
				(type default)
			)
			(layer "B.Fab")
		)
		(fp_line
			(start 0.67945 -0.305054)
			(end 0.12065 -0.305054)
			(stroke
				(width 0.1)
				(type default)
			)
			(layer "B.Fab")
		)
		(fp_line
			(start 0.67945 0.3048)
			(end 0.67945 -0.305054)
			(stroke
				(width 0.1)
				(type default)
			)
			(layer "B.Fab")
		)
		(pad "1" smd circle
			(at 0.40005 0 180)
			(size 0 0)
			(layers "B.Cu" "B.Mask" "B.Paste")
			(net "PWRGD_P52V_HS1_PG_N")
		)
		(pad "2" smd circle
			(at -0.40005 0 180)
			(size 0 0)
			(layers "B.Cu" "B.Mask" "B.Paste")
			(net "BRICK_P12V0_EN_N")
		)
	)
	(footprint ""
		(layer "B.Cu")
		(at 202.946 -85.09 180)
		(property "Reference" "R130"
			(at 0 0 0)
			(layer "B.SilkS")
			(hide yes)
			(effects
				(font
					(size 1.27 1.27)
				)
				(justify mirror)
			)
		)
		(property "Value" ""
			(at 0 0 0)
			(layer "B.Fab")
			(effects
				(font
					(size 1.27 1.27)
				)
				(justify mirror)
			)
		)
		(duplicate_pad_numbers_are_jumpers no)
		(fp_line
			(start 0.7874 0.4064)
			(end 0.7874 -0.4064)
			(stroke
				(width 0.1524)
				(type default)
			)
			(layer "B.SilkS")
		)
		(fp_line
			(start 0.7874 -0.4064)
			(end -0.7874 -0.4064)
			(stroke
				(width 0.1524)
				(type default)
			)
			(layer "B.SilkS")
		)
		(fp_line
			(start -0.7874 0.4064)
			(end 0.7874 0.4064)
			(stroke
				(width 0.1524)
				(type default)
			)
			(layer "B.SilkS")
		)
		(fp_line
			(start -0.7874 -0.4064)
			(end -0.7874 0.4064)
			(stroke
				(width 0.1524)
				(type default)
			)
			(layer "B.SilkS")
		)
		(fp_line
			(start 0.67945 0.3048)
			(end 0.67945 -0.305054)
			(stroke
				(width 0.1)
				(type default)
			)
			(layer "B.Fab")
		)
		(fp_line
			(start 0.67945 -0.305054)
			(end 0.12065 -0.305054)
			(stroke
				(width 0.1)
				(type default)
			)
			(layer "B.Fab")
		)
		(fp_line
			(start 0.12065 0.3048)
			(end 0.67945 0.3048)
			(stroke
				(width 0.1)
				(type default)
			)
			(layer "B.Fab")
		)
		(fp_line
			(start 0.12065 0.2794)
			(end 0.12065 0.3048)
			(stroke
				(width 0.1)
				(type default)
			)
			(layer "B.Fab")
		)
		(fp_line
			(start 0.12065 -0.2794)
			(end -0.12065 -0.2794)
			(stroke
				(width 0.1)
				(type default)
			)
			(layer "B.Fab")
		)
		(fp_line
			(start 0.12065 -0.305054)
			(end 0.12065 -0.2794)
			(stroke
				(width 0.1)
				(type default)
			)
			(layer "B.Fab")
		)
		(fp_line
			(start -0.120396 0.3048)
			(end -0.120396 0.2794)
			(stroke
				(width 0.1)
				(type default)
			)
			(layer "B.Fab")
		)
		(fp_line
			(start -0.120396 0.2794)
			(end 0.12065 0.2794)
			(stroke
				(width 0.1)
				(type default)
			)
			(layer "B.Fab")
		)
		(fp_line
			(start -0.12065 -0.2794)
			(end -0.12065 -0.3048)
			(stroke
				(width 0.1)
				(type default)
			)
			(layer "B.Fab")
		)
		(fp_line
			(start -0.12065 -0.3048)
			(end -0.67945 -0.3048)
			(stroke
				(width 0.1)
				(type default)
			)
			(layer "B.Fab")
		)
		(fp_line
			(start -0.67945 0.3048)
			(end -0.120396 0.3048)
			(stroke
				(width 0.1)
				(type default)
			)
			(layer "B.Fab")
		)
		(fp_line
			(start -0.67945 -0.3048)
			(end -0.67945 0.3048)
			(stroke
				(width 0.1)
				(type default)
			)
			(layer "B.Fab")
		)
		(pad "1" smd circle
			(at 0.40005 0)
			(size 0 0)
			(layers "B.Cu" "B.Mask" "B.Paste")
			(net "SMB_HPDB_MISC_SDA")
		)
		(pad "2" smd circle
			(at -0.40005 0)
			(size 0 0)
			(layers "B.Cu" "B.Mask" "B.Paste")
			(net "P3V3_AUX")
		)
	)
	(footprint ""
		(layer "B.Cu")
		(at 300.624494 -36.438586 -90)
		(property "Reference" "PD6"
			(at 7.001256 -0.117094 0)
			(unlocked yes)
			(layer "B.SilkS")
			(effects
				(font
					(size 0.7874 0.5842)
					(thickness 0.1524)
				)
				(justify left mirror)
			)
		)
		(property "Value" ""
			(at 0 0 90)
			(layer "B.Fab")
			(effects
				(font
					(size 1.27 1.27)
				)
				(justify mirror)
			)
		)
		(duplicate_pad_numbers_are_jumpers no)
		(fp_line
			(start -5.4102 3.109976)
			(end -5.4102 2.047494)
			(stroke
				(width 0.1524)
				(type default)
			)
			(layer "B.SilkS")
		)
		(fp_line
			(start -4.794504 3.109976)
			(end -3.554984 3.109976)
			(stroke
				(width 0.1524)
				(type default)
			)
			(layer "B.SilkS")
		)
		(fp_line
			(start -4.769104 3.109976)
			(end 4.664456 3.109976)
			(stroke
				(width 0.1524)
				(type default)
			)
			(layer "B.SilkS")
		)
		(fp_line
			(start -4.743704 3.109976)
			(end -5.4102 3.109976)
			(stroke
				(width 0.1524)
				(type default)
			)
			(layer "B.SilkS")
		)
		(fp_line
			(start -4.743704 3.109976)
			(end -4.6101 3.109976)
			(stroke
				(width 0.1524)
				(type default)
			)
			(layer "B.SilkS")
		)
		(fp_line
			(start -4.156202 3.109976)
			(end -4.183126 3.109976)
			(stroke
				(width 0.1524)
				(type default)
			)
			(layer "B.SilkS")
		)
		(fp_line
			(start 4.664456 3.109976)
			(end 4.664456 -3.109976)
			(stroke
				(width 0.1524)
				(type default)
			)
			(layer "B.SilkS")
		)
		(fp_line
			(start -4.715002 3.035554)
			(end -4.7117 2.984754)
			(stroke
				(width 0.1524)
				(type default)
			)
			(layer "B.SilkS")
		)
		(fp_line
			(start -5.313426 1.996694)
			(end -5.313426 3.109976)
			(stroke
				(width 0.1524)
				(type default)
			)
			(layer "B.SilkS")
		)
		(fp_line
			(start -5.262626 1.996694)
			(end -5.262626 3.109976)
			(stroke
				(width 0.1524)
				(type default)
			)
			(layer "B.SilkS")
		)
		(fp_line
			(start -5.211826 1.996694)
			(end -5.211826 3.109976)
			(stroke
				(width 0.1524)
				(type default)
			)
			(layer "B.SilkS")
		)
		(fp_line
			(start -0.762 1.27)
			(end -0.762 -1.27)
			(stroke
				(width 0.1524)
				(type default)
			)
			(layer "B.SilkS")
		)
		(fp_line
			(start -5.4102 1.107694)
			(end -5.4102 -0.822706)
			(stroke
				(width 0.1524)
				(type default)
			)
			(layer "B.SilkS")
		)
		(fp_line
			(start 0.508 1.016)
			(end 0.508 -1.016)
			(stroke
				(width 0.1524)
				(type default)
			)
			(layer "B.SilkS")
		)
		(fp_line
			(start -0.762 0)
			(end 0.508 1.016)
			(stroke
				(width 0.1524)
				(type default)
			)
			(layer "B.SilkS")
		)
		(fp_line
			(start -0.762 0)
			(end -1.2192 0)
			(stroke
				(width 0.1524)
				(type default)
			)
			(layer "B.SilkS")
		)
		(fp_line
			(start 1.0668 0)
			(end 0.6096 0)
			(stroke
				(width 0.1524)
				(type default)
			)
			(layer "B.SilkS")
		)
		(fp_line
			(start -5.313426 -0.822706)
			(end -5.313426 1.107694)
			(stroke
				(width 0.1524)
				(type default)
			)
			(layer "B.SilkS")
		)
		(fp_line
			(start -5.262626 -0.822706)
			(end -5.262626 1.107694)
			(stroke
				(width 0.1524)
				(type default)
			)
			(layer "B.SilkS")
		)
		(fp_line
			(start -5.211826 -0.822706)
			(end -5.211826 1.107694)
			(stroke
				(width 0.1524)
				(type default)
			)
			(layer "B.SilkS")
		)
		(fp_line
			(start 0.508 -1.016)
			(end -0.762 0)
			(stroke
				(width 0.1524)
				(type default)
			)
			(layer "B.SilkS")
		)
		(fp_line
			(start -5.4102 -1.762506)
			(end -5.4102 -3.109976)
			(stroke
				(width 0.1524)
				(type default)
			)
			(layer "B.SilkS")
		)
		(fp_line
			(start -5.4102 -3.109976)
			(end -4.783074 -3.109976)
			(stroke
				(width 0.1524)
				(type default)
			)
			(layer "B.SilkS")
		)
		(fp_line
			(start -5.313426 -3.109976)
			(end -5.313426 -1.762506)
			(stroke
				(width 0.1524)
				(type default)
			)
			(layer "B.SilkS")
		)
		(fp_line
			(start -5.262626 -3.109976)
			(end -5.262626 -1.762506)
			(stroke
				(width 0.1524)
				(type default)
			)
			(layer "B.SilkS")
		)
		(fp_line
			(start -5.211826 -3.109976)
			(end -5.211826 -1.762506)
			(stroke
				(width 0.1524)
				(type default)
			)
			(layer "B.SilkS")
		)
		(fp_line
			(start -5.110226 -3.109976)
			(end -5.110226 3.109976)
			(stroke
				(width 0.1524)
				(type default)
			)
			(layer "B.SilkS")
		)
		(fp_line
			(start -5.008626 -3.109976)
			(end -5.008626 3.109976)
			(stroke
				(width 0.1524)
				(type default)
			)
			(layer "B.SilkS")
		)
		(fp_line
			(start -4.932426 -3.109976)
			(end -4.932426 3.109976)
			(stroke
				(width 0.1524)
				(type default)
			)
			(layer "B.SilkS")
		)
		(fp_line
			(start -4.805426 -3.109976)
			(end -4.805426 3.109976)
			(stroke
				(width 0.1524)
				(type default)
			)
			(layer "B.SilkS")
		)
		(fp_line
			(start -4.70535 -3.109976)
			(end -4.70535 3.109976)
			(stroke
				(width 0.1524)
				(type default)
			)
			(layer "B.SilkS")
		)
		(fp_line
			(start -4.70535 -3.109976)
			(end -4.70535 3.109976)
			(stroke
				(width 0.1524)
				(type default)
			)
			(layer "B.SilkS")
		)
		(fp_line
			(start -4.70535 -3.109976)
			(end -4.70535 3.109976)
			(stroke
				(width 0.1524)
				(type default)
			)
			(layer "B.SilkS")
		)
		(fp_line
			(start -4.695444 -3.109976)
			(end -4.695444 3.109976)
			(stroke
				(width 0.1524)
				(type default)
			)
			(layer "B.SilkS")
		)
		(fp_line
			(start -4.6101 -3.109976)
			(end -4.283202 -3.109976)
			(stroke
				(width 0.1524)
				(type default)
			)
			(layer "B.SilkS")
		)
		(fp_line
			(start -4.511802 -3.109976)
			(end -4.207002 -3.109976)
			(stroke
				(width 0.1524)
				(type default)
			)
			(layer "B.SilkS")
		)
		(fp_line
			(start -4.183126 -3.109976)
			(end -4.794504 -3.109976)
			(stroke
				(width 0.1524)
				(type default)
			)
			(layer "B.SilkS")
		)
		(fp_line
			(start 4.664456 -3.109976)
			(end -4.743704 -3.109976)
			(stroke
				(width 0.1524)
				(type default)
			)
			(layer "B.SilkS")
		)
		(fp_line
			(start -4.065016 3.109976)
			(end 4.065016 3.109976)
			(stroke
				(width 0.1)
				(type default)
			)
			(layer "B.Fab")
		)
		(fp_line
			(start 4.065016 3.109976)
			(end 4.065016 -3.109976)
			(stroke
				(width 0.1)
				(type default)
			)
			(layer "B.Fab")
		)
		(fp_line
			(start -4.065016 -3.109976)
			(end -4.065016 3.109976)
			(stroke
				(width 0.1)
				(type default)
			)
			(layer "B.Fab")
		)
		(fp_line
			(start 4.065016 -3.109976)
			(end -4.065016 -3.109976)
			(stroke
				(width 0.1)
				(type default)
			)
			(layer "B.Fab")
		)
		(fp_text user "-"
			(at -7.122414 -2.815844 90)
			(unlocked yes)
			(layer "B.SilkS")
			(effects
				(font
					(size 1.905 1.4224)
					(thickness 0.1524)
				)
				(justify left mirror)
			)
		)
		(fp_text user "+"
			(at 3.850894 -3.69443 90)
			(unlocked yes)
			(layer "B.SilkS")
			(effects
				(font
					(size 1.905 1.4224)
					(thickness 0.1524)
				)
				(justify left mirror)
			)
		)
		(fp_text user "-"
			(at -6.643624 0.40005 90)
			(unlocked yes)
			(layer "B.Fab")
			(effects
				(font
					(size 1.905 1.4224)
					(thickness 0.1524)
				)
				(justify left mirror)
			)
		)
		(fp_text user "+"
			(at 4.5974 0.24765 90)
			(unlocked yes)
			(layer "B.Fab")
			(effects
				(font
					(size 1.905 1.4224)
					(thickness 0.1524)
				)
				(justify left mirror)
			)
		)
		(pad "A" smd rect
			(at 3.299968 0 270)
			(size 2.413 3.302)
			(layers "B.Cu" "B.Mask" "B.Paste")
			(net "GND")
		)
		(pad "C" smd rect
			(at -3.299968 0 270)
			(size 2.413 3.302)
			(layers "B.Cu" "B.Mask" "B.Paste")
			(net "P52V_1_FUSE_1")
		)
	)
	(footprint ""
		(layer "B.Cu")
		(at 38.989 -89.027)
		(property "Reference" "R77"
			(at 0 0 0)
			(layer "B.SilkS")
			(hide yes)
			(effects
				(font
					(size 1.27 1.27)
				)
				(justify mirror)
			)
		)
		(property "Value" ""
			(at 0 0 0)
			(layer "B.Fab")
			(effects
				(font
					(size 1.27 1.27)
				)
				(justify mirror)
			)
		)
		(duplicate_pad_numbers_are_jumpers no)
		(fp_line
			(start -0.7874 -0.4064)
			(end -0.7874 0.4064)
			(stroke
				(width 0.1524)
				(type default)
			)
			(layer "B.SilkS")
		)
		(fp_line
			(start -0.7874 0.4064)
			(end 0.7874 0.4064)
			(stroke
				(width 0.1524)
				(type default)
			)
			(layer "B.SilkS")
		)
		(fp_line
			(start 0.7874 -0.4064)
			(end -0.7874 -0.4064)
			(stroke
				(width 0.1524)
				(type default)
			)
			(layer "B.SilkS")
		)
		(fp_line
			(start 0.7874 0.4064)
			(end 0.7874 -0.4064)
			(stroke
				(width 0.1524)
				(type default)
			)
			(layer "B.SilkS")
		)
		(fp_line
			(start -0.67945 -0.3048)
			(end -0.67945 0.3048)
			(stroke
				(width 0.1)
				(type default)
			)
			(layer "B.Fab")
		)
		(fp_line
			(start -0.67945 0.3048)
			(end -0.120396 0.3048)
			(stroke
				(width 0.1)
				(type default)
			)
			(layer "B.Fab")
		)
		(fp_line
			(start -0.12065 -0.3048)
			(end -0.67945 -0.3048)
			(stroke
				(width 0.1)
				(type default)
			)
			(layer "B.Fab")
		)
		(fp_line
			(start -0.12065 -0.2794)
			(end -0.12065 -0.3048)
			(stroke
				(width 0.1)
				(type default)
			)
			(layer "B.Fab")
		)
		(fp_line
			(start -0.120396 0.2794)
			(end 0.12065 0.2794)
			(stroke
				(width 0.1)
				(type default)
			)
			(layer "B.Fab")
		)
		(fp_line
			(start -0.120396 0.3048)
			(end -0.120396 0.2794)
			(stroke
				(width 0.1)
				(type default)
			)
			(layer "B.Fab")
		)
		(fp_line
			(start 0.12065 -0.305054)
			(end 0.12065 -0.2794)
			(stroke
				(width 0.1)
				(type default)
			)
			(layer "B.Fab")
		)
		(fp_line
			(start 0.12065 -0.2794)
			(end -0.12065 -0.2794)
			(stroke
				(width 0.1)
				(type default)
			)
			(layer "B.Fab")
		)
		(fp_line
			(start 0.12065 0.2794)
			(end 0.12065 0.3048)
			(stroke
				(width 0.1)
				(type default)
			)
			(layer "B.Fab")
		)
		(fp_line
			(start 0.12065 0.3048)
			(end 0.67945 0.3048)
			(stroke
				(width 0.1)
				(type default)
			)
			(layer "B.Fab")
		)
		(fp_line
			(start 0.67945 -0.305054)
			(end 0.12065 -0.305054)
			(stroke
				(width 0.1)
				(type default)
			)
			(layer "B.Fab")
		)
		(fp_line
			(start 0.67945 0.3048)
			(end 0.67945 -0.305054)
			(stroke
				(width 0.1)
				(type default)
			)
			(layer "B.Fab")
		)
		(pad "1" smd circle
			(at 0.40005 0 180)
			(size 0 0)
			(layers "B.Cu" "B.Mask" "B.Paste")
			(net "SMB_HPDB_MISC_SDA")
		)
		(pad "2" smd circle
			(at -0.40005 0 180)
			(size 0 0)
			(layers "B.Cu" "B.Mask" "B.Paste")
			(net "SMB_HPDB_MISC_R_SDA")
		)
	)
	(footprint ""
		(layer "B.Cu")
		(at 216.154 -69.723 -90)
		(property "Reference" "R134"
			(at 0 0 90)
			(layer "B.SilkS")
			(hide yes)
			(effects
				(font
					(size 1.27 1.27)
				)
				(justify mirror)
			)
		)
		(property "Value" ""
			(at 0 0 90)
			(layer "B.Fab")
			(effects
				(font
					(size 1.27 1.27)
				)
				(justify mirror)
			)
		)
		(duplicate_pad_numbers_are_jumpers no)
		(fp_line
			(start -0.7874 0.4064)
			(end 0.7874 0.4064)
			(stroke
				(width 0.1524)
				(type default)
			)
			(layer "B.SilkS")
		)
		(fp_line
			(start 0.7874 0.4064)
			(end 0.7874 -0.4064)
			(stroke
				(width 0.1524)
				(type default)
			)
			(layer "B.SilkS")
		)
		(fp_line
			(start -0.7874 -0.4064)
			(end -0.7874 0.4064)
			(stroke
				(width 0.1524)
				(type default)
			)
			(layer "B.SilkS")
		)
		(fp_line
			(start 0.7874 -0.4064)
			(end -0.7874 -0.4064)
			(stroke
				(width 0.1524)
				(type default)
			)
			(layer "B.SilkS")
		)
		(fp_line
			(start -0.67945 0.3048)
			(end -0.120396 0.3048)
			(stroke
				(width 0.1)
				(type default)
			)
			(layer "B.Fab")
		)
		(fp_line
			(start -0.120396 0.3048)
			(end -0.120396 0.2794)
			(stroke
				(width 0.1)
				(type default)
			)
			(layer "B.Fab")
		)
		(fp_line
			(start 0.12065 0.3048)
			(end 0.67945 0.3048)
			(stroke
				(width 0.1)
				(type default)
			)
			(layer "B.Fab")
		)
		(fp_line
			(start 0.67945 0.3048)
			(end 0.67945 -0.305054)
			(stroke
				(width 0.1)
				(type default)
			)
			(layer "B.Fab")
		)
		(fp_line
			(start -0.120396 0.2794)
			(end 0.12065 0.2794)
			(stroke
				(width 0.1)
				(type default)
			)
			(layer "B.Fab")
		)
		(fp_line
			(start 0.12065 0.2794)
			(end 0.12065 0.3048)
			(stroke
				(width 0.1)
				(type default)
			)
			(layer "B.Fab")
		)
		(fp_line
			(start -0.12065 -0.2794)
			(end -0.12065 -0.3048)
			(stroke
				(width 0.1)
				(type default)
			)
			(layer "B.Fab")
		)
		(fp_line
			(start 0.12065 -0.2794)
			(end -0.12065 -0.2794)
			(stroke
				(width 0.1)
				(type default)
			)
			(layer "B.Fab")
		)
		(fp_line
			(start -0.67945 -0.3048)
			(end -0.67945 0.3048)
			(stroke
				(width 0.1)
				(type default)
			)
			(layer "B.Fab")
		)
		(fp_line
			(start -0.12065 -0.3048)
			(end -0.67945 -0.3048)
			(stroke
				(width 0.1)
				(type default)
			)
			(layer "B.Fab")
		)
		(fp_line
			(start 0.12065 -0.305054)
			(end 0.12065 -0.2794)
			(stroke
				(width 0.1)
				(type default)
			)
			(layer "B.Fab")
		)
		(fp_line
			(start 0.67945 -0.305054)
			(end 0.12065 -0.305054)
			(stroke
				(width 0.1)
				(type default)
			)
			(layer "B.Fab")
		)
		(pad "1" smd circle
			(at 0.40005 0 90)
			(size 0 0)
			(layers "B.Cu" "B.Mask" "B.Paste")
			(net "P3V3_AUX")
		)
		(pad "2" smd circle
			(at -0.40005 0 90)
			(size 0 0)
			(layers "B.Cu" "B.Mask" "B.Paste")
			(net "BOARD_ID_1")
		)
	)
	(footprint ""
		(layer "B.Cu")
		(at 231.775 -82.296 -90)
		(property "Reference" "C5"
			(at 0 0 90)
			(layer "B.SilkS")
			(hide yes)
			(effects
				(font
					(size 1.27 1.27)
				)
				(justify mirror)
			)
		)
		(property "Value" ""
			(at 0 0 90)
			(layer "B.Fab")
			(effects
				(font
					(size 1.27 1.27)
				)
				(justify mirror)
			)
		)
		(duplicate_pad_numbers_are_jumpers no)
		(fp_line
			(start -0.7874 0.4064)
			(end 0.7874 0.4064)
			(stroke
				(width 0.1524)
				(type default)
			)
			(layer "B.SilkS")
		)
		(fp_line
			(start 0.7874 0.4064)
			(end 0.7874 -0.4064)
			(stroke
				(width 0.1524)
				(type default)
			)
			(layer "B.SilkS")
		)
		(fp_line
			(start -0.7874 -0.4064)
			(end -0.7874 0.4064)
			(stroke
				(width 0.1524)
				(type default)
			)
			(layer "B.SilkS")
		)
		(fp_line
			(start 0.7874 -0.4064)
			(end -0.7874 -0.4064)
			(stroke
				(width 0.1524)
				(type default)
			)
			(layer "B.SilkS")
		)
		(fp_line
			(start -0.67945 0.3048)
			(end -0.120396 0.3048)
			(stroke
				(width 0.1)
				(type default)
			)
			(layer "B.Fab")
		)
		(fp_line
			(start -0.120396 0.3048)
			(end -0.120396 0.2794)
			(stroke
				(width 0.1)
				(type default)
			)
			(layer "B.Fab")
		)
		(fp_line
			(start 0.12065 0.3048)
			(end 0.67945 0.3048)
			(stroke
				(width 0.1)
				(type default)
			)
			(layer "B.Fab")
		)
		(fp_line
			(start 0.67945 0.3048)
			(end 0.67945 -0.305054)
			(stroke
				(width 0.1)
				(type default)
			)
			(layer "B.Fab")
		)
		(fp_line
			(start -0.120396 0.2794)
			(end 0.12065 0.2794)
			(stroke
				(width 0.1)
				(type default)
			)
			(layer "B.Fab")
		)
		(fp_line
			(start 0.12065 0.2794)
			(end 0.12065 0.3048)
			(stroke
				(width 0.1)
				(type default)
			)
			(layer "B.Fab")
		)
		(fp_line
			(start -0.12065 -0.2794)
			(end -0.12065 -0.3048)
			(stroke
				(width 0.1)
				(type default)
			)
			(layer "B.Fab")
		)
		(fp_line
			(start 0.12065 -0.2794)
			(end -0.12065 -0.2794)
			(stroke
				(width 0.1)
				(type default)
			)
			(layer "B.Fab")
		)
		(fp_line
			(start -0.67945 -0.3048)
			(end -0.67945 0.3048)
			(stroke
				(width 0.1)
				(type default)
			)
			(layer "B.Fab")
		)
		(fp_line
			(start -0.12065 -0.3048)
			(end -0.67945 -0.3048)
			(stroke
				(width 0.1)
				(type default)
			)
			(layer "B.Fab")
		)
		(fp_line
			(start 0.12065 -0.305054)
			(end 0.12065 -0.2794)
			(stroke
				(width 0.1)
				(type default)
			)
			(layer "B.Fab")
		)
		(fp_line
			(start 0.67945 -0.305054)
			(end 0.12065 -0.305054)
			(stroke
				(width 0.1)
				(type default)
			)
			(layer "B.Fab")
		)
		(pad "1" smd circle
			(at 0.40005 0 90)
			(size 0 0)
			(layers "B.Cu" "B.Mask" "B.Paste")
			(net "P3V3_AUX")
		)
		(pad "2" smd circle
			(at -0.40005 0 90)
			(size 0 0)
			(layers "B.Cu" "B.Mask" "B.Paste")
			(net "GND")
		)
	)
	(footprint ""
		(layer "B.Cu")
		(at 210.058 -90.551 90)
		(property "Reference" "R29"
			(at 0 0 90)
			(layer "B.SilkS")
			(hide yes)
			(effects
				(font
					(size 1.27 1.27)
				)
				(justify mirror)
			)
		)
		(property "Value" ""
			(at 0 0 90)
			(layer "B.Fab")
			(effects
				(font
					(size 1.27 1.27)
				)
				(justify mirror)
			)
		)
		(duplicate_pad_numbers_are_jumpers no)
		(fp_line
			(start 0.7874 -0.4064)
			(end -0.7874 -0.4064)
			(stroke
				(width 0.1524)
				(type default)
			)
			(layer "B.SilkS")
		)
		(fp_line
			(start -0.7874 -0.4064)
			(end -0.7874 0.4064)
			(stroke
				(width 0.1524)
				(type default)
			)
			(layer "B.SilkS")
		)
		(fp_line
			(start 0.7874 0.4064)
			(end 0.7874 -0.4064)
			(stroke
				(width 0.1524)
				(type default)
			)
			(layer "B.SilkS")
		)
		(fp_line
			(start -0.7874 0.4064)
			(end 0.7874 0.4064)
			(stroke
				(width 0.1524)
				(type default)
			)
			(layer "B.SilkS")
		)
		(fp_line
			(start 0.67945 -0.305054)
			(end 0.12065 -0.305054)
			(stroke
				(width 0.1)
				(type default)
			)
			(layer "B.Fab")
		)
		(fp_line
			(start 0.12065 -0.305054)
			(end 0.12065 -0.2794)
			(stroke
				(width 0.1)
				(type default)
			)
			(layer "B.Fab")
		)
		(fp_line
			(start -0.12065 -0.3048)
			(end -0.67945 -0.3048)
			(stroke
				(width 0.1)
				(type default)
			)
			(layer "B.Fab")
		)
		(fp_line
			(start -0.67945 -0.3048)
			(end -0.67945 0.3048)
			(stroke
				(width 0.1)
				(type default)
			)
			(layer "B.Fab")
		)
		(fp_line
			(start 0.12065 -0.2794)
			(end -0.12065 -0.2794)
			(stroke
				(width 0.1)
				(type default)
			)
			(layer "B.Fab")
		)
		(fp_line
			(start -0.12065 -0.2794)
			(end -0.12065 -0.3048)
			(stroke
				(width 0.1)
				(type default)
			)
			(layer "B.Fab")
		)
		(fp_line
			(start 0.12065 0.2794)
			(end 0.12065 0.3048)
			(stroke
				(width 0.1)
				(type default)
			)
			(layer "B.Fab")
		)
		(fp_line
			(start -0.120396 0.2794)
			(end 0.12065 0.2794)
			(stroke
				(width 0.1)
				(type default)
			)
			(layer "B.Fab")
		)
		(fp_line
			(start 0.67945 0.3048)
			(end 0.67945 -0.305054)
			(stroke
				(width 0.1)
				(type default)
			)
			(layer "B.Fab")
		)
		(fp_line
			(start 0.12065 0.3048)
			(end 0.67945 0.3048)
			(stroke
				(width 0.1)
				(type default)
			)
			(layer "B.Fab")
		)
		(fp_line
			(start -0.120396 0.3048)
			(end -0.120396 0.2794)
			(stroke
				(width 0.1)
				(type default)
			)
			(layer "B.Fab")
		)
		(fp_line
			(start -0.67945 0.3048)
			(end -0.120396 0.3048)
			(stroke
				(width 0.1)
				(type default)
			)
			(layer "B.Fab")
		)
		(pad "1" smd circle
			(at 0.40005 0 270)
			(size 0 0)
			(layers "B.Cu" "B.Mask" "B.Paste")
			(net "P3V3_AUX")
		)
		(pad "2" smd circle
			(at -0.40005 0 270)
			(size 0 0)
			(layers "B.Cu" "B.Mask" "B.Paste")
			(net "PWRGD_GPU_HSC_BUF")
		)
	)
	(footprint ""
		(layer "B.Cu")
		(at 139.573 -114.046 90)
		(property "Reference" "R399"
			(at 0 0 90)
			(layer "B.SilkS")
			(hide yes)
			(effects
				(font
					(size 1.27 1.27)
				)
				(justify mirror)
			)
		)
		(property "Value" ""
			(at 0 0 90)
			(layer "B.Fab")
			(effects
				(font
					(size 1.27 1.27)
				)
				(justify mirror)
			)
		)
		(duplicate_pad_numbers_are_jumpers no)
		(fp_line
			(start 0.7874 -0.4064)
			(end -0.7874 -0.4064)
			(stroke
				(width 0.1524)
				(type default)
			)
			(layer "B.SilkS")
		)
		(fp_line
			(start -0.7874 -0.4064)
			(end -0.7874 0.4064)
			(stroke
				(width 0.1524)
				(type default)
			)
			(layer "B.SilkS")
		)
		(fp_line
			(start 0.7874 0.4064)
			(end 0.7874 -0.4064)
			(stroke
				(width 0.1524)
				(type default)
			)
			(layer "B.SilkS")
		)
		(fp_line
			(start -0.7874 0.4064)
			(end 0.7874 0.4064)
			(stroke
				(width 0.1524)
				(type default)
			)
			(layer "B.SilkS")
		)
		(fp_line
			(start 0.67945 -0.305054)
			(end 0.12065 -0.305054)
			(stroke
				(width 0.1)
				(type default)
			)
			(layer "B.Fab")
		)
		(fp_line
			(start 0.12065 -0.305054)
			(end 0.12065 -0.2794)
			(stroke
				(width 0.1)
				(type default)
			)
			(layer "B.Fab")
		)
		(fp_line
			(start -0.12065 -0.3048)
			(end -0.67945 -0.3048)
			(stroke
				(width 0.1)
				(type default)
			)
			(layer "B.Fab")
		)
		(fp_line
			(start -0.67945 -0.3048)
			(end -0.67945 0.3048)
			(stroke
				(width 0.1)
				(type default)
			)
			(layer "B.Fab")
		)
		(fp_line
			(start 0.12065 -0.2794)
			(end -0.12065 -0.2794)
			(stroke
				(width 0.1)
				(type default)
			)
			(layer "B.Fab")
		)
		(fp_line
			(start -0.12065 -0.2794)
			(end -0.12065 -0.3048)
			(stroke
				(width 0.1)
				(type default)
			)
			(layer "B.Fab")
		)
		(fp_line
			(start 0.12065 0.2794)
			(end 0.12065 0.3048)
			(stroke
				(width 0.1)
				(type default)
			)
			(layer "B.Fab")
		)
		(fp_line
			(start -0.120396 0.2794)
			(end 0.12065 0.2794)
			(stroke
				(width 0.1)
				(type default)
			)
			(layer "B.Fab")
		)
		(fp_line
			(start 0.67945 0.3048)
			(end 0.67945 -0.305054)
			(stroke
				(width 0.1)
				(type default)
			)
			(layer "B.Fab")
		)
		(fp_line
			(start 0.12065 0.3048)
			(end 0.67945 0.3048)
			(stroke
				(width 0.1)
				(type default)
			)
			(layer "B.Fab")
		)
		(fp_line
			(start -0.120396 0.3048)
			(end -0.120396 0.2794)
			(stroke
				(width 0.1)
				(type default)
			)
			(layer "B.Fab")
		)
		(fp_line
			(start -0.67945 0.3048)
			(end -0.120396 0.3048)
			(stroke
				(width 0.1)
				(type default)
			)
			(layer "B.Fab")
		)
		(pad "1" smd circle
			(at 0.40005 0 270)
			(size 0 0)
			(layers "B.Cu" "B.Mask" "B.Paste")
			(net "BRICK_P12V0_EN_N")
		)
		(pad "2" smd circle
			(at -0.40005 0 270)
			(size 0 0)
			(layers "B.Cu" "B.Mask" "B.Paste")
			(net "GND")
		)
	)
	(footprint ""
		(layer "B.Cu")
		(at 108.081826 -116.205)
		(property "Reference" "R200"
			(at 0 0 0)
			(layer "B.SilkS")
			(hide yes)
			(effects
				(font
					(size 1.27 1.27)
				)
				(justify mirror)
			)
		)
		(property "Value" ""
			(at 0 0 0)
			(layer "B.Fab")
			(effects
				(font
					(size 1.27 1.27)
				)
				(justify mirror)
			)
		)
		(duplicate_pad_numbers_are_jumpers no)
		(fp_line
			(start -0.7874 -0.4064)
			(end -0.7874 0.4064)
			(stroke
				(width 0.1524)
				(type default)
			)
			(layer "B.SilkS")
		)
		(fp_line
			(start -0.7874 0.4064)
			(end 0.7874 0.4064)
			(stroke
				(width 0.1524)
				(type default)
			)
			(layer "B.SilkS")
		)
		(fp_line
			(start 0.7874 -0.4064)
			(end -0.7874 -0.4064)
			(stroke
				(width 0.1524)
				(type default)
			)
			(layer "B.SilkS")
		)
		(fp_line
			(start 0.7874 0.4064)
			(end 0.7874 -0.4064)
			(stroke
				(width 0.1524)
				(type default)
			)
			(layer "B.SilkS")
		)
		(fp_line
			(start -0.67945 -0.3048)
			(end -0.67945 0.3048)
			(stroke
				(width 0.1)
				(type default)
			)
			(layer "B.Fab")
		)
		(fp_line
			(start -0.67945 0.3048)
			(end -0.120396 0.3048)
			(stroke
				(width 0.1)
				(type default)
			)
			(layer "B.Fab")
		)
		(fp_line
			(start -0.12065 -0.3048)
			(end -0.67945 -0.3048)
			(stroke
				(width 0.1)
				(type default)
			)
			(layer "B.Fab")
		)
		(fp_line
			(start -0.12065 -0.2794)
			(end -0.12065 -0.3048)
			(stroke
				(width 0.1)
				(type default)
			)
			(layer "B.Fab")
		)
		(fp_line
			(start -0.120396 0.2794)
			(end 0.12065 0.2794)
			(stroke
				(width 0.1)
				(type default)
			)
			(layer "B.Fab")
		)
		(fp_line
			(start -0.120396 0.3048)
			(end -0.120396 0.2794)
			(stroke
				(width 0.1)
				(type default)
			)
			(layer "B.Fab")
		)
		(fp_line
			(start 0.12065 -0.305054)
			(end 0.12065 -0.2794)
			(stroke
				(width 0.1)
				(type default)
			)
			(layer "B.Fab")
		)
		(fp_line
			(start 0.12065 -0.2794)
			(end -0.12065 -0.2794)
			(stroke
				(width 0.1)
				(type default)
			)
			(layer "B.Fab")
		)
		(fp_line
			(start 0.12065 0.2794)
			(end 0.12065 0.3048)
			(stroke
				(width 0.1)
				(type default)
			)
			(layer "B.Fab")
		)
		(fp_line
			(start 0.12065 0.3048)
			(end 0.67945 0.3048)
			(stroke
				(width 0.1)
				(type default)
			)
			(layer "B.Fab")
		)
		(fp_line
			(start 0.67945 -0.305054)
			(end 0.12065 -0.305054)
			(stroke
				(width 0.1)
				(type default)
			)
			(layer "B.Fab")
		)
		(fp_line
			(start 0.67945 0.3048)
			(end 0.67945 -0.305054)
			(stroke
				(width 0.1)
				(type default)
			)
			(layer "B.Fab")
		)
		(pad "1" smd circle
			(at 0.40005 0 180)
			(size 0 0)
			(layers "B.Cu" "B.Mask" "B.Paste")
			(net "P12V_BRICK0_PWRGD")
		)
		(pad "2" smd circle
			(at -0.40005 0 180)
			(size 0 0)
			(layers "B.Cu" "B.Mask" "B.Paste")
			(net "BRICK_P12V_1_EN_N")
		)
	)
	(footprint ""
		(layer "B.Cu")
		(at 58.928 -78.613)
		(property "Reference" "R183"
			(at 0 0 0)
			(layer "B.SilkS")
			(hide yes)
			(effects
				(font
					(size 1.27 1.27)
				)
				(justify mirror)
			)
		)
		(property "Value" ""
			(at 0 0 0)
			(layer "B.Fab")
			(effects
				(font
					(size 1.27 1.27)
				)
				(justify mirror)
			)
		)
		(duplicate_pad_numbers_are_jumpers no)
		(fp_line
			(start -0.7874 -0.4064)
			(end -0.7874 0.4064)
			(stroke
				(width 0.1524)
				(type default)
			)
			(layer "B.SilkS")
		)
		(fp_line
			(start -0.7874 0.4064)
			(end 0.7874 0.4064)
			(stroke
				(width 0.1524)
				(type default)
			)
			(layer "B.SilkS")
		)
		(fp_line
			(start 0.7874 -0.4064)
			(end -0.7874 -0.4064)
			(stroke
				(width 0.1524)
				(type default)
			)
			(layer "B.SilkS")
		)
		(fp_line
			(start 0.7874 0.4064)
			(end 0.7874 -0.4064)
			(stroke
				(width 0.1524)
				(type default)
			)
			(layer "B.SilkS")
		)
		(fp_line
			(start -0.67945 -0.3048)
			(end -0.67945 0.3048)
			(stroke
				(width 0.1)
				(type default)
			)
			(layer "B.Fab")
		)
		(fp_line
			(start -0.67945 0.3048)
			(end -0.120396 0.3048)
			(stroke
				(width 0.1)
				(type default)
			)
			(layer "B.Fab")
		)
		(fp_line
			(start -0.12065 -0.3048)
			(end -0.67945 -0.3048)
			(stroke
				(width 0.1)
				(type default)
			)
			(layer "B.Fab")
		)
		(fp_line
			(start -0.12065 -0.2794)
			(end -0.12065 -0.3048)
			(stroke
				(width 0.1)
				(type default)
			)
			(layer "B.Fab")
		)
		(fp_line
			(start -0.120396 0.2794)
			(end 0.12065 0.2794)
			(stroke
				(width 0.1)
				(type default)
			)
			(layer "B.Fab")
		)
		(fp_line
			(start -0.120396 0.3048)
			(end -0.120396 0.2794)
			(stroke
				(width 0.1)
				(type default)
			)
			(layer "B.Fab")
		)
		(fp_line
			(start 0.12065 -0.305054)
			(end 0.12065 -0.2794)
			(stroke
				(width 0.1)
				(type default)
			)
			(layer "B.Fab")
		)
		(fp_line
			(start 0.12065 -0.2794)
			(end -0.12065 -0.2794)
			(stroke
				(width 0.1)
				(type default)
			)
			(layer "B.Fab")
		)
		(fp_line
			(start 0.12065 0.2794)
			(end 0.12065 0.3048)
			(stroke
				(width 0.1)
				(type default)
			)
			(layer "B.Fab")
		)
		(fp_line
			(start 0.12065 0.3048)
			(end 0.67945 0.3048)
			(stroke
				(width 0.1)
				(type default)
			)
			(layer "B.Fab")
		)
		(fp_line
			(start 0.67945 -0.305054)
			(end 0.12065 -0.305054)
			(stroke
				(width 0.1)
				(type default)
			)
			(layer "B.Fab")
		)
		(fp_line
			(start 0.67945 0.3048)
			(end 0.67945 -0.305054)
			(stroke
				(width 0.1)
				(type default)
			)
			(layer "B.Fab")
		)
		(pad "1" smd circle
			(at 0.40005 0 180)
			(size 0 0)
			(layers "B.Cu" "B.Mask" "B.Paste")
			(net "P3V3_AUX")
		)
		(pad "2" smd circle
			(at -0.40005 0 180)
			(size 0 0)
			(layers "B.Cu" "B.Mask" "B.Paste")
			(net "SMB_P52V_VPDB_SCL")
		)
	)
	(footprint ""
		(layer "B.Cu")
		(at 281.432 -27.178 180)
		(property "Reference" "D11"
			(at 0.9271 -2.19837 0)
			(unlocked yes)
			(layer "B.SilkS")
			(effects
				(font
					(size 0.7874 0.5842)
					(thickness 0.1524)
				)
				(justify left mirror)
			)
		)
		(property "Value" ""
			(at 0 0 0)
			(layer "B.Fab")
			(effects
				(font
					(size 1.27 1.27)
				)
				(justify mirror)
			)
		)
		(duplicate_pad_numbers_are_jumpers no)
		(fp_line
			(start 3.400044 1.459992)
			(end 3.400044 -1.459992)
			(stroke
				(width 0.1524)
				(type default)
			)
			(layer "B.SilkS")
		)
		(fp_line
			(start 3.400044 -1.459992)
			(end -4.107942 -1.459992)
			(stroke
				(width 0.1524)
				(type default)
			)
			(layer "B.SilkS")
		)
		(fp_line
			(start -4.107942 1.459992)
			(end 3.400044 1.459992)
			(stroke
				(width 0.1524)
				(type default)
			)
			(layer "B.SilkS")
		)
		(fp_line
			(start -4.107942 -1.459992)
			(end -4.107942 1.459992)
			(stroke
				(width 0.1524)
				(type default)
			)
			(layer "B.SilkS")
		)
		(fp_poly
			(pts
				(xy -4.107942 -1.459992) (xy -4.107942 1.459992) (xy -3.308096 1.459992) (xy -3.308096 -1.459992)
			)
			(stroke
				(width 0)
				(type default)
			)
			(fill yes)
			(layer "B.SilkS")
		)
		(fp_line
			(start 2.29997 1.459992)
			(end 2.29997 -1.459992)
			(stroke
				(width 0.1)
				(type default)
			)
			(layer "B.Fab")
		)
		(fp_line
			(start 2.29997 -1.459992)
			(end -2.29997 -1.459992)
			(stroke
				(width 0.1)
				(type default)
			)
			(layer "B.Fab")
		)
		(fp_line
			(start -2.29997 1.459992)
			(end 2.29997 1.459992)
			(stroke
				(width 0.1)
				(type default)
			)
			(layer "B.Fab")
		)
		(fp_line
			(start -2.29997 -1.459992)
			(end -2.29997 1.459992)
			(stroke
				(width 0.1)
				(type default)
			)
			(layer "B.Fab")
		)
		(fp_text user "+"
			(at 4.7752 -0.12065 180)
			(unlocked yes)
			(layer "B.SilkS")
			(effects
				(font
					(size 1.905 1.4224)
					(thickness 0.1524)
				)
				(justify left mirror)
			)
		)
		(fp_text user "-"
			(at -5.4102 0.29845 0)
			(unlocked yes)
			(layer "B.SilkS")
			(effects
				(font
					(size 1.905 1.4224)
					(thickness 0.1524)
				)
				(justify left mirror)
			)
		)
		(fp_text user "+"
			(at 4.7752 -0.12065 180)
			(unlocked yes)
			(layer "B.Fab")
			(effects
				(font
					(size 1.905 1.4224)
					(thickness 0.1524)
				)
				(justify left mirror)
			)
		)
		(fp_text user "-"
			(at -5.4102 0.29845 0)
			(unlocked yes)
			(layer "B.Fab")
			(effects
				(font
					(size 1.905 1.4224)
					(thickness 0.1524)
				)
				(justify left mirror)
			)
		)
		(pad "A" smd rect
			(at 1.999996 0 270)
			(size 1.7018 2.5146)
			(layers "B.Cu" "B.Mask" "B.Paste")
			(net "FM_AC_PWR_CYCLE_R_BUF")
		)
		(pad "C" smd rect
			(at -1.999996 0 270)
			(size 1.7018 2.5146)
			(layers "B.Cu" "B.Mask" "B.Paste")
			(net "FM_AC_PWR_CYCLE_BUF")
		)
	)
	(footprint ""
		(layer "B.Cu")
		(at 233.553 -70.993 90)
		(property "Reference" "R139"
			(at 0 0 90)
			(layer "B.SilkS")
			(hide yes)
			(effects
				(font
					(size 1.27 1.27)
				)
				(justify mirror)
			)
		)
		(property "Value" ""
			(at 0 0 90)
			(layer "B.Fab")
			(effects
				(font
					(size 1.27 1.27)
				)
				(justify mirror)
			)
		)
		(duplicate_pad_numbers_are_jumpers no)
		(fp_line
			(start 0.7874 -0.4064)
			(end -0.7874 -0.4064)
			(stroke
				(width 0.1524)
				(type default)
			)
			(layer "B.SilkS")
		)
		(fp_line
			(start -0.7874 -0.4064)
			(end -0.7874 0.4064)
			(stroke
				(width 0.1524)
				(type default)
			)
			(layer "B.SilkS")
		)
		(fp_line
			(start 0.7874 0.4064)
			(end 0.7874 -0.4064)
			(stroke
				(width 0.1524)
				(type default)
			)
			(layer "B.SilkS")
		)
		(fp_line
			(start -0.7874 0.4064)
			(end 0.7874 0.4064)
			(stroke
				(width 0.1524)
				(type default)
			)
			(layer "B.SilkS")
		)
		(fp_line
			(start 0.67945 -0.305054)
			(end 0.12065 -0.305054)
			(stroke
				(width 0.1)
				(type default)
			)
			(layer "B.Fab")
		)
		(fp_line
			(start 0.12065 -0.305054)
			(end 0.12065 -0.2794)
			(stroke
				(width 0.1)
				(type default)
			)
			(layer "B.Fab")
		)
		(fp_line
			(start -0.12065 -0.3048)
			(end -0.67945 -0.3048)
			(stroke
				(width 0.1)
				(type default)
			)
			(layer "B.Fab")
		)
		(fp_line
			(start -0.67945 -0.3048)
			(end -0.67945 0.3048)
			(stroke
				(width 0.1)
				(type default)
			)
			(layer "B.Fab")
		)
		(fp_line
			(start 0.12065 -0.2794)
			(end -0.12065 -0.2794)
			(stroke
				(width 0.1)
				(type default)
			)
			(layer "B.Fab")
		)
		(fp_line
			(start -0.12065 -0.2794)
			(end -0.12065 -0.3048)
			(stroke
				(width 0.1)
				(type default)
			)
			(layer "B.Fab")
		)
		(fp_line
			(start 0.12065 0.2794)
			(end 0.12065 0.3048)
			(stroke
				(width 0.1)
				(type default)
			)
			(layer "B.Fab")
		)
		(fp_line
			(start -0.120396 0.2794)
			(end 0.12065 0.2794)
			(stroke
				(width 0.1)
				(type default)
			)
			(layer "B.Fab")
		)
		(fp_line
			(start 0.67945 0.3048)
			(end 0.67945 -0.305054)
			(stroke
				(width 0.1)
				(type default)
			)
			(layer "B.Fab")
		)
		(fp_line
			(start 0.12065 0.3048)
			(end 0.67945 0.3048)
			(stroke
				(width 0.1)
				(type default)
			)
			(layer "B.Fab")
		)
		(fp_line
			(start -0.120396 0.3048)
			(end -0.120396 0.2794)
			(stroke
				(width 0.1)
				(type default)
			)
			(layer "B.Fab")
		)
		(fp_line
			(start -0.67945 0.3048)
			(end -0.120396 0.3048)
			(stroke
				(width 0.1)
				(type default)
			)
			(layer "B.Fab")
		)
		(pad "1" smd circle
			(at 0.40005 0 270)
			(size 0 0)
			(layers "B.Cu" "B.Mask" "B.Paste")
			(net "PWRGD_P3V3_AUX_MB")
		)
		(pad "2" smd circle
			(at -0.40005 0 270)
			(size 0 0)
			(layers "B.Cu" "B.Mask" "B.Paste")
			(net "PWRGD_P3V3_AUX_MB_R")
		)
	)
	(footprint ""
		(layer "B.Cu")
		(at 219.964 -95.504 90)
		(property "Reference" "C40"
			(at 0 0 90)
			(layer "B.SilkS")
			(hide yes)
			(effects
				(font
					(size 1.27 1.27)
				)
				(justify mirror)
			)
		)
		(property "Value" ""
			(at 0 0 90)
			(layer "B.Fab")
			(effects
				(font
					(size 1.27 1.27)
				)
				(justify mirror)
			)
		)
		(duplicate_pad_numbers_are_jumpers no)
		(fp_line
			(start 2.2098 -0.9398)
			(end -2.2098 -0.9398)
			(stroke
				(width 0.1524)
				(type default)
			)
			(layer "B.SilkS")
		)
		(fp_line
			(start -2.2098 -0.9398)
			(end -2.2098 0.9398)
			(stroke
				(width 0.1524)
				(type default)
			)
			(layer "B.SilkS")
		)
		(fp_line
			(start 2.2098 0.9398)
			(end 2.2098 -0.9398)
			(stroke
				(width 0.1524)
				(type default)
			)
			(layer "B.SilkS")
		)
		(fp_line
			(start -2.2098 0.9398)
			(end 2.2098 0.9398)
			(stroke
				(width 0.1524)
				(type default)
			)
			(layer "B.SilkS")
		)
		(fp_line
			(start 1.700022 -0.899922)
			(end -1.700022 -0.899922)
			(stroke
				(width 0.1)
				(type default)
			)
			(layer "B.Fab")
		)
		(fp_line
			(start -1.700022 -0.899922)
			(end -1.700022 0.899922)
			(stroke
				(width 0.1)
				(type default)
			)
			(layer "B.Fab")
		)
		(fp_line
			(start 1.700022 0.899922)
			(end 1.700022 -0.899922)
			(stroke
				(width 0.1)
				(type default)
			)
			(layer "B.Fab")
		)
		(fp_line
			(start -1.700022 0.899922)
			(end 1.700022 0.899922)
			(stroke
				(width 0.1)
				(type default)
			)
			(layer "B.Fab")
		)
		(pad "1" smd rect
			(at 1.4732 0 90)
			(size 1.1684 1.5748)
			(layers "B.Cu" "B.Mask" "B.Paste")
			(net "P52V_HS")
		)
		(pad "2" smd rect
			(at -1.4732 0 90)
			(size 1.1684 1.5748)
			(layers "B.Cu" "B.Mask" "B.Paste")
			(net "GND")
		)
	)
	(footprint ""
		(layer "B.Cu")
		(at 205.994 -69.723 90)
		(property "Reference" "C4"
			(at 0 0 90)
			(layer "B.SilkS")
			(hide yes)
			(effects
				(font
					(size 1.27 1.27)
				)
				(justify mirror)
			)
		)
		(property "Value" ""
			(at 0 0 90)
			(layer "B.Fab")
			(effects
				(font
					(size 1.27 1.27)
				)
				(justify mirror)
			)
		)
		(duplicate_pad_numbers_are_jumpers no)
		(fp_line
			(start 0.7874 -0.4064)
			(end -0.7874 -0.4064)
			(stroke
				(width 0.1524)
				(type default)
			)
			(layer "B.SilkS")
		)
		(fp_line
			(start -0.7874 -0.4064)
			(end -0.7874 0.4064)
			(stroke
				(width 0.1524)
				(type default)
			)
			(layer "B.SilkS")
		)
		(fp_line
			(start 0.7874 0.4064)
			(end 0.7874 -0.4064)
			(stroke
				(width 0.1524)
				(type default)
			)
			(layer "B.SilkS")
		)
		(fp_line
			(start -0.7874 0.4064)
			(end 0.7874 0.4064)
			(stroke
				(width 0.1524)
				(type default)
			)
			(layer "B.SilkS")
		)
		(fp_line
			(start 0.67945 -0.305054)
			(end 0.12065 -0.305054)
			(stroke
				(width 0.1)
				(type default)
			)
			(layer "B.Fab")
		)
		(fp_line
			(start 0.12065 -0.305054)
			(end 0.12065 -0.2794)
			(stroke
				(width 0.1)
				(type default)
			)
			(layer "B.Fab")
		)
		(fp_line
			(start -0.12065 -0.3048)
			(end -0.67945 -0.3048)
			(stroke
				(width 0.1)
				(type default)
			)
			(layer "B.Fab")
		)
		(fp_line
			(start -0.67945 -0.3048)
			(end -0.67945 0.3048)
			(stroke
				(width 0.1)
				(type default)
			)
			(layer "B.Fab")
		)
		(fp_line
			(start 0.12065 -0.2794)
			(end -0.12065 -0.2794)
			(stroke
				(width 0.1)
				(type default)
			)
			(layer "B.Fab")
		)
		(fp_line
			(start -0.12065 -0.2794)
			(end -0.12065 -0.3048)
			(stroke
				(width 0.1)
				(type default)
			)
			(layer "B.Fab")
		)
		(fp_line
			(start 0.12065 0.2794)
			(end 0.12065 0.3048)
			(stroke
				(width 0.1)
				(type default)
			)
			(layer "B.Fab")
		)
		(fp_line
			(start -0.120396 0.2794)
			(end 0.12065 0.2794)
			(stroke
				(width 0.1)
				(type default)
			)
			(layer "B.Fab")
		)
		(fp_line
			(start 0.67945 0.3048)
			(end 0.67945 -0.305054)
			(stroke
				(width 0.1)
				(type default)
			)
			(layer "B.Fab")
		)
		(fp_line
			(start 0.12065 0.3048)
			(end 0.67945 0.3048)
			(stroke
				(width 0.1)
				(type default)
			)
			(layer "B.Fab")
		)
		(fp_line
			(start -0.120396 0.3048)
			(end -0.120396 0.2794)
			(stroke
				(width 0.1)
				(type default)
			)
			(layer "B.Fab")
		)
		(fp_line
			(start -0.67945 0.3048)
			(end -0.120396 0.3048)
			(stroke
				(width 0.1)
				(type default)
			)
			(layer "B.Fab")
		)
		(pad "1" smd circle
			(at 0.40005 0 270)
			(size 0 0)
			(layers "B.Cu" "B.Mask" "B.Paste")
			(net "P3V3_AUX")
		)
		(pad "2" smd circle
			(at -0.40005 0 270)
			(size 0 0)
			(layers "B.Cu" "B.Mask" "B.Paste")
			(net "GND")
		)
	)
	(footprint ""
		(layer "B.Cu")
		(at 206.121 -82.55 90)
		(property "Reference" "R17"
			(at 0 0 90)
			(layer "B.SilkS")
			(hide yes)
			(effects
				(font
					(size 1.27 1.27)
				)
				(justify mirror)
			)
		)
		(property "Value" ""
			(at 0 0 90)
			(layer "B.Fab")
			(effects
				(font
					(size 1.27 1.27)
				)
				(justify mirror)
			)
		)
		(duplicate_pad_numbers_are_jumpers no)
		(fp_line
			(start 0.7874 -0.4064)
			(end -0.7874 -0.4064)
			(stroke
				(width 0.1524)
				(type default)
			)
			(layer "B.SilkS")
		)
		(fp_line
			(start -0.7874 -0.4064)
			(end -0.7874 0.4064)
			(stroke
				(width 0.1524)
				(type default)
			)
			(layer "B.SilkS")
		)
		(fp_line
			(start 0.7874 0.4064)
			(end 0.7874 -0.4064)
			(stroke
				(width 0.1524)
				(type default)
			)
			(layer "B.SilkS")
		)
		(fp_line
			(start -0.7874 0.4064)
			(end 0.7874 0.4064)
			(stroke
				(width 0.1524)
				(type default)
			)
			(layer "B.SilkS")
		)
		(fp_line
			(start 0.67945 -0.305054)
			(end 0.12065 -0.305054)
			(stroke
				(width 0.1)
				(type default)
			)
			(layer "B.Fab")
		)
		(fp_line
			(start 0.12065 -0.305054)
			(end 0.12065 -0.2794)
			(stroke
				(width 0.1)
				(type default)
			)
			(layer "B.Fab")
		)
		(fp_line
			(start -0.12065 -0.3048)
			(end -0.67945 -0.3048)
			(stroke
				(width 0.1)
				(type default)
			)
			(layer "B.Fab")
		)
		(fp_line
			(start -0.67945 -0.3048)
			(end -0.67945 0.3048)
			(stroke
				(width 0.1)
				(type default)
			)
			(layer "B.Fab")
		)
		(fp_line
			(start 0.12065 -0.2794)
			(end -0.12065 -0.2794)
			(stroke
				(width 0.1)
				(type default)
			)
			(layer "B.Fab")
		)
		(fp_line
			(start -0.12065 -0.2794)
			(end -0.12065 -0.3048)
			(stroke
				(width 0.1)
				(type default)
			)
			(layer "B.Fab")
		)
		(fp_line
			(start 0.12065 0.2794)
			(end 0.12065 0.3048)
			(stroke
				(width 0.1)
				(type default)
			)
			(layer "B.Fab")
		)
		(fp_line
			(start -0.120396 0.2794)
			(end 0.12065 0.2794)
			(stroke
				(width 0.1)
				(type default)
			)
			(layer "B.Fab")
		)
		(fp_line
			(start 0.67945 0.3048)
			(end 0.67945 -0.305054)
			(stroke
				(width 0.1)
				(type default)
			)
			(layer "B.Fab")
		)
		(fp_line
			(start 0.12065 0.3048)
			(end 0.67945 0.3048)
			(stroke
				(width 0.1)
				(type default)
			)
			(layer "B.Fab")
		)
		(fp_line
			(start -0.120396 0.3048)
			(end -0.120396 0.2794)
			(stroke
				(width 0.1)
				(type default)
			)
			(layer "B.Fab")
		)
		(fp_line
			(start -0.67945 0.3048)
			(end -0.120396 0.3048)
			(stroke
				(width 0.1)
				(type default)
			)
			(layer "B.Fab")
		)
		(pad "1" smd circle
			(at 0.40005 0 270)
			(size 0 0)
			(layers "B.Cu" "B.Mask" "B.Paste")
			(net "P3V3_AUX")
		)
		(pad "2" smd circle
			(at -0.40005 0 270)
			(size 0 0)
			(layers "B.Cu" "B.Mask" "B.Paste")
			(net "PU_U4_PIN1")
		)
	)
	(footprint ""
		(layer "B.Cu")
		(at 237.031784 -88.74379 90)
		(property "Reference" "R3"
			(at 0 0 90)
			(layer "B.SilkS")
			(hide yes)
			(effects
				(font
					(size 1.27 1.27)
				)
				(justify mirror)
			)
		)
		(property "Value" ""
			(at 0 0 90)
			(layer "B.Fab")
			(effects
				(font
					(size 1.27 1.27)
				)
				(justify mirror)
			)
		)
		(duplicate_pad_numbers_are_jumpers no)
		(fp_line
			(start 0.7874 -0.4064)
			(end -0.7874 -0.4064)
			(stroke
				(width 0.1524)
				(type default)
			)
			(layer "B.SilkS")
		)
		(fp_line
			(start -0.7874 -0.4064)
			(end -0.7874 0.4064)
			(stroke
				(width 0.1524)
				(type default)
			)
			(layer "B.SilkS")
		)
		(fp_line
			(start 0.7874 0.4064)
			(end 0.7874 -0.4064)
			(stroke
				(width 0.1524)
				(type default)
			)
			(layer "B.SilkS")
		)
		(fp_line
			(start -0.7874 0.4064)
			(end 0.7874 0.4064)
			(stroke
				(width 0.1524)
				(type default)
			)
			(layer "B.SilkS")
		)
		(fp_line
			(start 0.67945 -0.305054)
			(end 0.12065 -0.305054)
			(stroke
				(width 0.1)
				(type default)
			)
			(layer "B.Fab")
		)
		(fp_line
			(start 0.12065 -0.305054)
			(end 0.12065 -0.2794)
			(stroke
				(width 0.1)
				(type default)
			)
			(layer "B.Fab")
		)
		(fp_line
			(start -0.12065 -0.3048)
			(end -0.67945 -0.3048)
			(stroke
				(width 0.1)
				(type default)
			)
			(layer "B.Fab")
		)
		(fp_line
			(start -0.67945 -0.3048)
			(end -0.67945 0.3048)
			(stroke
				(width 0.1)
				(type default)
			)
			(layer "B.Fab")
		)
		(fp_line
			(start 0.12065 -0.2794)
			(end -0.12065 -0.2794)
			(stroke
				(width 0.1)
				(type default)
			)
			(layer "B.Fab")
		)
		(fp_line
			(start -0.12065 -0.2794)
			(end -0.12065 -0.3048)
			(stroke
				(width 0.1)
				(type default)
			)
			(layer "B.Fab")
		)
		(fp_line
			(start 0.12065 0.2794)
			(end 0.12065 0.3048)
			(stroke
				(width 0.1)
				(type default)
			)
			(layer "B.Fab")
		)
		(fp_line
			(start -0.120396 0.2794)
			(end 0.12065 0.2794)
			(stroke
				(width 0.1)
				(type default)
			)
			(layer "B.Fab")
		)
		(fp_line
			(start 0.67945 0.3048)
			(end 0.67945 -0.305054)
			(stroke
				(width 0.1)
				(type default)
			)
			(layer "B.Fab")
		)
		(fp_line
			(start 0.12065 0.3048)
			(end 0.67945 0.3048)
			(stroke
				(width 0.1)
				(type default)
			)
			(layer "B.Fab")
		)
		(fp_line
			(start -0.120396 0.3048)
			(end -0.120396 0.2794)
			(stroke
				(width 0.1)
				(type default)
			)
			(layer "B.Fab")
		)
		(fp_line
			(start -0.67945 0.3048)
			(end -0.120396 0.3048)
			(stroke
				(width 0.1)
				(type default)
			)
			(layer "B.Fab")
		)
		(pad "1" smd circle
			(at 0.40005 0 270)
			(size 0 0)
			(layers "B.Cu" "B.Mask" "B.Paste")
			(net "PWRGD_P3V3_AUX_MB_BUF")
		)
		(pad "2" smd circle
			(at -0.40005 0 270)
			(size 0 0)
			(layers "B.Cu" "B.Mask" "B.Paste")
			(net "MB_MISC_I2C_EN")
		)
	)
	(footprint ""
		(layer "B.Cu")
		(at 215.519 -87.63 -90)
		(property "Reference" "U8"
			(at 3.46837 -0.2032 0)
			(unlocked yes)
			(layer "B.SilkS")
			(effects
				(font
					(size 0.7874 0.5842)
					(thickness 0.1524)
				)
				(justify left mirror)
			)
		)
		(property "Value" ""
			(at 0 0 90)
			(layer "B.Fab")
			(effects
				(font
					(size 1.27 1.27)
				)
				(justify mirror)
			)
		)
		(duplicate_pad_numbers_are_jumpers no)
		(fp_line
			(start -2.032 1.549908)
			(end 2.032 1.549908)
			(stroke
				(width 0.1524)
				(type default)
			)
			(layer "B.SilkS")
		)
		(fp_line
			(start 2.032 1.549908)
			(end 2.032 -1.549908)
			(stroke
				(width 0.1524)
				(type default)
			)
			(layer "B.SilkS")
		)
		(fp_line
			(start -2.032 -1.549908)
			(end -2.032 1.549908)
			(stroke
				(width 0.1524)
				(type default)
			)
			(layer "B.SilkS")
		)
		(fp_line
			(start 2.032 -1.549908)
			(end -2.032 -1.549908)
			(stroke
				(width 0.1524)
				(type default)
			)
			(layer "B.SilkS")
		)
		(fp_poly
			(pts
				(xy 1.397 -2.5654) (xy 1.905 -2.5654) (xy 1.651 -1.8034)
			)
			(stroke
				(width 0)
				(type default)
			)
			(fill yes)
			(layer "B.SilkS")
		)
		(fp_line
			(start -0.849884 1.549908)
			(end -0.849884 -1.549908)
			(stroke
				(width 0.1)
				(type default)
			)
			(layer "B.Fab")
		)
		(fp_line
			(start 0.849884 1.549908)
			(end -0.849884 1.549908)
			(stroke
				(width 0.1)
				(type default)
			)
			(layer "B.Fab")
		)
		(fp_line
			(start -0.849884 -1.549908)
			(end 0.849884 -1.549908)
			(stroke
				(width 0.1)
				(type default)
			)
			(layer "B.Fab")
		)
		(fp_line
			(start 0.849884 -1.549908)
			(end 0.849884 1.549908)
			(stroke
				(width 0.1)
				(type default)
			)
			(layer "B.Fab")
		)
		(fp_poly
			(pts
				(xy 2.9464 -1.2192) (xy 2.9464 -0.7112) (xy 2.1844 -0.9652)
			)
			(stroke
				(width 0)
				(type default)
			)
			(fill yes)
			(layer "B.Fab")
		)
		(pad "1" smd rect
			(at 1.225042 -0.94996 180)
			(size 0.4572 1.3208)
			(layers "B.Cu" "B.Mask" "B.Paste")
			(net "PWRGD_P3V3_AUX_MB_BUF_N")
		)
		(pad "2" smd rect
			(at 1.225042 0 180)
			(size 0.4572 1.3208)
			(layers "B.Cu" "B.Mask" "B.Paste")
			(net "FAN_PWR_EN")
		)
		(pad "3" smd rect
			(at 1.225042 0.94996 180)
			(size 0.4572 1.3208)
			(layers "B.Cu" "B.Mask" "B.Paste")
			(net "GND")
		)
		(pad "4" smd rect
			(at -1.225042 0.94996 180)
			(size 0.4572 1.3208)
			(layers "B.Cu" "B.Mask" "B.Paste")
			(net "FAN_PWR_EN_BUF_R")
		)
		(pad "5" smd rect
			(at -1.225042 -0.94996 180)
			(size 0.4572 1.3208)
			(layers "B.Cu" "B.Mask" "B.Paste")
			(net "P3V3_AUX")
		)
	)
	(footprint ""
		(layer "B.Cu")
		(at 100.849938 -76.708 90)
		(property "Reference" "PR73"
			(at 0 0 90)
			(layer "B.SilkS")
			(hide yes)
			(effects
				(font
					(size 1.27 1.27)
				)
				(justify mirror)
			)
		)
		(property "Value" ""
			(at 0 0 90)
			(layer "B.Fab")
			(effects
				(font
					(size 1.27 1.27)
				)
				(justify mirror)
			)
		)
		(duplicate_pad_numbers_are_jumpers no)
		(fp_line
			(start 0.7874 -0.4064)
			(end -0.7874 -0.4064)
			(stroke
				(width 0.1524)
				(type default)
			)
			(layer "B.SilkS")
		)
		(fp_line
			(start -0.7874 -0.4064)
			(end -0.7874 0.4064)
			(stroke
				(width 0.1524)
				(type default)
			)
			(layer "B.SilkS")
		)
		(fp_line
			(start 0.7874 0.4064)
			(end 0.7874 -0.4064)
			(stroke
				(width 0.1524)
				(type default)
			)
			(layer "B.SilkS")
		)
		(fp_line
			(start -0.7874 0.4064)
			(end 0.7874 0.4064)
			(stroke
				(width 0.1524)
				(type default)
			)
			(layer "B.SilkS")
		)
		(fp_line
			(start 0.67945 -0.305054)
			(end 0.12065 -0.305054)
			(stroke
				(width 0.1)
				(type default)
			)
			(layer "B.Fab")
		)
		(fp_line
			(start 0.12065 -0.305054)
			(end 0.12065 -0.2794)
			(stroke
				(width 0.1)
				(type default)
			)
			(layer "B.Fab")
		)
		(fp_line
			(start -0.12065 -0.3048)
			(end -0.67945 -0.3048)
			(stroke
				(width 0.1)
				(type default)
			)
			(layer "B.Fab")
		)
		(fp_line
			(start -0.67945 -0.3048)
			(end -0.67945 0.3048)
			(stroke
				(width 0.1)
				(type default)
			)
			(layer "B.Fab")
		)
		(fp_line
			(start 0.12065 -0.2794)
			(end -0.12065 -0.2794)
			(stroke
				(width 0.1)
				(type default)
			)
			(layer "B.Fab")
		)
		(fp_line
			(start -0.12065 -0.2794)
			(end -0.12065 -0.3048)
			(stroke
				(width 0.1)
				(type default)
			)
			(layer "B.Fab")
		)
		(fp_line
			(start 0.12065 0.2794)
			(end 0.12065 0.3048)
			(stroke
				(width 0.1)
				(type default)
			)
			(layer "B.Fab")
		)
		(fp_line
			(start -0.120396 0.2794)
			(end 0.12065 0.2794)
			(stroke
				(width 0.1)
				(type default)
			)
			(layer "B.Fab")
		)
		(fp_line
			(start 0.67945 0.3048)
			(end 0.67945 -0.305054)
			(stroke
				(width 0.1)
				(type default)
			)
			(layer "B.Fab")
		)
		(fp_line
			(start 0.12065 0.3048)
			(end 0.67945 0.3048)
			(stroke
				(width 0.1)
				(type default)
			)
			(layer "B.Fab")
		)
		(fp_line
			(start -0.120396 0.3048)
			(end -0.120396 0.2794)
			(stroke
				(width 0.1)
				(type default)
			)
			(layer "B.Fab")
		)
		(fp_line
			(start -0.67945 0.3048)
			(end -0.120396 0.3048)
			(stroke
				(width 0.1)
				(type default)
			)
			(layer "B.Fab")
		)
		(pad "1" smd circle
			(at 0.40005 0 270)
			(size 0 0)
			(layers "B.Cu" "B.Mask" "B.Paste")
			(net "GND")
		)
		(pad "2" smd circle
			(at -0.40005 0 270)
			(size 0 0)
			(layers "B.Cu" "B.Mask" "B.Paste")
			(net "BRICK1_PMBADD")
		)
	)
	(footprint ""
		(layer "B.Cu")
		(at 222.377 -95.504 90)
		(property "Reference" "C38"
			(at 0 0 90)
			(layer "B.SilkS")
			(hide yes)
			(effects
				(font
					(size 1.27 1.27)
				)
				(justify mirror)
			)
		)
		(property "Value" ""
			(at 0 0 90)
			(layer "B.Fab")
			(effects
				(font
					(size 1.27 1.27)
				)
				(justify mirror)
			)
		)
		(duplicate_pad_numbers_are_jumpers no)
		(fp_line
			(start 2.2098 -0.9398)
			(end -2.2098 -0.9398)
			(stroke
				(width 0.1524)
				(type default)
			)
			(layer "B.SilkS")
		)
		(fp_line
			(start -2.2098 -0.9398)
			(end -2.2098 0.9398)
			(stroke
				(width 0.1524)
				(type default)
			)
			(layer "B.SilkS")
		)
		(fp_line
			(start 2.2098 0.9398)
			(end 2.2098 -0.9398)
			(stroke
				(width 0.1524)
				(type default)
			)
			(layer "B.SilkS")
		)
		(fp_line
			(start -2.2098 0.9398)
			(end 2.2098 0.9398)
			(stroke
				(width 0.1524)
				(type default)
			)
			(layer "B.SilkS")
		)
		(fp_line
			(start 1.700022 -0.899922)
			(end -1.700022 -0.899922)
			(stroke
				(width 0.1)
				(type default)
			)
			(layer "B.Fab")
		)
		(fp_line
			(start -1.700022 -0.899922)
			(end -1.700022 0.899922)
			(stroke
				(width 0.1)
				(type default)
			)
			(layer "B.Fab")
		)
		(fp_line
			(start 1.700022 0.899922)
			(end 1.700022 -0.899922)
			(stroke
				(width 0.1)
				(type default)
			)
			(layer "B.Fab")
		)
		(fp_line
			(start -1.700022 0.899922)
			(end 1.700022 0.899922)
			(stroke
				(width 0.1)
				(type default)
			)
			(layer "B.Fab")
		)
		(pad "1" smd rect
			(at 1.4732 0 90)
			(size 1.1684 1.5748)
			(layers "B.Cu" "B.Mask" "B.Paste")
			(net "P52V_HS")
		)
		(pad "2" smd rect
			(at -1.4732 0 90)
			(size 1.1684 1.5748)
			(layers "B.Cu" "B.Mask" "B.Paste")
			(net "GND")
		)
	)
	(footprint ""
		(layer "B.Cu")
		(at 274.026122 -91.298522 180)
		(property "Reference" "R5863"
			(at 0 0 0)
			(layer "B.SilkS")
			(hide yes)
			(effects
				(font
					(size 1.27 1.27)
				)
				(justify mirror)
			)
		)
		(property "Value" ""
			(at 0 0 0)
			(layer "B.Fab")
			(effects
				(font
					(size 1.27 1.27)
				)
				(justify mirror)
			)
		)
		(duplicate_pad_numbers_are_jumpers no)
		(fp_line
			(start 0.7874 0.4064)
			(end 0.7874 -0.4064)
			(stroke
				(width 0.1524)
				(type default)
			)
			(layer "B.SilkS")
		)
		(fp_line
			(start 0.7874 -0.4064)
			(end -0.7874 -0.4064)
			(stroke
				(width 0.1524)
				(type default)
			)
			(layer "B.SilkS")
		)
		(fp_line
			(start -0.7874 0.4064)
			(end 0.7874 0.4064)
			(stroke
				(width 0.1524)
				(type default)
			)
			(layer "B.SilkS")
		)
		(fp_line
			(start -0.7874 -0.4064)
			(end -0.7874 0.4064)
			(stroke
				(width 0.1524)
				(type default)
			)
			(layer "B.SilkS")
		)
		(fp_line
			(start 0.67945 0.3048)
			(end 0.67945 -0.305054)
			(stroke
				(width 0.1)
				(type default)
			)
			(layer "B.Fab")
		)
		(fp_line
			(start 0.67945 -0.305054)
			(end 0.12065 -0.305054)
			(stroke
				(width 0.1)
				(type default)
			)
			(layer "B.Fab")
		)
		(fp_line
			(start 0.12065 0.3048)
			(end 0.67945 0.3048)
			(stroke
				(width 0.1)
				(type default)
			)
			(layer "B.Fab")
		)
		(fp_line
			(start 0.12065 0.2794)
			(end 0.12065 0.3048)
			(stroke
				(width 0.1)
				(type default)
			)
			(layer "B.Fab")
		)
		(fp_line
			(start 0.12065 -0.2794)
			(end -0.12065 -0.2794)
			(stroke
				(width 0.1)
				(type default)
			)
			(layer "B.Fab")
		)
		(fp_line
			(start 0.12065 -0.305054)
			(end 0.12065 -0.2794)
			(stroke
				(width 0.1)
				(type default)
			)
			(layer "B.Fab")
		)
		(fp_line
			(start -0.120396 0.3048)
			(end -0.120396 0.2794)
			(stroke
				(width 0.1)
				(type default)
			)
			(layer "B.Fab")
		)
		(fp_line
			(start -0.120396 0.2794)
			(end 0.12065 0.2794)
			(stroke
				(width 0.1)
				(type default)
			)
			(layer "B.Fab")
		)
		(fp_line
			(start -0.12065 -0.2794)
			(end -0.12065 -0.3048)
			(stroke
				(width 0.1)
				(type default)
			)
			(layer "B.Fab")
		)
		(fp_line
			(start -0.12065 -0.3048)
			(end -0.67945 -0.3048)
			(stroke
				(width 0.1)
				(type default)
			)
			(layer "B.Fab")
		)
		(fp_line
			(start -0.67945 0.3048)
			(end -0.120396 0.3048)
			(stroke
				(width 0.1)
				(type default)
			)
			(layer "B.Fab")
		)
		(fp_line
			(start -0.67945 -0.3048)
			(end -0.67945 0.3048)
			(stroke
				(width 0.1)
				(type default)
			)
			(layer "B.Fab")
		)
		(pad "1" smd circle
			(at 0.40005 0)
			(size 0 0)
			(layers "B.Cu" "B.Mask" "B.Paste")
			(net "P52V_HS1_GATE2_R")
		)
		(pad "2" smd circle
			(at -0.40005 0)
			(size 0 0)
			(layers "B.Cu" "B.Mask" "B.Paste")
			(net "P52V_HS1_4287_GATE2_R")
		)
	)
	(footprint ""
		(layer "B.Cu")
		(at 242.4557 -19.6215)
		(property "Reference" ""
			(at 0 0 0)
			(layer "B.SilkS")
			(hide yes)
			(effects
				(font
					(size 1.27 1.27)
				)
				(justify mirror)
			)
		)
		(property "Value" ""
			(at 0 0 0)
			(layer "B.Fab")
			(effects
				(font
					(size 1.27 1.27)
				)
				(justify mirror)
			)
		)
		(duplicate_pad_numbers_are_jumpers no)
		(pad "1" smd circle
			(at 0 0 180)
			(size 0.9906 0.9906)
			(layers "B.Cu" "B.Mask" "B.Paste")
			(net "Net_152")
		)
		(zone
			(layer "B.Cu")
			(hatch none 0.5)
			(connect_pads
				(clearance 0)
			)
			(min_thickness 0.25)
			(keepout
				(tracks not_allowed)
				(vias allowed)
				(pads allowed)
				(copperpour not_allowed)
				(footprints allowed)
			)
			(placement
				(enabled no)
				(sheetname "")
			)
			(fill
				(thermal_gap 0.5)
				(thermal_bridge_width 0.5)
				(island_removal_mode 0)
			)
			(polygon
				(pts
					(arc
						(start 244.0813 -19.6215)
						(mid 240.8301 -19.6215)
						(end 244.0813 -19.6215)
					)
				)
			)
		)
	)
	(footprint ""
		(layer "B.Cu")
		(at 222.25 -78.359 -90)
		(property "Reference" "R39"
			(at 0 0 90)
			(layer "B.SilkS")
			(hide yes)
			(effects
				(font
					(size 1.27 1.27)
				)
				(justify mirror)
			)
		)
		(property "Value" ""
			(at 0 0 90)
			(layer "B.Fab")
			(effects
				(font
					(size 1.27 1.27)
				)
				(justify mirror)
			)
		)
		(duplicate_pad_numbers_are_jumpers no)
		(fp_line
			(start -0.7874 0.4064)
			(end 0.7874 0.4064)
			(stroke
				(width 0.1524)
				(type default)
			)
			(layer "B.SilkS")
		)
		(fp_line
			(start 0.7874 0.4064)
			(end 0.7874 -0.4064)
			(stroke
				(width 0.1524)
				(type default)
			)
			(layer "B.SilkS")
		)
		(fp_line
			(start -0.7874 -0.4064)
			(end -0.7874 0.4064)
			(stroke
				(width 0.1524)
				(type default)
			)
			(layer "B.SilkS")
		)
		(fp_line
			(start 0.7874 -0.4064)
			(end -0.7874 -0.4064)
			(stroke
				(width 0.1524)
				(type default)
			)
			(layer "B.SilkS")
		)
		(fp_line
			(start -0.67945 0.3048)
			(end -0.120396 0.3048)
			(stroke
				(width 0.1)
				(type default)
			)
			(layer "B.Fab")
		)
		(fp_line
			(start -0.120396 0.3048)
			(end -0.120396 0.2794)
			(stroke
				(width 0.1)
				(type default)
			)
			(layer "B.Fab")
		)
		(fp_line
			(start 0.12065 0.3048)
			(end 0.67945 0.3048)
			(stroke
				(width 0.1)
				(type default)
			)
			(layer "B.Fab")
		)
		(fp_line
			(start 0.67945 0.3048)
			(end 0.67945 -0.305054)
			(stroke
				(width 0.1)
				(type default)
			)
			(layer "B.Fab")
		)
		(fp_line
			(start -0.120396 0.2794)
			(end 0.12065 0.2794)
			(stroke
				(width 0.1)
				(type default)
			)
			(layer "B.Fab")
		)
		(fp_line
			(start 0.12065 0.2794)
			(end 0.12065 0.3048)
			(stroke
				(width 0.1)
				(type default)
			)
			(layer "B.Fab")
		)
		(fp_line
			(start -0.12065 -0.2794)
			(end -0.12065 -0.3048)
			(stroke
				(width 0.1)
				(type default)
			)
			(layer "B.Fab")
		)
		(fp_line
			(start 0.12065 -0.2794)
			(end -0.12065 -0.2794)
			(stroke
				(width 0.1)
				(type default)
			)
			(layer "B.Fab")
		)
		(fp_line
			(start -0.67945 -0.3048)
			(end -0.67945 0.3048)
			(stroke
				(width 0.1)
				(type default)
			)
			(layer "B.Fab")
		)
		(fp_line
			(start -0.12065 -0.3048)
			(end -0.67945 -0.3048)
			(stroke
				(width 0.1)
				(type default)
			)
			(layer "B.Fab")
		)
		(fp_line
			(start 0.12065 -0.305054)
			(end 0.12065 -0.2794)
			(stroke
				(width 0.1)
				(type default)
			)
			(layer "B.Fab")
		)
		(fp_line
			(start 0.67945 -0.305054)
			(end 0.12065 -0.305054)
			(stroke
				(width 0.1)
				(type default)
			)
			(layer "B.Fab")
		)
		(pad "1" smd circle
			(at 0.40005 0 90)
			(size 0 0)
			(layers "B.Cu" "B.Mask" "B.Paste")
			(net "P3V3_AUX")
		)
		(pad "2" smd circle
			(at -0.40005 0 90)
			(size 0 0)
			(layers "B.Cu" "B.Mask" "B.Paste")
			(net "FRU_ADDR1")
		)
	)
	(footprint ""
		(layer "B.Cu")
		(at 277.876 -89.916)
		(property "Reference" "PR6970"
			(at 0 0 0)
			(layer "B.SilkS")
			(hide yes)
			(effects
				(font
					(size 1.27 1.27)
				)
				(justify mirror)
			)
		)
		(property "Value" ""
			(at 0 0 0)
			(layer "B.Fab")
			(effects
				(font
					(size 1.27 1.27)
				)
				(justify mirror)
			)
		)
		(duplicate_pad_numbers_are_jumpers no)
		(fp_line
			(start -0.7874 -0.4064)
			(end -0.7874 0.4064)
			(stroke
				(width 0.1524)
				(type default)
			)
			(layer "B.SilkS")
		)
		(fp_line
			(start -0.7874 0.4064)
			(end 0.7874 0.4064)
			(stroke
				(width 0.1524)
				(type default)
			)
			(layer "B.SilkS")
		)
		(fp_line
			(start 0.7874 -0.4064)
			(end -0.7874 -0.4064)
			(stroke
				(width 0.1524)
				(type default)
			)
			(layer "B.SilkS")
		)
		(fp_line
			(start 0.7874 0.4064)
			(end 0.7874 -0.4064)
			(stroke
				(width 0.1524)
				(type default)
			)
			(layer "B.SilkS")
		)
		(fp_line
			(start -0.67945 -0.3048)
			(end -0.67945 0.3048)
			(stroke
				(width 0.1)
				(type default)
			)
			(layer "B.Fab")
		)
		(fp_line
			(start -0.67945 0.3048)
			(end -0.120396 0.3048)
			(stroke
				(width 0.1)
				(type default)
			)
			(layer "B.Fab")
		)
		(fp_line
			(start -0.12065 -0.3048)
			(end -0.67945 -0.3048)
			(stroke
				(width 0.1)
				(type default)
			)
			(layer "B.Fab")
		)
		(fp_line
			(start -0.12065 -0.2794)
			(end -0.12065 -0.3048)
			(stroke
				(width 0.1)
				(type default)
			)
			(layer "B.Fab")
		)
		(fp_line
			(start -0.120396 0.2794)
			(end 0.12065 0.2794)
			(stroke
				(width 0.1)
				(type default)
			)
			(layer "B.Fab")
		)
		(fp_line
			(start -0.120396 0.3048)
			(end -0.120396 0.2794)
			(stroke
				(width 0.1)
				(type default)
			)
			(layer "B.Fab")
		)
		(fp_line
			(start 0.12065 -0.305054)
			(end 0.12065 -0.2794)
			(stroke
				(width 0.1)
				(type default)
			)
			(layer "B.Fab")
		)
		(fp_line
			(start 0.12065 -0.2794)
			(end -0.12065 -0.2794)
			(stroke
				(width 0.1)
				(type default)
			)
			(layer "B.Fab")
		)
		(fp_line
			(start 0.12065 0.2794)
			(end 0.12065 0.3048)
			(stroke
				(width 0.1)
				(type default)
			)
			(layer "B.Fab")
		)
		(fp_line
			(start 0.12065 0.3048)
			(end 0.67945 0.3048)
			(stroke
				(width 0.1)
				(type default)
			)
			(layer "B.Fab")
		)
		(fp_line
			(start 0.67945 -0.305054)
			(end 0.12065 -0.305054)
			(stroke
				(width 0.1)
				(type default)
			)
			(layer "B.Fab")
		)
		(fp_line
			(start 0.67945 0.3048)
			(end 0.67945 -0.305054)
			(stroke
				(width 0.1)
				(type default)
			)
			(layer "B.Fab")
		)
		(pad "1" smd rect
			(at 0.40005 0)
			(size 0.4572 0.508)
			(layers "B.Cu" "B.Mask" "B.Paste")
			(net "P52V_HS1_GATE2_R1")
		)
		(pad "2" smd rect
			(at -0.40005 0)
			(size 0.4572 0.508)
			(layers "B.Cu" "B.Mask" "B.Paste")
			(net "P52V_HS1_4287_GATE2_R")
		)
	)
	(footprint ""
		(layer "B.Cu")
		(at 238.252 -91.313 -90)
		(property "Reference" "R4"
			(at 0 0 90)
			(layer "B.SilkS")
			(hide yes)
			(effects
				(font
					(size 1.27 1.27)
				)
				(justify mirror)
			)
		)
		(property "Value" ""
			(at 0 0 90)
			(layer "B.Fab")
			(effects
				(font
					(size 1.27 1.27)
				)
				(justify mirror)
			)
		)
		(duplicate_pad_numbers_are_jumpers no)
		(fp_line
			(start -0.7874 0.4064)
			(end 0.7874 0.4064)
			(stroke
				(width 0.1524)
				(type default)
			)
			(layer "B.SilkS")
		)
		(fp_line
			(start 0.7874 0.4064)
			(end 0.7874 -0.4064)
			(stroke
				(width 0.1524)
				(type default)
			)
			(layer "B.SilkS")
		)
		(fp_line
			(start -0.7874 -0.4064)
			(end -0.7874 0.4064)
			(stroke
				(width 0.1524)
				(type default)
			)
			(layer "B.SilkS")
		)
		(fp_line
			(start 0.7874 -0.4064)
			(end -0.7874 -0.4064)
			(stroke
				(width 0.1524)
				(type default)
			)
			(layer "B.SilkS")
		)
		(fp_line
			(start -0.67945 0.3048)
			(end -0.120396 0.3048)
			(stroke
				(width 0.1)
				(type default)
			)
			(layer "B.Fab")
		)
		(fp_line
			(start -0.120396 0.3048)
			(end -0.120396 0.2794)
			(stroke
				(width 0.1)
				(type default)
			)
			(layer "B.Fab")
		)
		(fp_line
			(start 0.12065 0.3048)
			(end 0.67945 0.3048)
			(stroke
				(width 0.1)
				(type default)
			)
			(layer "B.Fab")
		)
		(fp_line
			(start 0.67945 0.3048)
			(end 0.67945 -0.305054)
			(stroke
				(width 0.1)
				(type default)
			)
			(layer "B.Fab")
		)
		(fp_line
			(start -0.120396 0.2794)
			(end 0.12065 0.2794)
			(stroke
				(width 0.1)
				(type default)
			)
			(layer "B.Fab")
		)
		(fp_line
			(start 0.12065 0.2794)
			(end 0.12065 0.3048)
			(stroke
				(width 0.1)
				(type default)
			)
			(layer "B.Fab")
		)
		(fp_line
			(start -0.12065 -0.2794)
			(end -0.12065 -0.3048)
			(stroke
				(width 0.1)
				(type default)
			)
			(layer "B.Fab")
		)
		(fp_line
			(start 0.12065 -0.2794)
			(end -0.12065 -0.2794)
			(stroke
				(width 0.1)
				(type default)
			)
			(layer "B.Fab")
		)
		(fp_line
			(start -0.67945 -0.3048)
			(end -0.67945 0.3048)
			(stroke
				(width 0.1)
				(type default)
			)
			(layer "B.Fab")
		)
		(fp_line
			(start -0.12065 -0.3048)
			(end -0.67945 -0.3048)
			(stroke
				(width 0.1)
				(type default)
			)
			(layer "B.Fab")
		)
		(fp_line
			(start 0.12065 -0.305054)
			(end 0.12065 -0.2794)
			(stroke
				(width 0.1)
				(type default)
			)
			(layer "B.Fab")
		)
		(fp_line
			(start 0.67945 -0.305054)
			(end 0.12065 -0.305054)
			(stroke
				(width 0.1)
				(type default)
			)
			(layer "B.Fab")
		)
		(pad "1" smd circle
			(at 0.40005 0 90)
			(size 0 0)
			(layers "B.Cu" "B.Mask" "B.Paste")
			(net "SMB_PDB_MISC_SCL_R")
		)
		(pad "2" smd circle
			(at -0.40005 0 90)
			(size 0 0)
			(layers "B.Cu" "B.Mask" "B.Paste")
			(net "SMB_PDB_MISC_SCL")
		)
	)
	(footprint ""
		(layer "B.Cu")
		(at 60.850018 -76.708 -90)
		(property "Reference" "PR325"
			(at 0 0 90)
			(layer "B.SilkS")
			(hide yes)
			(effects
				(font
					(size 1.27 1.27)
				)
				(justify mirror)
			)
		)
		(property "Value" ""
			(at 0 0 90)
			(layer "B.Fab")
			(effects
				(font
					(size 1.27 1.27)
				)
				(justify mirror)
			)
		)
		(duplicate_pad_numbers_are_jumpers no)
		(fp_line
			(start -0.7874 0.4064)
			(end 0.7874 0.4064)
			(stroke
				(width 0.1524)
				(type default)
			)
			(layer "B.SilkS")
		)
		(fp_line
			(start 0.7874 0.4064)
			(end 0.7874 -0.4064)
			(stroke
				(width 0.1524)
				(type default)
			)
			(layer "B.SilkS")
		)
		(fp_line
			(start -0.7874 -0.4064)
			(end -0.7874 0.4064)
			(stroke
				(width 0.1524)
				(type default)
			)
			(layer "B.SilkS")
		)
		(fp_line
			(start 0.7874 -0.4064)
			(end -0.7874 -0.4064)
			(stroke
				(width 0.1524)
				(type default)
			)
			(layer "B.SilkS")
		)
		(fp_line
			(start -0.67945 0.3048)
			(end -0.120396 0.3048)
			(stroke
				(width 0.1)
				(type default)
			)
			(layer "B.Fab")
		)
		(fp_line
			(start -0.120396 0.3048)
			(end -0.120396 0.2794)
			(stroke
				(width 0.1)
				(type default)
			)
			(layer "B.Fab")
		)
		(fp_line
			(start 0.12065 0.3048)
			(end 0.67945 0.3048)
			(stroke
				(width 0.1)
				(type default)
			)
			(layer "B.Fab")
		)
		(fp_line
			(start 0.67945 0.3048)
			(end 0.67945 -0.305054)
			(stroke
				(width 0.1)
				(type default)
			)
			(layer "B.Fab")
		)
		(fp_line
			(start -0.120396 0.2794)
			(end 0.12065 0.2794)
			(stroke
				(width 0.1)
				(type default)
			)
			(layer "B.Fab")
		)
		(fp_line
			(start 0.12065 0.2794)
			(end 0.12065 0.3048)
			(stroke
				(width 0.1)
				(type default)
			)
			(layer "B.Fab")
		)
		(fp_line
			(start -0.12065 -0.2794)
			(end -0.12065 -0.3048)
			(stroke
				(width 0.1)
				(type default)
			)
			(layer "B.Fab")
		)
		(fp_line
			(start 0.12065 -0.2794)
			(end -0.12065 -0.2794)
			(stroke
				(width 0.1)
				(type default)
			)
			(layer "B.Fab")
		)
		(fp_line
			(start -0.67945 -0.3048)
			(end -0.67945 0.3048)
			(stroke
				(width 0.1)
				(type default)
			)
			(layer "B.Fab")
		)
		(fp_line
			(start -0.12065 -0.3048)
			(end -0.67945 -0.3048)
			(stroke
				(width 0.1)
				(type default)
			)
			(layer "B.Fab")
		)
		(fp_line
			(start 0.12065 -0.305054)
			(end 0.12065 -0.2794)
			(stroke
				(width 0.1)
				(type default)
			)
			(layer "B.Fab")
		)
		(fp_line
			(start 0.67945 -0.305054)
			(end 0.12065 -0.305054)
			(stroke
				(width 0.1)
				(type default)
			)
			(layer "B.Fab")
		)
		(pad "1" smd circle
			(at 0.40005 0 90)
			(size 0 0)
			(layers "B.Cu" "B.Mask" "B.Paste")
			(net "BRICK3_PMBADD")
		)
		(pad "2" smd circle
			(at -0.40005 0 90)
			(size 0 0)
			(layers "B.Cu" "B.Mask" "B.Paste")
			(net "GND")
		)
	)
	(footprint ""
		(layer "B.Cu")
		(at 266.192 -32.766 180)
		(property "Reference" "PR27"
			(at 0 0 0)
			(layer "B.SilkS")
			(hide yes)
			(effects
				(font
					(size 1.27 1.27)
				)
				(justify mirror)
			)
		)
		(property "Value" ""
			(at 0 0 0)
			(layer "B.Fab")
			(effects
				(font
					(size 1.27 1.27)
				)
				(justify mirror)
			)
		)
		(duplicate_pad_numbers_are_jumpers no)
		(fp_line
			(start 0.7874 0.4064)
			(end 0.7874 -0.4064)
			(stroke
				(width 0.1524)
				(type default)
			)
			(layer "B.SilkS")
		)
		(fp_line
			(start 0.7874 -0.4064)
			(end -0.7874 -0.4064)
			(stroke
				(width 0.1524)
				(type default)
			)
			(layer "B.SilkS")
		)
		(fp_line
			(start -0.7874 0.4064)
			(end 0.7874 0.4064)
			(stroke
				(width 0.1524)
				(type default)
			)
			(layer "B.SilkS")
		)
		(fp_line
			(start -0.7874 -0.4064)
			(end -0.7874 0.4064)
			(stroke
				(width 0.1524)
				(type default)
			)
			(layer "B.SilkS")
		)
		(fp_line
			(start 0.67945 0.3048)
			(end 0.67945 -0.305054)
			(stroke
				(width 0.1)
				(type default)
			)
			(layer "B.Fab")
		)
		(fp_line
			(start 0.67945 -0.305054)
			(end 0.12065 -0.305054)
			(stroke
				(width 0.1)
				(type default)
			)
			(layer "B.Fab")
		)
		(fp_line
			(start 0.12065 0.3048)
			(end 0.67945 0.3048)
			(stroke
				(width 0.1)
				(type default)
			)
			(layer "B.Fab")
		)
		(fp_line
			(start 0.12065 0.2794)
			(end 0.12065 0.3048)
			(stroke
				(width 0.1)
				(type default)
			)
			(layer "B.Fab")
		)
		(fp_line
			(start 0.12065 -0.2794)
			(end -0.12065 -0.2794)
			(stroke
				(width 0.1)
				(type default)
			)
			(layer "B.Fab")
		)
		(fp_line
			(start 0.12065 -0.305054)
			(end 0.12065 -0.2794)
			(stroke
				(width 0.1)
				(type default)
			)
			(layer "B.Fab")
		)
		(fp_line
			(start -0.120396 0.3048)
			(end -0.120396 0.2794)
			(stroke
				(width 0.1)
				(type default)
			)
			(layer "B.Fab")
		)
		(fp_line
			(start -0.120396 0.2794)
			(end 0.12065 0.2794)
			(stroke
				(width 0.1)
				(type default)
			)
			(layer "B.Fab")
		)
		(fp_line
			(start -0.12065 -0.2794)
			(end -0.12065 -0.3048)
			(stroke
				(width 0.1)
				(type default)
			)
			(layer "B.Fab")
		)
		(fp_line
			(start -0.12065 -0.3048)
			(end -0.67945 -0.3048)
			(stroke
				(width 0.1)
				(type default)
			)
			(layer "B.Fab")
		)
		(fp_line
			(start -0.67945 0.3048)
			(end -0.120396 0.3048)
			(stroke
				(width 0.1)
				(type default)
			)
			(layer "B.Fab")
		)
		(fp_line
			(start -0.67945 -0.3048)
			(end -0.67945 0.3048)
			(stroke
				(width 0.1)
				(type default)
			)
			(layer "B.Fab")
		)
		(pad "1" smd circle
			(at 0.40005 0)
			(size 0 0)
			(layers "B.Cu" "B.Mask" "B.Paste")
			(net "P52V_HS1_INTVCC")
		)
		(pad "2" smd circle
			(at -0.40005 0)
			(size 0 0)
			(layers "B.Cu" "B.Mask" "B.Paste")
			(net "P52V_HS1_SCK")
		)
	)
	(footprint ""
		(layer "B.Cu")
		(at 216.154 -67.183 90)
		(property "Reference" "R137"
			(at 0 0 90)
			(layer "B.SilkS")
			(hide yes)
			(effects
				(font
					(size 1.27 1.27)
				)
				(justify mirror)
			)
		)
		(property "Value" ""
			(at 0 0 90)
			(layer "B.Fab")
			(effects
				(font
					(size 1.27 1.27)
				)
				(justify mirror)
			)
		)
		(duplicate_pad_numbers_are_jumpers no)
		(fp_line
			(start 0.7874 -0.4064)
			(end -0.7874 -0.4064)
			(stroke
				(width 0.1524)
				(type default)
			)
			(layer "B.SilkS")
		)
		(fp_line
			(start -0.7874 -0.4064)
			(end -0.7874 0.4064)
			(stroke
				(width 0.1524)
				(type default)
			)
			(layer "B.SilkS")
		)
		(fp_line
			(start 0.7874 0.4064)
			(end 0.7874 -0.4064)
			(stroke
				(width 0.1524)
				(type default)
			)
			(layer "B.SilkS")
		)
		(fp_line
			(start -0.7874 0.4064)
			(end 0.7874 0.4064)
			(stroke
				(width 0.1524)
				(type default)
			)
			(layer "B.SilkS")
		)
		(fp_line
			(start 0.67945 -0.305054)
			(end 0.12065 -0.305054)
			(stroke
				(width 0.1)
				(type default)
			)
			(layer "B.Fab")
		)
		(fp_line
			(start 0.12065 -0.305054)
			(end 0.12065 -0.2794)
			(stroke
				(width 0.1)
				(type default)
			)
			(layer "B.Fab")
		)
		(fp_line
			(start -0.12065 -0.3048)
			(end -0.67945 -0.3048)
			(stroke
				(width 0.1)
				(type default)
			)
			(layer "B.Fab")
		)
		(fp_line
			(start -0.67945 -0.3048)
			(end -0.67945 0.3048)
			(stroke
				(width 0.1)
				(type default)
			)
			(layer "B.Fab")
		)
		(fp_line
			(start 0.12065 -0.2794)
			(end -0.12065 -0.2794)
			(stroke
				(width 0.1)
				(type default)
			)
			(layer "B.Fab")
		)
		(fp_line
			(start -0.12065 -0.2794)
			(end -0.12065 -0.3048)
			(stroke
				(width 0.1)
				(type default)
			)
			(layer "B.Fab")
		)
		(fp_line
			(start 0.12065 0.2794)
			(end 0.12065 0.3048)
			(stroke
				(width 0.1)
				(type default)
			)
			(layer "B.Fab")
		)
		(fp_line
			(start -0.120396 0.2794)
			(end 0.12065 0.2794)
			(stroke
				(width 0.1)
				(type default)
			)
			(layer "B.Fab")
		)
		(fp_line
			(start 0.67945 0.3048)
			(end 0.67945 -0.305054)
			(stroke
				(width 0.1)
				(type default)
			)
			(layer "B.Fab")
		)
		(fp_line
			(start 0.12065 0.3048)
			(end 0.67945 0.3048)
			(stroke
				(width 0.1)
				(type default)
			)
			(layer "B.Fab")
		)
		(fp_line
			(start -0.120396 0.3048)
			(end -0.120396 0.2794)
			(stroke
				(width 0.1)
				(type default)
			)
			(layer "B.Fab")
		)
		(fp_line
			(start -0.67945 0.3048)
			(end -0.120396 0.3048)
			(stroke
				(width 0.1)
				(type default)
			)
			(layer "B.Fab")
		)
		(pad "1" smd circle
			(at 0.40005 0 270)
			(size 0 0)
			(layers "B.Cu" "B.Mask" "B.Paste")
			(net "BOARD_ID_1")
		)
		(pad "2" smd circle
			(at -0.40005 0 270)
			(size 0 0)
			(layers "B.Cu" "B.Mask" "B.Paste")
			(net "GND")
		)
	)
	(footprint ""
		(layer "B.Cu")
		(at 98.806 -76.327 180)
		(property "Reference" "R171"
			(at 0 0 0)
			(layer "B.SilkS")
			(hide yes)
			(effects
				(font
					(size 1.27 1.27)
				)
				(justify mirror)
			)
		)
		(property "Value" ""
			(at 0 0 0)
			(layer "B.Fab")
			(effects
				(font
					(size 1.27 1.27)
				)
				(justify mirror)
			)
		)
		(duplicate_pad_numbers_are_jumpers no)
		(fp_line
			(start 0.7874 0.4064)
			(end 0.7874 -0.4064)
			(stroke
				(width 0.1524)
				(type default)
			)
			(layer "B.SilkS")
		)
		(fp_line
			(start 0.7874 -0.4064)
			(end -0.7874 -0.4064)
			(stroke
				(width 0.1524)
				(type default)
			)
			(layer "B.SilkS")
		)
		(fp_line
			(start -0.7874 0.4064)
			(end 0.7874 0.4064)
			(stroke
				(width 0.1524)
				(type default)
			)
			(layer "B.SilkS")
		)
		(fp_line
			(start -0.7874 -0.4064)
			(end -0.7874 0.4064)
			(stroke
				(width 0.1524)
				(type default)
			)
			(layer "B.SilkS")
		)
		(fp_line
			(start 0.67945 0.3048)
			(end 0.67945 -0.305054)
			(stroke
				(width 0.1)
				(type default)
			)
			(layer "B.Fab")
		)
		(fp_line
			(start 0.67945 -0.305054)
			(end 0.12065 -0.305054)
			(stroke
				(width 0.1)
				(type default)
			)
			(layer "B.Fab")
		)
		(fp_line
			(start 0.12065 0.3048)
			(end 0.67945 0.3048)
			(stroke
				(width 0.1)
				(type default)
			)
			(layer "B.Fab")
		)
		(fp_line
			(start 0.12065 0.2794)
			(end 0.12065 0.3048)
			(stroke
				(width 0.1)
				(type default)
			)
			(layer "B.Fab")
		)
		(fp_line
			(start 0.12065 -0.2794)
			(end -0.12065 -0.2794)
			(stroke
				(width 0.1)
				(type default)
			)
			(layer "B.Fab")
		)
		(fp_line
			(start 0.12065 -0.305054)
			(end 0.12065 -0.2794)
			(stroke
				(width 0.1)
				(type default)
			)
			(layer "B.Fab")
		)
		(fp_line
			(start -0.120396 0.3048)
			(end -0.120396 0.2794)
			(stroke
				(width 0.1)
				(type default)
			)
			(layer "B.Fab")
		)
		(fp_line
			(start -0.120396 0.2794)
			(end 0.12065 0.2794)
			(stroke
				(width 0.1)
				(type default)
			)
			(layer "B.Fab")
		)
		(fp_line
			(start -0.12065 -0.2794)
			(end -0.12065 -0.3048)
			(stroke
				(width 0.1)
				(type default)
			)
			(layer "B.Fab")
		)
		(fp_line
			(start -0.12065 -0.3048)
			(end -0.67945 -0.3048)
			(stroke
				(width 0.1)
				(type default)
			)
			(layer "B.Fab")
		)
		(fp_line
			(start -0.67945 0.3048)
			(end -0.120396 0.3048)
			(stroke
				(width 0.1)
				(type default)
			)
			(layer "B.Fab")
		)
		(fp_line
			(start -0.67945 -0.3048)
			(end -0.67945 0.3048)
			(stroke
				(width 0.1)
				(type default)
			)
			(layer "B.Fab")
		)
		(pad "1" smd circle
			(at 0.40005 0)
			(size 0 0)
			(layers "B.Cu" "B.Mask" "B.Paste")
			(net "SMB_P52V_VPDB_SDA")
		)
		(pad "2" smd circle
			(at -0.40005 0)
			(size 0 0)
			(layers "B.Cu" "B.Mask" "B.Paste")
			(net "SMB_BRICK1_SDA")
		)
	)
	(footprint ""
		(layer "B.Cu")
		(at 212.344 -82.169)
		(property "Reference" "R188"
			(at 0 0 0)
			(layer "B.SilkS")
			(hide yes)
			(effects
				(font
					(size 1.27 1.27)
				)
				(justify mirror)
			)
		)
		(property "Value" ""
			(at 0 0 0)
			(layer "B.Fab")
			(effects
				(font
					(size 1.27 1.27)
				)
				(justify mirror)
			)
		)
		(duplicate_pad_numbers_are_jumpers no)
		(fp_line
			(start -0.7874 -0.4064)
			(end -0.7874 0.4064)
			(stroke
				(width 0.1524)
				(type default)
			)
			(layer "B.SilkS")
		)
		(fp_line
			(start -0.7874 0.4064)
			(end 0.7874 0.4064)
			(stroke
				(width 0.1524)
				(type default)
			)
			(layer "B.SilkS")
		)
		(fp_line
			(start 0.7874 -0.4064)
			(end -0.7874 -0.4064)
			(stroke
				(width 0.1524)
				(type default)
			)
			(layer "B.SilkS")
		)
		(fp_line
			(start 0.7874 0.4064)
			(end 0.7874 -0.4064)
			(stroke
				(width 0.1524)
				(type default)
			)
			(layer "B.SilkS")
		)
		(fp_line
			(start -0.67945 -0.3048)
			(end -0.67945 0.3048)
			(stroke
				(width 0.1)
				(type default)
			)
			(layer "B.Fab")
		)
		(fp_line
			(start -0.67945 0.3048)
			(end -0.120396 0.3048)
			(stroke
				(width 0.1)
				(type default)
			)
			(layer "B.Fab")
		)
		(fp_line
			(start -0.12065 -0.3048)
			(end -0.67945 -0.3048)
			(stroke
				(width 0.1)
				(type default)
			)
			(layer "B.Fab")
		)
		(fp_line
			(start -0.12065 -0.2794)
			(end -0.12065 -0.3048)
			(stroke
				(width 0.1)
				(type default)
			)
			(layer "B.Fab")
		)
		(fp_line
			(start -0.120396 0.2794)
			(end 0.12065 0.2794)
			(stroke
				(width 0.1)
				(type default)
			)
			(layer "B.Fab")
		)
		(fp_line
			(start -0.120396 0.3048)
			(end -0.120396 0.2794)
			(stroke
				(width 0.1)
				(type default)
			)
			(layer "B.Fab")
		)
		(fp_line
			(start 0.12065 -0.305054)
			(end 0.12065 -0.2794)
			(stroke
				(width 0.1)
				(type default)
			)
			(layer "B.Fab")
		)
		(fp_line
			(start 0.12065 -0.2794)
			(end -0.12065 -0.2794)
			(stroke
				(width 0.1)
				(type default)
			)
			(layer "B.Fab")
		)
		(fp_line
			(start 0.12065 0.2794)
			(end 0.12065 0.3048)
			(stroke
				(width 0.1)
				(type default)
			)
			(layer "B.Fab")
		)
		(fp_line
			(start 0.12065 0.3048)
			(end 0.67945 0.3048)
			(stroke
				(width 0.1)
				(type default)
			)
			(layer "B.Fab")
		)
		(fp_line
			(start 0.67945 -0.305054)
			(end 0.12065 -0.305054)
			(stroke
				(width 0.1)
				(type default)
			)
			(layer "B.Fab")
		)
		(fp_line
			(start 0.67945 0.3048)
			(end 0.67945 -0.305054)
			(stroke
				(width 0.1)
				(type default)
			)
			(layer "B.Fab")
		)
		(pad "1" smd circle
			(at 0.40005 0 180)
			(size 0 0)
			(layers "B.Cu" "B.Mask" "B.Paste")
			(net "GND")
		)
		(pad "2" smd circle
			(at -0.40005 0 180)
			(size 0 0)
			(layers "B.Cu" "B.Mask" "B.Paste")
			(net "PWRGD_GPU_HSC")
		)
	)
	(footprint ""
		(layer "B.Cu")
		(at 109.732826 -115.824 -90)
		(property "Reference" "C74"
			(at 0 0 90)
			(layer "B.SilkS")
			(hide yes)
			(effects
				(font
					(size 1.27 1.27)
				)
				(justify mirror)
			)
		)
		(property "Value" ""
			(at 0 0 90)
			(layer "B.Fab")
			(effects
				(font
					(size 1.27 1.27)
				)
				(justify mirror)
			)
		)
		(duplicate_pad_numbers_are_jumpers no)
		(fp_line
			(start -0.7874 0.4064)
			(end 0.7874 0.4064)
			(stroke
				(width 0.1524)
				(type default)
			)
			(layer "B.SilkS")
		)
		(fp_line
			(start 0.7874 0.4064)
			(end 0.7874 -0.4064)
			(stroke
				(width 0.1524)
				(type default)
			)
			(layer "B.SilkS")
		)
		(fp_line
			(start -0.7874 -0.4064)
			(end -0.7874 0.4064)
			(stroke
				(width 0.1524)
				(type default)
			)
			(layer "B.SilkS")
		)
		(fp_line
			(start 0.7874 -0.4064)
			(end -0.7874 -0.4064)
			(stroke
				(width 0.1524)
				(type default)
			)
			(layer "B.SilkS")
		)
		(fp_line
			(start -0.67945 0.3048)
			(end -0.120396 0.3048)
			(stroke
				(width 0.1)
				(type default)
			)
			(layer "B.Fab")
		)
		(fp_line
			(start -0.120396 0.3048)
			(end -0.120396 0.2794)
			(stroke
				(width 0.1)
				(type default)
			)
			(layer "B.Fab")
		)
		(fp_line
			(start 0.12065 0.3048)
			(end 0.67945 0.3048)
			(stroke
				(width 0.1)
				(type default)
			)
			(layer "B.Fab")
		)
		(fp_line
			(start 0.67945 0.3048)
			(end 0.67945 -0.305054)
			(stroke
				(width 0.1)
				(type default)
			)
			(layer "B.Fab")
		)
		(fp_line
			(start -0.120396 0.2794)
			(end 0.12065 0.2794)
			(stroke
				(width 0.1)
				(type default)
			)
			(layer "B.Fab")
		)
		(fp_line
			(start 0.12065 0.2794)
			(end 0.12065 0.3048)
			(stroke
				(width 0.1)
				(type default)
			)
			(layer "B.Fab")
		)
		(fp_line
			(start -0.12065 -0.2794)
			(end -0.12065 -0.3048)
			(stroke
				(width 0.1)
				(type default)
			)
			(layer "B.Fab")
		)
		(fp_line
			(start 0.12065 -0.2794)
			(end -0.12065 -0.2794)
			(stroke
				(width 0.1)
				(type default)
			)
			(layer "B.Fab")
		)
		(fp_line
			(start -0.67945 -0.3048)
			(end -0.67945 0.3048)
			(stroke
				(width 0.1)
				(type default)
			)
			(layer "B.Fab")
		)
		(fp_line
			(start -0.12065 -0.3048)
			(end -0.67945 -0.3048)
			(stroke
				(width 0.1)
				(type default)
			)
			(layer "B.Fab")
		)
		(fp_line
			(start 0.12065 -0.305054)
			(end 0.12065 -0.2794)
			(stroke
				(width 0.1)
				(type default)
			)
			(layer "B.Fab")
		)
		(fp_line
			(start 0.67945 -0.305054)
			(end 0.12065 -0.305054)
			(stroke
				(width 0.1)
				(type default)
			)
			(layer "B.Fab")
		)
		(pad "1" smd circle
			(at 0.40005 0 90)
			(size 0 0)
			(layers "B.Cu" "B.Mask" "B.Paste")
			(net "GND")
		)
		(pad "2" smd circle
			(at -0.40005 0 90)
			(size 0 0)
			(layers "B.Cu" "B.Mask" "B.Paste")
			(net "P12V_BRICK0_PWRGD")
		)
	)
	(footprint ""
		(layer "B.Cu")
		(at 134.493 -78.867)
		(property "Reference" "R163"
			(at 0 0 0)
			(layer "B.SilkS")
			(hide yes)
			(effects
				(font
					(size 1.27 1.27)
				)
				(justify mirror)
			)
		)
		(property "Value" ""
			(at 0 0 0)
			(layer "B.Fab")
			(effects
				(font
					(size 1.27 1.27)
				)
				(justify mirror)
			)
		)
		(duplicate_pad_numbers_are_jumpers no)
		(fp_line
			(start -0.7874 -0.4064)
			(end -0.7874 0.4064)
			(stroke
				(width 0.1524)
				(type default)
			)
			(layer "B.SilkS")
		)
		(fp_line
			(start -0.7874 0.4064)
			(end 0.7874 0.4064)
			(stroke
				(width 0.1524)
				(type default)
			)
			(layer "B.SilkS")
		)
		(fp_line
			(start 0.7874 -0.4064)
			(end -0.7874 -0.4064)
			(stroke
				(width 0.1524)
				(type default)
			)
			(layer "B.SilkS")
		)
		(fp_line
			(start 0.7874 0.4064)
			(end 0.7874 -0.4064)
			(stroke
				(width 0.1524)
				(type default)
			)
			(layer "B.SilkS")
		)
		(fp_line
			(start -0.67945 -0.3048)
			(end -0.67945 0.3048)
			(stroke
				(width 0.1)
				(type default)
			)
			(layer "B.Fab")
		)
		(fp_line
			(start -0.67945 0.3048)
			(end -0.120396 0.3048)
			(stroke
				(width 0.1)
				(type default)
			)
			(layer "B.Fab")
		)
		(fp_line
			(start -0.12065 -0.3048)
			(end -0.67945 -0.3048)
			(stroke
				(width 0.1)
				(type default)
			)
			(layer "B.Fab")
		)
		(fp_line
			(start -0.12065 -0.2794)
			(end -0.12065 -0.3048)
			(stroke
				(width 0.1)
				(type default)
			)
			(layer "B.Fab")
		)
		(fp_line
			(start -0.120396 0.2794)
			(end 0.12065 0.2794)
			(stroke
				(width 0.1)
				(type default)
			)
			(layer "B.Fab")
		)
		(fp_line
			(start -0.120396 0.3048)
			(end -0.120396 0.2794)
			(stroke
				(width 0.1)
				(type default)
			)
			(layer "B.Fab")
		)
		(fp_line
			(start 0.12065 -0.305054)
			(end 0.12065 -0.2794)
			(stroke
				(width 0.1)
				(type default)
			)
			(layer "B.Fab")
		)
		(fp_line
			(start 0.12065 -0.2794)
			(end -0.12065 -0.2794)
			(stroke
				(width 0.1)
				(type default)
			)
			(layer "B.Fab")
		)
		(fp_line
			(start 0.12065 0.2794)
			(end 0.12065 0.3048)
			(stroke
				(width 0.1)
				(type default)
			)
			(layer "B.Fab")
		)
		(fp_line
			(start 0.12065 0.3048)
			(end 0.67945 0.3048)
			(stroke
				(width 0.1)
				(type default)
			)
			(layer "B.Fab")
		)
		(fp_line
			(start 0.67945 -0.305054)
			(end 0.12065 -0.305054)
			(stroke
				(width 0.1)
				(type default)
			)
			(layer "B.Fab")
		)
		(fp_line
			(start 0.67945 0.3048)
			(end 0.67945 -0.305054)
			(stroke
				(width 0.1)
				(type default)
			)
			(layer "B.Fab")
		)
		(pad "1" smd circle
			(at 0.40005 0 180)
			(size 0 0)
			(layers "B.Cu" "B.Mask" "B.Paste")
			(net "P3V3_AUX")
		)
		(pad "2" smd circle
			(at -0.40005 0 180)
			(size 0 0)
			(layers "B.Cu" "B.Mask" "B.Paste")
			(net "SMB_P52V_VPDB_SDA")
		)
	)
	(footprint ""
		(layer "B.Cu")
		(at 136.85012 -116.078 -90)
		(property "Reference" "R160"
			(at 0 0 90)
			(layer "B.SilkS")
			(hide yes)
			(effects
				(font
					(size 1.27 1.27)
				)
				(justify mirror)
			)
		)
		(property "Value" ""
			(at 0 0 90)
			(layer "B.Fab")
			(effects
				(font
					(size 1.27 1.27)
				)
				(justify mirror)
			)
		)
		(duplicate_pad_numbers_are_jumpers no)
		(fp_line
			(start -0.7874 0.4064)
			(end 0.7874 0.4064)
			(stroke
				(width 0.1524)
				(type default)
			)
			(layer "B.SilkS")
		)
		(fp_line
			(start 0.7874 0.4064)
			(end 0.7874 -0.4064)
			(stroke
				(width 0.1524)
				(type default)
			)
			(layer "B.SilkS")
		)
		(fp_line
			(start -0.7874 -0.4064)
			(end -0.7874 0.4064)
			(stroke
				(width 0.1524)
				(type default)
			)
			(layer "B.SilkS")
		)
		(fp_line
			(start 0.7874 -0.4064)
			(end -0.7874 -0.4064)
			(stroke
				(width 0.1524)
				(type default)
			)
			(layer "B.SilkS")
		)
		(fp_line
			(start -0.67945 0.3048)
			(end -0.120396 0.3048)
			(stroke
				(width 0.1)
				(type default)
			)
			(layer "B.Fab")
		)
		(fp_line
			(start -0.120396 0.3048)
			(end -0.120396 0.2794)
			(stroke
				(width 0.1)
				(type default)
			)
			(layer "B.Fab")
		)
		(fp_line
			(start 0.12065 0.3048)
			(end 0.67945 0.3048)
			(stroke
				(width 0.1)
				(type default)
			)
			(layer "B.Fab")
		)
		(fp_line
			(start 0.67945 0.3048)
			(end 0.67945 -0.305054)
			(stroke
				(width 0.1)
				(type default)
			)
			(layer "B.Fab")
		)
		(fp_line
			(start -0.120396 0.2794)
			(end 0.12065 0.2794)
			(stroke
				(width 0.1)
				(type default)
			)
			(layer "B.Fab")
		)
		(fp_line
			(start 0.12065 0.2794)
			(end 0.12065 0.3048)
			(stroke
				(width 0.1)
				(type default)
			)
			(layer "B.Fab")
		)
		(fp_line
			(start -0.12065 -0.2794)
			(end -0.12065 -0.3048)
			(stroke
				(width 0.1)
				(type default)
			)
			(layer "B.Fab")
		)
		(fp_line
			(start 0.12065 -0.2794)
			(end -0.12065 -0.2794)
			(stroke
				(width 0.1)
				(type default)
			)
			(layer "B.Fab")
		)
		(fp_line
			(start -0.67945 -0.3048)
			(end -0.67945 0.3048)
			(stroke
				(width 0.1)
				(type default)
			)
			(layer "B.Fab")
		)
		(fp_line
			(start -0.12065 -0.3048)
			(end -0.67945 -0.3048)
			(stroke
				(width 0.1)
				(type default)
			)
			(layer "B.Fab")
		)
		(fp_line
			(start 0.12065 -0.305054)
			(end 0.12065 -0.2794)
			(stroke
				(width 0.1)
				(type default)
			)
			(layer "B.Fab")
		)
		(fp_line
			(start 0.67945 -0.305054)
			(end 0.12065 -0.305054)
			(stroke
				(width 0.1)
				(type default)
			)
			(layer "B.Fab")
		)
		(pad "1" smd circle
			(at 0.40005 0 90)
			(size 0 0)
			(layers "B.Cu" "B.Mask" "B.Paste")
			(net "BRICK_P12V0_EN_N")
		)
		(pad "2" smd circle
			(at -0.40005 0 90)
			(size 0 0)
			(layers "B.Cu" "B.Mask" "B.Paste")
			(net "BRICK_P12V0_ON_OFF_R")
		)
	)
	(footprint ""
		(layer "B.Cu")
		(at 237.031784 -79.72679 90)
		(property "Reference" "C1"
			(at 0 0 90)
			(layer "B.SilkS")
			(hide yes)
			(effects
				(font
					(size 1.27 1.27)
				)
				(justify mirror)
			)
		)
		(property "Value" ""
			(at 0 0 90)
			(layer "B.Fab")
			(effects
				(font
					(size 1.27 1.27)
				)
				(justify mirror)
			)
		)
		(duplicate_pad_numbers_are_jumpers no)
		(fp_line
			(start 0.7874 -0.4064)
			(end -0.7874 -0.4064)
			(stroke
				(width 0.1524)
				(type default)
			)
			(layer "B.SilkS")
		)
		(fp_line
			(start -0.7874 -0.4064)
			(end -0.7874 0.4064)
			(stroke
				(width 0.1524)
				(type default)
			)
			(layer "B.SilkS")
		)
		(fp_line
			(start 0.7874 0.4064)
			(end 0.7874 -0.4064)
			(stroke
				(width 0.1524)
				(type default)
			)
			(layer "B.SilkS")
		)
		(fp_line
			(start -0.7874 0.4064)
			(end 0.7874 0.4064)
			(stroke
				(width 0.1524)
				(type default)
			)
			(layer "B.SilkS")
		)
		(fp_line
			(start 0.67945 -0.305054)
			(end 0.12065 -0.305054)
			(stroke
				(width 0.1)
				(type default)
			)
			(layer "B.Fab")
		)
		(fp_line
			(start 0.12065 -0.305054)
			(end 0.12065 -0.2794)
			(stroke
				(width 0.1)
				(type default)
			)
			(layer "B.Fab")
		)
		(fp_line
			(start -0.12065 -0.3048)
			(end -0.67945 -0.3048)
			(stroke
				(width 0.1)
				(type default)
			)
			(layer "B.Fab")
		)
		(fp_line
			(start -0.67945 -0.3048)
			(end -0.67945 0.3048)
			(stroke
				(width 0.1)
				(type default)
			)
			(layer "B.Fab")
		)
		(fp_line
			(start 0.12065 -0.2794)
			(end -0.12065 -0.2794)
			(stroke
				(width 0.1)
				(type default)
			)
			(layer "B.Fab")
		)
		(fp_line
			(start -0.12065 -0.2794)
			(end -0.12065 -0.3048)
			(stroke
				(width 0.1)
				(type default)
			)
			(layer "B.Fab")
		)
		(fp_line
			(start 0.12065 0.2794)
			(end 0.12065 0.3048)
			(stroke
				(width 0.1)
				(type default)
			)
			(layer "B.Fab")
		)
		(fp_line
			(start -0.120396 0.2794)
			(end 0.12065 0.2794)
			(stroke
				(width 0.1)
				(type default)
			)
			(layer "B.Fab")
		)
		(fp_line
			(start 0.67945 0.3048)
			(end 0.67945 -0.305054)
			(stroke
				(width 0.1)
				(type default)
			)
			(layer "B.Fab")
		)
		(fp_line
			(start 0.12065 0.3048)
			(end 0.67945 0.3048)
			(stroke
				(width 0.1)
				(type default)
			)
			(layer "B.Fab")
		)
		(fp_line
			(start -0.120396 0.3048)
			(end -0.120396 0.2794)
			(stroke
				(width 0.1)
				(type default)
			)
			(layer "B.Fab")
		)
		(fp_line
			(start -0.67945 0.3048)
			(end -0.120396 0.3048)
			(stroke
				(width 0.1)
				(type default)
			)
			(layer "B.Fab")
		)
		(pad "1" smd circle
			(at 0.40005 0 270)
			(size 0 0)
			(layers "B.Cu" "B.Mask" "B.Paste")
			(net "P3V3_AUX")
		)
		(pad "2" smd circle
			(at -0.40005 0 270)
			(size 0 0)
			(layers "B.Cu" "B.Mask" "B.Paste")
			(net "GND")
		)
	)
	(footprint ""
		(layer "B.Cu")
		(at 52.850034 -76.708 -90)
		(property "Reference" "PR79"
			(at 0 0 90)
			(layer "B.SilkS")
			(hide yes)
			(effects
				(font
					(size 1.27 1.27)
				)
				(justify mirror)
			)
		)
		(property "Value" ""
			(at 0 0 90)
			(layer "B.Fab")
			(effects
				(font
					(size 1.27 1.27)
				)
				(justify mirror)
			)
		)
		(duplicate_pad_numbers_are_jumpers no)
		(fp_line
			(start -0.7874 0.4064)
			(end 0.7874 0.4064)
			(stroke
				(width 0.1524)
				(type default)
			)
			(layer "B.SilkS")
		)
		(fp_line
			(start 0.7874 0.4064)
			(end 0.7874 -0.4064)
			(stroke
				(width 0.1524)
				(type default)
			)
			(layer "B.SilkS")
		)
		(fp_line
			(start -0.7874 -0.4064)
			(end -0.7874 0.4064)
			(stroke
				(width 0.1524)
				(type default)
			)
			(layer "B.SilkS")
		)
		(fp_line
			(start 0.7874 -0.4064)
			(end -0.7874 -0.4064)
			(stroke
				(width 0.1524)
				(type default)
			)
			(layer "B.SilkS")
		)
		(fp_line
			(start -0.67945 0.3048)
			(end -0.120396 0.3048)
			(stroke
				(width 0.1)
				(type default)
			)
			(layer "B.Fab")
		)
		(fp_line
			(start -0.120396 0.3048)
			(end -0.120396 0.2794)
			(stroke
				(width 0.1)
				(type default)
			)
			(layer "B.Fab")
		)
		(fp_line
			(start 0.12065 0.3048)
			(end 0.67945 0.3048)
			(stroke
				(width 0.1)
				(type default)
			)
			(layer "B.Fab")
		)
		(fp_line
			(start 0.67945 0.3048)
			(end 0.67945 -0.305054)
			(stroke
				(width 0.1)
				(type default)
			)
			(layer "B.Fab")
		)
		(fp_line
			(start -0.120396 0.2794)
			(end 0.12065 0.2794)
			(stroke
				(width 0.1)
				(type default)
			)
			(layer "B.Fab")
		)
		(fp_line
			(start 0.12065 0.2794)
			(end 0.12065 0.3048)
			(stroke
				(width 0.1)
				(type default)
			)
			(layer "B.Fab")
		)
		(fp_line
			(start -0.12065 -0.2794)
			(end -0.12065 -0.3048)
			(stroke
				(width 0.1)
				(type default)
			)
			(layer "B.Fab")
		)
		(fp_line
			(start 0.12065 -0.2794)
			(end -0.12065 -0.2794)
			(stroke
				(width 0.1)
				(type default)
			)
			(layer "B.Fab")
		)
		(fp_line
			(start -0.67945 -0.3048)
			(end -0.67945 0.3048)
			(stroke
				(width 0.1)
				(type default)
			)
			(layer "B.Fab")
		)
		(fp_line
			(start -0.12065 -0.3048)
			(end -0.67945 -0.3048)
			(stroke
				(width 0.1)
				(type default)
			)
			(layer "B.Fab")
		)
		(fp_line
			(start 0.12065 -0.305054)
			(end 0.12065 -0.2794)
			(stroke
				(width 0.1)
				(type default)
			)
			(layer "B.Fab")
		)
		(fp_line
			(start 0.67945 -0.305054)
			(end 0.12065 -0.305054)
			(stroke
				(width 0.1)
				(type default)
			)
			(layer "B.Fab")
		)
		(pad "1" smd circle
			(at 0.40005 0 90)
			(size 0 0)
			(layers "B.Cu" "B.Mask" "B.Paste")
			(net "P12V_MB3_SENSE-")
		)
		(pad "2" smd circle
			(at -0.40005 0 90)
			(size 0 0)
			(layers "B.Cu" "B.Mask" "B.Paste")
			(net "GND")
		)
	)
	(footprint ""
		(layer "B.Cu")
		(at 54.483 -77.47 180)
		(property "Reference" "C61"
			(at 0 0 0)
			(layer "B.SilkS")
			(hide yes)
			(effects
				(font
					(size 1.27 1.27)
				)
				(justify mirror)
			)
		)
		(property "Value" ""
			(at 0 0 0)
			(layer "B.Fab")
			(effects
				(font
					(size 1.27 1.27)
				)
				(justify mirror)
			)
		)
		(duplicate_pad_numbers_are_jumpers no)
		(fp_line
			(start 0.7874 0.4064)
			(end 0.7874 -0.4064)
			(stroke
				(width 0.1524)
				(type default)
			)
			(layer "B.SilkS")
		)
		(fp_line
			(start 0.7874 -0.4064)
			(end -0.7874 -0.4064)
			(stroke
				(width 0.1524)
				(type default)
			)
			(layer "B.SilkS")
		)
		(fp_line
			(start -0.7874 0.4064)
			(end 0.7874 0.4064)
			(stroke
				(width 0.1524)
				(type default)
			)
			(layer "B.SilkS")
		)
		(fp_line
			(start -0.7874 -0.4064)
			(end -0.7874 0.4064)
			(stroke
				(width 0.1524)
				(type default)
			)
			(layer "B.SilkS")
		)
		(fp_line
			(start 0.67945 0.3048)
			(end 0.67945 -0.305054)
			(stroke
				(width 0.1)
				(type default)
			)
			(layer "B.Fab")
		)
		(fp_line
			(start 0.67945 -0.305054)
			(end 0.12065 -0.305054)
			(stroke
				(width 0.1)
				(type default)
			)
			(layer "B.Fab")
		)
		(fp_line
			(start 0.12065 0.3048)
			(end 0.67945 0.3048)
			(stroke
				(width 0.1)
				(type default)
			)
			(layer "B.Fab")
		)
		(fp_line
			(start 0.12065 0.2794)
			(end 0.12065 0.3048)
			(stroke
				(width 0.1)
				(type default)
			)
			(layer "B.Fab")
		)
		(fp_line
			(start 0.12065 -0.2794)
			(end -0.12065 -0.2794)
			(stroke
				(width 0.1)
				(type default)
			)
			(layer "B.Fab")
		)
		(fp_line
			(start 0.12065 -0.305054)
			(end 0.12065 -0.2794)
			(stroke
				(width 0.1)
				(type default)
			)
			(layer "B.Fab")
		)
		(fp_line
			(start -0.120396 0.3048)
			(end -0.120396 0.2794)
			(stroke
				(width 0.1)
				(type default)
			)
			(layer "B.Fab")
		)
		(fp_line
			(start -0.120396 0.2794)
			(end 0.12065 0.2794)
			(stroke
				(width 0.1)
				(type default)
			)
			(layer "B.Fab")
		)
		(fp_line
			(start -0.12065 -0.2794)
			(end -0.12065 -0.3048)
			(stroke
				(width 0.1)
				(type default)
			)
			(layer "B.Fab")
		)
		(fp_line
			(start -0.12065 -0.3048)
			(end -0.67945 -0.3048)
			(stroke
				(width 0.1)
				(type default)
			)
			(layer "B.Fab")
		)
		(fp_line
			(start -0.67945 0.3048)
			(end -0.120396 0.3048)
			(stroke
				(width 0.1)
				(type default)
			)
			(layer "B.Fab")
		)
		(fp_line
			(start -0.67945 -0.3048)
			(end -0.67945 0.3048)
			(stroke
				(width 0.1)
				(type default)
			)
			(layer "B.Fab")
		)
		(pad "1" smd circle
			(at 0.40005 0)
			(size 0 0)
			(layers "B.Cu" "B.Mask" "B.Paste")
			(net "SMB_P52V_VPDB_SDA")
		)
		(pad "2" smd circle
			(at -0.40005 0)
			(size 0 0)
			(layers "B.Cu" "B.Mask" "B.Paste")
			(net "GND")
		)
	)
	(footprint ""
		(layer "B.Cu")
		(at 289.687 -53.34 90)
		(property "Reference" "PR3"
			(at 0 0 90)
			(layer "B.SilkS")
			(hide yes)
			(effects
				(font
					(size 1.27 1.27)
				)
				(justify mirror)
			)
		)
		(property "Value" ""
			(at 0 0 90)
			(layer "B.Fab")
			(effects
				(font
					(size 1.27 1.27)
				)
				(justify mirror)
			)
		)
		(duplicate_pad_numbers_are_jumpers no)
		(fp_line
			(start 1.651 -0.8382)
			(end -1.651 -0.8382)
			(stroke
				(width 0.1524)
				(type default)
			)
			(layer "B.SilkS")
		)
		(fp_line
			(start -1.651 -0.8382)
			(end -1.651 0.8382)
			(stroke
				(width 0.1524)
				(type default)
			)
			(layer "B.SilkS")
		)
		(fp_line
			(start 1.651 0.8382)
			(end 1.651 -0.8382)
			(stroke
				(width 0.1524)
				(type default)
			)
			(layer "B.SilkS")
		)
		(fp_line
			(start -1.651 0.8382)
			(end 1.651 0.8382)
			(stroke
				(width 0.1524)
				(type default)
			)
			(layer "B.SilkS")
		)
		(fp_line
			(start 1.559814 -0.7366)
			(end 1.559814 0.7366)
			(stroke
				(width 0.1)
				(type default)
			)
			(layer "B.Fab")
		)
		(fp_line
			(start 1.524 -0.7366)
			(end 1.559814 -0.7366)
			(stroke
				(width 0.1)
				(type default)
			)
			(layer "B.Fab")
		)
		(fp_line
			(start -1.524 -0.7366)
			(end 1.524 -0.7366)
			(stroke
				(width 0.1)
				(type default)
			)
			(layer "B.Fab")
		)
		(fp_line
			(start -1.560576 -0.7366)
			(end -1.524 -0.7366)
			(stroke
				(width 0.1)
				(type default)
			)
			(layer "B.Fab")
		)
		(fp_line
			(start 1.559814 0.7366)
			(end 1.524 0.7366)
			(stroke
				(width 0.1)
				(type default)
			)
			(layer "B.Fab")
		)
		(fp_line
			(start 1.524 0.7366)
			(end -1.524 0.7366)
			(stroke
				(width 0.1)
				(type default)
			)
			(layer "B.Fab")
		)
		(fp_line
			(start -1.524 0.7366)
			(end -1.560576 0.7366)
			(stroke
				(width 0.1)
				(type default)
			)
			(layer "B.Fab")
		)
		(fp_line
			(start -1.560576 0.7366)
			(end -1.560576 -0.7366)
			(stroke
				(width 0.1)
				(type default)
			)
			(layer "B.Fab")
		)
		(pad "1" smd rect
			(at 0.94996 0 90)
			(size 1.1176 1.3716)
			(layers "B.Cu" "B.Mask" "B.Paste")
			(net "P52V_1")
		)
		(pad "2" smd rect
			(at -0.94996 0 90)
			(size 1.1176 1.3716)
			(layers "B.Cu" "B.Mask" "B.Paste")
			(net "P52V_HS1_UVLO_EN")
		)
	)
	(footprint ""
		(layer "B.Cu")
		(at 289.38093 -36.508436 180)
		(property "Reference" "R5919"
			(at 0 0 0)
			(layer "B.SilkS")
			(hide yes)
			(effects
				(font
					(size 1.27 1.27)
				)
				(justify mirror)
			)
		)
		(property "Value" ""
			(at 0 0 0)
			(layer "B.Fab")
			(effects
				(font
					(size 1.27 1.27)
				)
				(justify mirror)
			)
		)
		(duplicate_pad_numbers_are_jumpers no)
		(fp_line
			(start 0.7874 0.4064)
			(end 0.7874 -0.4064)
			(stroke
				(width 0.1524)
				(type default)
			)
			(layer "B.SilkS")
		)
		(fp_line
			(start 0.7874 -0.4064)
			(end -0.7874 -0.4064)
			(stroke
				(width 0.1524)
				(type default)
			)
			(layer "B.SilkS")
		)
		(fp_line
			(start -0.7874 0.4064)
			(end 0.7874 0.4064)
			(stroke
				(width 0.1524)
				(type default)
			)
			(layer "B.SilkS")
		)
		(fp_line
			(start -0.7874 -0.4064)
			(end -0.7874 0.4064)
			(stroke
				(width 0.1524)
				(type default)
			)
			(layer "B.SilkS")
		)
		(fp_line
			(start 0.67945 0.3048)
			(end 0.67945 -0.305054)
			(stroke
				(width 0.1)
				(type default)
			)
			(layer "B.Fab")
		)
		(fp_line
			(start 0.67945 -0.305054)
			(end 0.12065 -0.305054)
			(stroke
				(width 0.1)
				(type default)
			)
			(layer "B.Fab")
		)
		(fp_line
			(start 0.12065 0.3048)
			(end 0.67945 0.3048)
			(stroke
				(width 0.1)
				(type default)
			)
			(layer "B.Fab")
		)
		(fp_line
			(start 0.12065 0.2794)
			(end 0.12065 0.3048)
			(stroke
				(width 0.1)
				(type default)
			)
			(layer "B.Fab")
		)
		(fp_line
			(start 0.12065 -0.2794)
			(end -0.12065 -0.2794)
			(stroke
				(width 0.1)
				(type default)
			)
			(layer "B.Fab")
		)
		(fp_line
			(start 0.12065 -0.305054)
			(end 0.12065 -0.2794)
			(stroke
				(width 0.1)
				(type default)
			)
			(layer "B.Fab")
		)
		(fp_line
			(start -0.120396 0.3048)
			(end -0.120396 0.2794)
			(stroke
				(width 0.1)
				(type default)
			)
			(layer "B.Fab")
		)
		(fp_line
			(start -0.120396 0.2794)
			(end 0.12065 0.2794)
			(stroke
				(width 0.1)
				(type default)
			)
			(layer "B.Fab")
		)
		(fp_line
			(start -0.12065 -0.2794)
			(end -0.12065 -0.3048)
			(stroke
				(width 0.1)
				(type default)
			)
			(layer "B.Fab")
		)
		(fp_line
			(start -0.12065 -0.3048)
			(end -0.67945 -0.3048)
			(stroke
				(width 0.1)
				(type default)
			)
			(layer "B.Fab")
		)
		(fp_line
			(start -0.67945 0.3048)
			(end -0.120396 0.3048)
			(stroke
				(width 0.1)
				(type default)
			)
			(layer "B.Fab")
		)
		(fp_line
			(start -0.67945 -0.3048)
			(end -0.67945 0.3048)
			(stroke
				(width 0.1)
				(type default)
			)
			(layer "B.Fab")
		)
		(pad "1" smd circle
			(at 0.40005 0)
			(size 0 0)
			(layers "B.Cu" "B.Mask" "B.Paste")
			(net "FM_AC_PWR_CYCLE_N")
		)
		(pad "2" smd circle
			(at -0.40005 0)
			(size 0 0)
			(layers "B.Cu" "B.Mask" "B.Paste")
			(net "FM_AC_PWR_CYCLE_R1_N")
		)
	)
	(footprint ""
		(layer "B.Cu")
		(at 176.850294 -114.046 90)
		(property "Reference" "C70"
			(at 0 0 90)
			(layer "B.SilkS")
			(hide yes)
			(effects
				(font
					(size 1.27 1.27)
				)
				(justify mirror)
			)
		)
		(property "Value" ""
			(at 0 0 90)
			(layer "B.Fab")
			(effects
				(font
					(size 1.27 1.27)
				)
				(justify mirror)
			)
		)
		(duplicate_pad_numbers_are_jumpers no)
		(fp_line
			(start 0.7874 -0.4064)
			(end -0.7874 -0.4064)
			(stroke
				(width 0.1524)
				(type default)
			)
			(layer "B.SilkS")
		)
		(fp_line
			(start -0.7874 -0.4064)
			(end -0.7874 0.4064)
			(stroke
				(width 0.1524)
				(type default)
			)
			(layer "B.SilkS")
		)
		(fp_line
			(start 0.7874 0.4064)
			(end 0.7874 -0.4064)
			(stroke
				(width 0.1524)
				(type default)
			)
			(layer "B.SilkS")
		)
		(fp_line
			(start -0.7874 0.4064)
			(end 0.7874 0.4064)
			(stroke
				(width 0.1524)
				(type default)
			)
			(layer "B.SilkS")
		)
		(fp_line
			(start 0.67945 -0.305054)
			(end 0.12065 -0.305054)
			(stroke
				(width 0.1)
				(type default)
			)
			(layer "B.Fab")
		)
		(fp_line
			(start 0.12065 -0.305054)
			(end 0.12065 -0.2794)
			(stroke
				(width 0.1)
				(type default)
			)
			(layer "B.Fab")
		)
		(fp_line
			(start -0.12065 -0.3048)
			(end -0.67945 -0.3048)
			(stroke
				(width 0.1)
				(type default)
			)
			(layer "B.Fab")
		)
		(fp_line
			(start -0.67945 -0.3048)
			(end -0.67945 0.3048)
			(stroke
				(width 0.1)
				(type default)
			)
			(layer "B.Fab")
		)
		(fp_line
			(start 0.12065 -0.2794)
			(end -0.12065 -0.2794)
			(stroke
				(width 0.1)
				(type default)
			)
			(layer "B.Fab")
		)
		(fp_line
			(start -0.12065 -0.2794)
			(end -0.12065 -0.3048)
			(stroke
				(width 0.1)
				(type default)
			)
			(layer "B.Fab")
		)
		(fp_line
			(start 0.12065 0.2794)
			(end 0.12065 0.3048)
			(stroke
				(width 0.1)
				(type default)
			)
			(layer "B.Fab")
		)
		(fp_line
			(start -0.120396 0.2794)
			(end 0.12065 0.2794)
			(stroke
				(width 0.1)
				(type default)
			)
			(layer "B.Fab")
		)
		(fp_line
			(start 0.67945 0.3048)
			(end 0.67945 -0.305054)
			(stroke
				(width 0.1)
				(type default)
			)
			(layer "B.Fab")
		)
		(fp_line
			(start 0.12065 0.3048)
			(end 0.67945 0.3048)
			(stroke
				(width 0.1)
				(type default)
			)
			(layer "B.Fab")
		)
		(fp_line
			(start -0.120396 0.3048)
			(end -0.120396 0.2794)
			(stroke
				(width 0.1)
				(type default)
			)
			(layer "B.Fab")
		)
		(fp_line
			(start -0.67945 0.3048)
			(end -0.120396 0.3048)
			(stroke
				(width 0.1)
				(type default)
			)
			(layer "B.Fab")
		)
		(pad "1" smd circle
			(at 0.40005 0 270)
			(size 0 0)
			(layers "B.Cu" "B.Mask" "B.Paste")
			(net "BRICK_P12V_1_EN_N")
		)
		(pad "2" smd circle
			(at -0.40005 0 270)
			(size 0 0)
			(layers "B.Cu" "B.Mask" "B.Paste")
			(net "GND")
		)
	)
	(footprint ""
		(layer "B.Cu")
		(at 276.225 -34.29 180)
		(property "Reference" "R5930"
			(at 0 0 0)
			(layer "B.SilkS")
			(hide yes)
			(effects
				(font
					(size 1.27 1.27)
				)
				(justify mirror)
			)
		)
		(property "Value" ""
			(at 0 0 0)
			(layer "B.Fab")
			(effects
				(font
					(size 1.27 1.27)
				)
				(justify mirror)
			)
		)
		(duplicate_pad_numbers_are_jumpers no)
		(fp_line
			(start 1.651 0.8382)
			(end 1.651 -0.8382)
			(stroke
				(width 0.1524)
				(type default)
			)
			(layer "B.SilkS")
		)
		(fp_line
			(start 1.651 -0.8382)
			(end -1.651 -0.8382)
			(stroke
				(width 0.1524)
				(type default)
			)
			(layer "B.SilkS")
		)
		(fp_line
			(start -1.651 0.8382)
			(end 1.651 0.8382)
			(stroke
				(width 0.1524)
				(type default)
			)
			(layer "B.SilkS")
		)
		(fp_line
			(start -1.651 -0.8382)
			(end -1.651 0.8382)
			(stroke
				(width 0.1524)
				(type default)
			)
			(layer "B.SilkS")
		)
		(fp_line
			(start 1.559814 0.7366)
			(end 1.524 0.7366)
			(stroke
				(width 0.1)
				(type default)
			)
			(layer "B.Fab")
		)
		(fp_line
			(start 1.559814 -0.7366)
			(end 1.559814 0.7366)
			(stroke
				(width 0.1)
				(type default)
			)
			(layer "B.Fab")
		)
		(fp_line
			(start 1.524 0.7366)
			(end -1.524 0.7366)
			(stroke
				(width 0.1)
				(type default)
			)
			(layer "B.Fab")
		)
		(fp_line
			(start 1.524 -0.7366)
			(end 1.559814 -0.7366)
			(stroke
				(width 0.1)
				(type default)
			)
			(layer "B.Fab")
		)
		(fp_line
			(start -1.524 0.7366)
			(end -1.560576 0.7366)
			(stroke
				(width 0.1)
				(type default)
			)
			(layer "B.Fab")
		)
		(fp_line
			(start -1.524 -0.7366)
			(end 1.524 -0.7366)
			(stroke
				(width 0.1)
				(type default)
			)
			(layer "B.Fab")
		)
		(fp_line
			(start -1.560576 0.7366)
			(end -1.560576 -0.7366)
			(stroke
				(width 0.1)
				(type default)
			)
			(layer "B.Fab")
		)
		(fp_line
			(start -1.560576 -0.7366)
			(end -1.524 -0.7366)
			(stroke
				(width 0.1)
				(type default)
			)
			(layer "B.Fab")
		)
		(pad "1" smd rect
			(at 0.94996 0 180)
			(size 1.1176 1.3716)
			(layers "B.Cu" "B.Mask" "B.Paste")
			(net "P52V_1_R")
		)
		(pad "2" smd rect
			(at -0.94996 0 180)
			(size 1.1176 1.3716)
			(layers "B.Cu" "B.Mask" "B.Paste")
			(net "P52V_HS1_EN_DELAY_N")
		)
	)
	(footprint ""
		(layer "B.Cu")
		(at 63.881 -76.708 -90)
		(property "Reference" "PR322"
			(at 0 0 90)
			(layer "B.SilkS")
			(hide yes)
			(effects
				(font
					(size 1.27 1.27)
				)
				(justify mirror)
			)
		)
		(property "Value" ""
			(at 0 0 90)
			(layer "B.Fab")
			(effects
				(font
					(size 1.27 1.27)
				)
				(justify mirror)
			)
		)
		(duplicate_pad_numbers_are_jumpers no)
		(fp_line
			(start -0.7874 0.4064)
			(end 0.7874 0.4064)
			(stroke
				(width 0.1524)
				(type default)
			)
			(layer "B.SilkS")
		)
		(fp_line
			(start 0.7874 0.4064)
			(end 0.7874 -0.4064)
			(stroke
				(width 0.1524)
				(type default)
			)
			(layer "B.SilkS")
		)
		(fp_line
			(start -0.7874 -0.4064)
			(end -0.7874 0.4064)
			(stroke
				(width 0.1524)
				(type default)
			)
			(layer "B.SilkS")
		)
		(fp_line
			(start 0.7874 -0.4064)
			(end -0.7874 -0.4064)
			(stroke
				(width 0.1524)
				(type default)
			)
			(layer "B.SilkS")
		)
		(fp_line
			(start -0.67945 0.3048)
			(end -0.120396 0.3048)
			(stroke
				(width 0.1)
				(type default)
			)
			(layer "B.Fab")
		)
		(fp_line
			(start -0.120396 0.3048)
			(end -0.120396 0.2794)
			(stroke
				(width 0.1)
				(type default)
			)
			(layer "B.Fab")
		)
		(fp_line
			(start 0.12065 0.3048)
			(end 0.67945 0.3048)
			(stroke
				(width 0.1)
				(type default)
			)
			(layer "B.Fab")
		)
		(fp_line
			(start 0.67945 0.3048)
			(end 0.67945 -0.305054)
			(stroke
				(width 0.1)
				(type default)
			)
			(layer "B.Fab")
		)
		(fp_line
			(start -0.120396 0.2794)
			(end 0.12065 0.2794)
			(stroke
				(width 0.1)
				(type default)
			)
			(layer "B.Fab")
		)
		(fp_line
			(start 0.12065 0.2794)
			(end 0.12065 0.3048)
			(stroke
				(width 0.1)
				(type default)
			)
			(layer "B.Fab")
		)
		(fp_line
			(start -0.12065 -0.2794)
			(end -0.12065 -0.3048)
			(stroke
				(width 0.1)
				(type default)
			)
			(layer "B.Fab")
		)
		(fp_line
			(start 0.12065 -0.2794)
			(end -0.12065 -0.2794)
			(stroke
				(width 0.1)
				(type default)
			)
			(layer "B.Fab")
		)
		(fp_line
			(start -0.67945 -0.3048)
			(end -0.67945 0.3048)
			(stroke
				(width 0.1)
				(type default)
			)
			(layer "B.Fab")
		)
		(fp_line
			(start -0.12065 -0.3048)
			(end -0.67945 -0.3048)
			(stroke
				(width 0.1)
				(type default)
			)
			(layer "B.Fab")
		)
		(fp_line
			(start 0.12065 -0.305054)
			(end 0.12065 -0.2794)
			(stroke
				(width 0.1)
				(type default)
			)
			(layer "B.Fab")
		)
		(fp_line
			(start 0.67945 -0.305054)
			(end 0.12065 -0.305054)
			(stroke
				(width 0.1)
				(type default)
			)
			(layer "B.Fab")
		)
		(pad "1" smd circle
			(at 0.40005 0 90)
			(size 0 0)
			(layers "B.Cu" "B.Mask" "B.Paste")
			(net "P12V_MB3_SENSE+")
		)
		(pad "2" smd circle
			(at -0.40005 0 90)
			(size 0 0)
			(layers "B.Cu" "B.Mask" "B.Paste")
			(net "P12V_MB2_SENSE+")
		)
	)
	(footprint ""
		(layer "B.Cu")
		(at 56.850026 -114.046 90)
		(property "Reference" "C60"
			(at 0 0 90)
			(layer "B.SilkS")
			(hide yes)
			(effects
				(font
					(size 1.27 1.27)
				)
				(justify mirror)
			)
		)
		(property "Value" ""
			(at 0 0 90)
			(layer "B.Fab")
			(effects
				(font
					(size 1.27 1.27)
				)
				(justify mirror)
			)
		)
		(duplicate_pad_numbers_are_jumpers no)
		(fp_line
			(start 0.7874 -0.4064)
			(end -0.7874 -0.4064)
			(stroke
				(width 0.1524)
				(type default)
			)
			(layer "B.SilkS")
		)
		(fp_line
			(start -0.7874 -0.4064)
			(end -0.7874 0.4064)
			(stroke
				(width 0.1524)
				(type default)
			)
			(layer "B.SilkS")
		)
		(fp_line
			(start 0.7874 0.4064)
			(end 0.7874 -0.4064)
			(stroke
				(width 0.1524)
				(type default)
			)
			(layer "B.SilkS")
		)
		(fp_line
			(start -0.7874 0.4064)
			(end 0.7874 0.4064)
			(stroke
				(width 0.1524)
				(type default)
			)
			(layer "B.SilkS")
		)
		(fp_line
			(start 0.67945 -0.305054)
			(end 0.12065 -0.305054)
			(stroke
				(width 0.1)
				(type default)
			)
			(layer "B.Fab")
		)
		(fp_line
			(start 0.12065 -0.305054)
			(end 0.12065 -0.2794)
			(stroke
				(width 0.1)
				(type default)
			)
			(layer "B.Fab")
		)
		(fp_line
			(start -0.12065 -0.3048)
			(end -0.67945 -0.3048)
			(stroke
				(width 0.1)
				(type default)
			)
			(layer "B.Fab")
		)
		(fp_line
			(start -0.67945 -0.3048)
			(end -0.67945 0.3048)
			(stroke
				(width 0.1)
				(type default)
			)
			(layer "B.Fab")
		)
		(fp_line
			(start 0.12065 -0.2794)
			(end -0.12065 -0.2794)
			(stroke
				(width 0.1)
				(type default)
			)
			(layer "B.Fab")
		)
		(fp_line
			(start -0.12065 -0.2794)
			(end -0.12065 -0.3048)
			(stroke
				(width 0.1)
				(type default)
			)
			(layer "B.Fab")
		)
		(fp_line
			(start 0.12065 0.2794)
			(end 0.12065 0.3048)
			(stroke
				(width 0.1)
				(type default)
			)
			(layer "B.Fab")
		)
		(fp_line
			(start -0.120396 0.2794)
			(end 0.12065 0.2794)
			(stroke
				(width 0.1)
				(type default)
			)
			(layer "B.Fab")
		)
		(fp_line
			(start 0.67945 0.3048)
			(end 0.67945 -0.305054)
			(stroke
				(width 0.1)
				(type default)
			)
			(layer "B.Fab")
		)
		(fp_line
			(start 0.12065 0.3048)
			(end 0.67945 0.3048)
			(stroke
				(width 0.1)
				(type default)
			)
			(layer "B.Fab")
		)
		(fp_line
			(start -0.120396 0.3048)
			(end -0.120396 0.2794)
			(stroke
				(width 0.1)
				(type default)
			)
			(layer "B.Fab")
		)
		(fp_line
			(start -0.67945 0.3048)
			(end -0.120396 0.3048)
			(stroke
				(width 0.1)
				(type default)
			)
			(layer "B.Fab")
		)
		(pad "1" smd circle
			(at 0.40005 0 270)
			(size 0 0)
			(layers "B.Cu" "B.Mask" "B.Paste")
			(net "BRICK_P12V_1_EN_N")
		)
		(pad "2" smd circle
			(at -0.40005 0 270)
			(size 0 0)
			(layers "B.Cu" "B.Mask" "B.Paste")
			(net "GND")
		)
	)
	(footprint ""
		(layer "B.Cu")
		(at 268.986 -36.068 180)
		(property "Reference" "PR11"
			(at 0 0 0)
			(layer "B.SilkS")
			(hide yes)
			(effects
				(font
					(size 1.27 1.27)
				)
				(justify mirror)
			)
		)
		(property "Value" ""
			(at 0 0 0)
			(layer "B.Fab")
			(effects
				(font
					(size 1.27 1.27)
				)
				(justify mirror)
			)
		)
		(duplicate_pad_numbers_are_jumpers no)
		(fp_line
			(start 0.7874 0.4064)
			(end 0.7874 -0.4064)
			(stroke
				(width 0.1524)
				(type default)
			)
			(layer "B.SilkS")
		)
		(fp_line
			(start 0.7874 -0.4064)
			(end -0.7874 -0.4064)
			(stroke
				(width 0.1524)
				(type default)
			)
			(layer "B.SilkS")
		)
		(fp_line
			(start -0.7874 0.4064)
			(end 0.7874 0.4064)
			(stroke
				(width 0.1524)
				(type default)
			)
			(layer "B.SilkS")
		)
		(fp_line
			(start -0.7874 -0.4064)
			(end -0.7874 0.4064)
			(stroke
				(width 0.1524)
				(type default)
			)
			(layer "B.SilkS")
		)
		(fp_line
			(start 0.67945 0.3048)
			(end 0.67945 -0.305054)
			(stroke
				(width 0.1)
				(type default)
			)
			(layer "B.Fab")
		)
		(fp_line
			(start 0.67945 -0.305054)
			(end 0.12065 -0.305054)
			(stroke
				(width 0.1)
				(type default)
			)
			(layer "B.Fab")
		)
		(fp_line
			(start 0.12065 0.3048)
			(end 0.67945 0.3048)
			(stroke
				(width 0.1)
				(type default)
			)
			(layer "B.Fab")
		)
		(fp_line
			(start 0.12065 0.2794)
			(end 0.12065 0.3048)
			(stroke
				(width 0.1)
				(type default)
			)
			(layer "B.Fab")
		)
		(fp_line
			(start 0.12065 -0.2794)
			(end -0.12065 -0.2794)
			(stroke
				(width 0.1)
				(type default)
			)
			(layer "B.Fab")
		)
		(fp_line
			(start 0.12065 -0.305054)
			(end 0.12065 -0.2794)
			(stroke
				(width 0.1)
				(type default)
			)
			(layer "B.Fab")
		)
		(fp_line
			(start -0.120396 0.3048)
			(end -0.120396 0.2794)
			(stroke
				(width 0.1)
				(type default)
			)
			(layer "B.Fab")
		)
		(fp_line
			(start -0.120396 0.2794)
			(end 0.12065 0.2794)
			(stroke
				(width 0.1)
				(type default)
			)
			(layer "B.Fab")
		)
		(fp_line
			(start -0.12065 -0.2794)
			(end -0.12065 -0.3048)
			(stroke
				(width 0.1)
				(type default)
			)
			(layer "B.Fab")
		)
		(fp_line
			(start -0.12065 -0.3048)
			(end -0.67945 -0.3048)
			(stroke
				(width 0.1)
				(type default)
			)
			(layer "B.Fab")
		)
		(fp_line
			(start -0.67945 0.3048)
			(end -0.120396 0.3048)
			(stroke
				(width 0.1)
				(type default)
			)
			(layer "B.Fab")
		)
		(fp_line
			(start -0.67945 -0.3048)
			(end -0.67945 0.3048)
			(stroke
				(width 0.1)
				(type default)
			)
			(layer "B.Fab")
		)
		(pad "1" smd circle
			(at 0.40005 0)
			(size 0 0)
			(layers "B.Cu" "B.Mask" "B.Paste")
			(net "GND_FIELD_SIGNAL")
		)
		(pad "2" smd circle
			(at -0.40005 0)
			(size 0 0)
			(layers "B.Cu" "B.Mask" "B.Paste")
			(net "P52V_HS1_CLKIN")
		)
	)
	(footprint ""
		(layer "B.Cu")
		(at 189.611 -84.963)
		(property "Reference" "R127"
			(at 0 0 0)
			(layer "B.SilkS")
			(hide yes)
			(effects
				(font
					(size 1.27 1.27)
				)
				(justify mirror)
			)
		)
		(property "Value" ""
			(at 0 0 0)
			(layer "B.Fab")
			(effects
				(font
					(size 1.27 1.27)
				)
				(justify mirror)
			)
		)
		(duplicate_pad_numbers_are_jumpers no)
		(fp_line
			(start -0.7874 -0.4064)
			(end -0.7874 0.4064)
			(stroke
				(width 0.1524)
				(type default)
			)
			(layer "B.SilkS")
		)
		(fp_line
			(start -0.7874 0.4064)
			(end 0.7874 0.4064)
			(stroke
				(width 0.1524)
				(type default)
			)
			(layer "B.SilkS")
		)
		(fp_line
			(start 0.7874 -0.4064)
			(end -0.7874 -0.4064)
			(stroke
				(width 0.1524)
				(type default)
			)
			(layer "B.SilkS")
		)
		(fp_line
			(start 0.7874 0.4064)
			(end 0.7874 -0.4064)
			(stroke
				(width 0.1524)
				(type default)
			)
			(layer "B.SilkS")
		)
		(fp_line
			(start -0.67945 -0.3048)
			(end -0.67945 0.3048)
			(stroke
				(width 0.1)
				(type default)
			)
			(layer "B.Fab")
		)
		(fp_line
			(start -0.67945 0.3048)
			(end -0.120396 0.3048)
			(stroke
				(width 0.1)
				(type default)
			)
			(layer "B.Fab")
		)
		(fp_line
			(start -0.12065 -0.3048)
			(end -0.67945 -0.3048)
			(stroke
				(width 0.1)
				(type default)
			)
			(layer "B.Fab")
		)
		(fp_line
			(start -0.12065 -0.2794)
			(end -0.12065 -0.3048)
			(stroke
				(width 0.1)
				(type default)
			)
			(layer "B.Fab")
		)
		(fp_line
			(start -0.120396 0.2794)
			(end 0.12065 0.2794)
			(stroke
				(width 0.1)
				(type default)
			)
			(layer "B.Fab")
		)
		(fp_line
			(start -0.120396 0.3048)
			(end -0.120396 0.2794)
			(stroke
				(width 0.1)
				(type default)
			)
			(layer "B.Fab")
		)
		(fp_line
			(start 0.12065 -0.305054)
			(end 0.12065 -0.2794)
			(stroke
				(width 0.1)
				(type default)
			)
			(layer "B.Fab")
		)
		(fp_line
			(start 0.12065 -0.2794)
			(end -0.12065 -0.2794)
			(stroke
				(width 0.1)
				(type default)
			)
			(layer "B.Fab")
		)
		(fp_line
			(start 0.12065 0.2794)
			(end 0.12065 0.3048)
			(stroke
				(width 0.1)
				(type default)
			)
			(layer "B.Fab")
		)
		(fp_line
			(start 0.12065 0.3048)
			(end 0.67945 0.3048)
			(stroke
				(width 0.1)
				(type default)
			)
			(layer "B.Fab")
		)
		(fp_line
			(start 0.67945 -0.305054)
			(end 0.12065 -0.305054)
			(stroke
				(width 0.1)
				(type default)
			)
			(layer "B.Fab")
		)
		(fp_line
			(start 0.67945 0.3048)
			(end 0.67945 -0.305054)
			(stroke
				(width 0.1)
				(type default)
			)
			(layer "B.Fab")
		)
		(pad "1" smd circle
			(at 0.40005 0 180)
			(size 0 0)
			(layers "B.Cu" "B.Mask" "B.Paste")
			(net "SMB_P52V_VPDB_SCL_R")
		)
		(pad "2" smd circle
			(at -0.40005 0 180)
			(size 0 0)
			(layers "B.Cu" "B.Mask" "B.Paste")
			(net "P3V3_AUX")
		)
	)
	(footprint ""
		(layer "B.Cu")
		(at 174.493174 -78.867)
		(property "Reference" "R192"
			(at 0 0 0)
			(layer "B.SilkS")
			(hide yes)
			(effects
				(font
					(size 1.27 1.27)
				)
				(justify mirror)
			)
		)
		(property "Value" ""
			(at 0 0 0)
			(layer "B.Fab")
			(effects
				(font
					(size 1.27 1.27)
				)
				(justify mirror)
			)
		)
		(duplicate_pad_numbers_are_jumpers no)
		(fp_line
			(start -0.7874 -0.4064)
			(end -0.7874 0.4064)
			(stroke
				(width 0.1524)
				(type default)
			)
			(layer "B.SilkS")
		)
		(fp_line
			(start -0.7874 0.4064)
			(end 0.7874 0.4064)
			(stroke
				(width 0.1524)
				(type default)
			)
			(layer "B.SilkS")
		)
		(fp_line
			(start 0.7874 -0.4064)
			(end -0.7874 -0.4064)
			(stroke
				(width 0.1524)
				(type default)
			)
			(layer "B.SilkS")
		)
		(fp_line
			(start 0.7874 0.4064)
			(end 0.7874 -0.4064)
			(stroke
				(width 0.1524)
				(type default)
			)
			(layer "B.SilkS")
		)
		(fp_line
			(start -0.67945 -0.3048)
			(end -0.67945 0.3048)
			(stroke
				(width 0.1)
				(type default)
			)
			(layer "B.Fab")
		)
		(fp_line
			(start -0.67945 0.3048)
			(end -0.120396 0.3048)
			(stroke
				(width 0.1)
				(type default)
			)
			(layer "B.Fab")
		)
		(fp_line
			(start -0.12065 -0.3048)
			(end -0.67945 -0.3048)
			(stroke
				(width 0.1)
				(type default)
			)
			(layer "B.Fab")
		)
		(fp_line
			(start -0.12065 -0.2794)
			(end -0.12065 -0.3048)
			(stroke
				(width 0.1)
				(type default)
			)
			(layer "B.Fab")
		)
		(fp_line
			(start -0.120396 0.2794)
			(end 0.12065 0.2794)
			(stroke
				(width 0.1)
				(type default)
			)
			(layer "B.Fab")
		)
		(fp_line
			(start -0.120396 0.3048)
			(end -0.120396 0.2794)
			(stroke
				(width 0.1)
				(type default)
			)
			(layer "B.Fab")
		)
		(fp_line
			(start 0.12065 -0.305054)
			(end 0.12065 -0.2794)
			(stroke
				(width 0.1)
				(type default)
			)
			(layer "B.Fab")
		)
		(fp_line
			(start 0.12065 -0.2794)
			(end -0.12065 -0.2794)
			(stroke
				(width 0.1)
				(type default)
			)
			(layer "B.Fab")
		)
		(fp_line
			(start 0.12065 0.2794)
			(end 0.12065 0.3048)
			(stroke
				(width 0.1)
				(type default)
			)
			(layer "B.Fab")
		)
		(fp_line
			(start 0.12065 0.3048)
			(end 0.67945 0.3048)
			(stroke
				(width 0.1)
				(type default)
			)
			(layer "B.Fab")
		)
		(fp_line
			(start 0.67945 -0.305054)
			(end 0.12065 -0.305054)
			(stroke
				(width 0.1)
				(type default)
			)
			(layer "B.Fab")
		)
		(fp_line
			(start 0.67945 0.3048)
			(end 0.67945 -0.305054)
			(stroke
				(width 0.1)
				(type default)
			)
			(layer "B.Fab")
		)
		(pad "1" smd circle
			(at 0.40005 0 180)
			(size 0 0)
			(layers "B.Cu" "B.Mask" "B.Paste")
			(net "P3V3_AUX")
		)
		(pad "2" smd circle
			(at -0.40005 0 180)
			(size 0 0)
			(layers "B.Cu" "B.Mask" "B.Paste")
			(net "SMB_P52V_VPDB_SDA")
		)
	)
	(footprint ""
		(layer "B.Cu")
		(at 277.114 -100.203 90)
		(property "Reference" "PR220"
			(at 0 0 90)
			(layer "B.SilkS")
			(hide yes)
			(effects
				(font
					(size 1.27 1.27)
				)
				(justify mirror)
			)
		)
		(property "Value" ""
			(at 0 0 90)
			(layer "B.Fab")
			(effects
				(font
					(size 1.27 1.27)
				)
				(justify mirror)
			)
		)
		(duplicate_pad_numbers_are_jumpers no)
		(fp_line
			(start 1.2954 -0.5842)
			(end -1.2954 -0.5842)
			(stroke
				(width 0.1524)
				(type default)
			)
			(layer "B.SilkS")
		)
		(fp_line
			(start -1.2954 -0.5842)
			(end -1.2954 0.5842)
			(stroke
				(width 0.1524)
				(type default)
			)
			(layer "B.SilkS")
		)
		(fp_line
			(start 1.2954 0.5842)
			(end 1.2954 -0.5842)
			(stroke
				(width 0.1524)
				(type default)
			)
			(layer "B.SilkS")
		)
		(fp_line
			(start -1.2954 0.5842)
			(end 1.2954 0.5842)
			(stroke
				(width 0.1524)
				(type default)
			)
			(layer "B.SilkS")
		)
		(fp_line
			(start 0.8636 -0.4572)
			(end -0.8636 -0.4572)
			(stroke
				(width 0.1)
				(type default)
			)
			(layer "B.Fab")
		)
		(fp_line
			(start -0.8636 -0.4572)
			(end -0.8636 -0.406654)
			(stroke
				(width 0.1)
				(type default)
			)
			(layer "B.Fab")
		)
		(fp_line
			(start 1.1938 -0.406654)
			(end 0.8636 -0.406654)
			(stroke
				(width 0.1)
				(type default)
			)
			(layer "B.Fab")
		)
		(fp_line
			(start 0.8636 -0.406654)
			(end 0.8636 -0.4572)
			(stroke
				(width 0.1)
				(type default)
			)
			(layer "B.Fab")
		)
		(fp_line
			(start -0.8636 -0.406654)
			(end -1.1938 -0.406654)
			(stroke
				(width 0.1)
				(type default)
			)
			(layer "B.Fab")
		)
		(fp_line
			(start -1.1938 -0.406654)
			(end -1.1938 0.4064)
			(stroke
				(width 0.1)
				(type default)
			)
			(layer "B.Fab")
		)
		(fp_line
			(start 1.1938 0.4064)
			(end 1.1938 -0.406654)
			(stroke
				(width 0.1)
				(type default)
			)
			(layer "B.Fab")
		)
		(fp_line
			(start 0.8636 0.4064)
			(end 1.1938 0.4064)
			(stroke
				(width 0.1)
				(type default)
			)
			(layer "B.Fab")
		)
		(fp_line
			(start -0.8636 0.4064)
			(end -0.8636 0.4572)
			(stroke
				(width 0.1)
				(type default)
			)
			(layer "B.Fab")
		)
		(fp_line
			(start -1.1938 0.4064)
			(end -0.8636 0.4064)
			(stroke
				(width 0.1)
				(type default)
			)
			(layer "B.Fab")
		)
		(fp_line
			(start 0.8636 0.4318)
			(end 0.8636 0.4064)
			(stroke
				(width 0.1)
				(type default)
			)
			(layer "B.Fab")
		)
		(fp_line
			(start 0.8636 0.4572)
			(end 0.8636 0.4318)
			(stroke
				(width 0.1)
				(type default)
			)
			(layer "B.Fab")
		)
		(fp_line
			(start -0.8636 0.4572)
			(end 0.8636 0.4572)
			(stroke
				(width 0.1)
				(type default)
			)
			(layer "B.Fab")
		)
		(pad "1" smd rect
			(at 0.7366 0)
			(size 0.7112 0.8128)
			(layers "B.Cu" "B.Mask" "B.Paste")
			(net "P52V_HS1_4287_GATE_R")
		)
		(pad "2" smd rect
			(at -0.7366 0)
			(size 0.7112 0.8128)
			(layers "B.Cu" "B.Mask" "B.Paste")
			(net "P52V_HS1_GATE_RC")
		)
	)
	(footprint ""
		(layer "B.Cu")
		(at 276.733 -44.323)
		(property "Reference" "PR36"
			(at 0 0 0)
			(layer "B.SilkS")
			(hide yes)
			(effects
				(font
					(size 1.27 1.27)
				)
				(justify mirror)
			)
		)
		(property "Value" ""
			(at 0 0 0)
			(layer "B.Fab")
			(effects
				(font
					(size 1.27 1.27)
				)
				(justify mirror)
			)
		)
		(duplicate_pad_numbers_are_jumpers no)
		(fp_line
			(start -0.7874 -0.4064)
			(end -0.7874 0.4064)
			(stroke
				(width 0.1524)
				(type default)
			)
			(layer "B.SilkS")
		)
		(fp_line
			(start -0.7874 0.4064)
			(end 0.7874 0.4064)
			(stroke
				(width 0.1524)
				(type default)
			)
			(layer "B.SilkS")
		)
		(fp_line
			(start 0.7874 -0.4064)
			(end -0.7874 -0.4064)
			(stroke
				(width 0.1524)
				(type default)
			)
			(layer "B.SilkS")
		)
		(fp_line
			(start 0.7874 0.4064)
			(end 0.7874 -0.4064)
			(stroke
				(width 0.1524)
				(type default)
			)
			(layer "B.SilkS")
		)
		(fp_line
			(start -0.67945 -0.3048)
			(end -0.67945 0.3048)
			(stroke
				(width 0.1)
				(type default)
			)
			(layer "B.Fab")
		)
		(fp_line
			(start -0.67945 0.3048)
			(end -0.120396 0.3048)
			(stroke
				(width 0.1)
				(type default)
			)
			(layer "B.Fab")
		)
		(fp_line
			(start -0.12065 -0.3048)
			(end -0.67945 -0.3048)
			(stroke
				(width 0.1)
				(type default)
			)
			(layer "B.Fab")
		)
		(fp_line
			(start -0.12065 -0.2794)
			(end -0.12065 -0.3048)
			(stroke
				(width 0.1)
				(type default)
			)
			(layer "B.Fab")
		)
		(fp_line
			(start -0.120396 0.2794)
			(end 0.12065 0.2794)
			(stroke
				(width 0.1)
				(type default)
			)
			(layer "B.Fab")
		)
		(fp_line
			(start -0.120396 0.3048)
			(end -0.120396 0.2794)
			(stroke
				(width 0.1)
				(type default)
			)
			(layer "B.Fab")
		)
		(fp_line
			(start 0.12065 -0.305054)
			(end 0.12065 -0.2794)
			(stroke
				(width 0.1)
				(type default)
			)
			(layer "B.Fab")
		)
		(fp_line
			(start 0.12065 -0.2794)
			(end -0.12065 -0.2794)
			(stroke
				(width 0.1)
				(type default)
			)
			(layer "B.Fab")
		)
		(fp_line
			(start 0.12065 0.2794)
			(end 0.12065 0.3048)
			(stroke
				(width 0.1)
				(type default)
			)
			(layer "B.Fab")
		)
		(fp_line
			(start 0.12065 0.3048)
			(end 0.67945 0.3048)
			(stroke
				(width 0.1)
				(type default)
			)
			(layer "B.Fab")
		)
		(fp_line
			(start 0.67945 -0.305054)
			(end 0.12065 -0.305054)
			(stroke
				(width 0.1)
				(type default)
			)
			(layer "B.Fab")
		)
		(fp_line
			(start 0.67945 0.3048)
			(end 0.67945 -0.305054)
			(stroke
				(width 0.1)
				(type default)
			)
			(layer "B.Fab")
		)
		(pad "1" smd circle
			(at 0.40005 0 180)
			(size 0 0)
			(layers "B.Cu" "B.Mask" "B.Paste")
			(net "P52V_HS1_ESTART")
		)
		(pad "2" smd circle
			(at -0.40005 0 180)
			(size 0 0)
			(layers "B.Cu" "B.Mask" "B.Paste")
			(net "GND_FIELD_SIGNAL")
		)
	)
	(footprint ""
		(layer "B.Cu")
		(at 238.76 -70.993 -90)
		(property "Reference" "R67"
			(at 0 0 90)
			(layer "B.SilkS")
			(hide yes)
			(effects
				(font
					(size 1.27 1.27)
				)
				(justify mirror)
			)
		)
		(property "Value" ""
			(at 0 0 90)
			(layer "B.Fab")
			(effects
				(font
					(size 1.27 1.27)
				)
				(justify mirror)
			)
		)
		(duplicate_pad_numbers_are_jumpers no)
		(fp_line
			(start -0.7874 0.4064)
			(end 0.7874 0.4064)
			(stroke
				(width 0.1524)
				(type default)
			)
			(layer "B.SilkS")
		)
		(fp_line
			(start 0.7874 0.4064)
			(end 0.7874 -0.4064)
			(stroke
				(width 0.1524)
				(type default)
			)
			(layer "B.SilkS")
		)
		(fp_line
			(start -0.7874 -0.4064)
			(end -0.7874 0.4064)
			(stroke
				(width 0.1524)
				(type default)
			)
			(layer "B.SilkS")
		)
		(fp_line
			(start 0.7874 -0.4064)
			(end -0.7874 -0.4064)
			(stroke
				(width 0.1524)
				(type default)
			)
			(layer "B.SilkS")
		)
		(fp_line
			(start -0.67945 0.3048)
			(end -0.120396 0.3048)
			(stroke
				(width 0.1)
				(type default)
			)
			(layer "B.Fab")
		)
		(fp_line
			(start -0.120396 0.3048)
			(end -0.120396 0.2794)
			(stroke
				(width 0.1)
				(type default)
			)
			(layer "B.Fab")
		)
		(fp_line
			(start 0.12065 0.3048)
			(end 0.67945 0.3048)
			(stroke
				(width 0.1)
				(type default)
			)
			(layer "B.Fab")
		)
		(fp_line
			(start 0.67945 0.3048)
			(end 0.67945 -0.305054)
			(stroke
				(width 0.1)
				(type default)
			)
			(layer "B.Fab")
		)
		(fp_line
			(start -0.120396 0.2794)
			(end 0.12065 0.2794)
			(stroke
				(width 0.1)
				(type default)
			)
			(layer "B.Fab")
		)
		(fp_line
			(start 0.12065 0.2794)
			(end 0.12065 0.3048)
			(stroke
				(width 0.1)
				(type default)
			)
			(layer "B.Fab")
		)
		(fp_line
			(start -0.12065 -0.2794)
			(end -0.12065 -0.3048)
			(stroke
				(width 0.1)
				(type default)
			)
			(layer "B.Fab")
		)
		(fp_line
			(start 0.12065 -0.2794)
			(end -0.12065 -0.2794)
			(stroke
				(width 0.1)
				(type default)
			)
			(layer "B.Fab")
		)
		(fp_line
			(start -0.67945 -0.3048)
			(end -0.67945 0.3048)
			(stroke
				(width 0.1)
				(type default)
			)
			(layer "B.Fab")
		)
		(fp_line
			(start -0.12065 -0.3048)
			(end -0.67945 -0.3048)
			(stroke
				(width 0.1)
				(type default)
			)
			(layer "B.Fab")
		)
		(fp_line
			(start 0.12065 -0.305054)
			(end 0.12065 -0.2794)
			(stroke
				(width 0.1)
				(type default)
			)
			(layer "B.Fab")
		)
		(fp_line
			(start 0.67945 -0.305054)
			(end 0.12065 -0.305054)
			(stroke
				(width 0.1)
				(type default)
			)
			(layer "B.Fab")
		)
		(pad "1" smd circle
			(at 0.40005 0 90)
			(size 0 0)
			(layers "B.Cu" "B.Mask" "B.Paste")
			(net "SMB_MB_PDB_R_SDA")
		)
		(pad "2" smd circle
			(at -0.40005 0 90)
			(size 0 0)
			(layers "B.Cu" "B.Mask" "B.Paste")
			(net "SMB_MB_PDB_SDA")
		)
	)
	(footprint ""
		(layer "B.Cu")
		(at 54.483 -76.327 180)
		(property "Reference" "R178"
			(at 0 0 0)
			(layer "B.SilkS")
			(hide yes)
			(effects
				(font
					(size 1.27 1.27)
				)
				(justify mirror)
			)
		)
		(property "Value" ""
			(at 0 0 0)
			(layer "B.Fab")
			(effects
				(font
					(size 1.27 1.27)
				)
				(justify mirror)
			)
		)
		(duplicate_pad_numbers_are_jumpers no)
		(fp_line
			(start 0.7874 0.4064)
			(end 0.7874 -0.4064)
			(stroke
				(width 0.1524)
				(type default)
			)
			(layer "B.SilkS")
		)
		(fp_line
			(start 0.7874 -0.4064)
			(end -0.7874 -0.4064)
			(stroke
				(width 0.1524)
				(type default)
			)
			(layer "B.SilkS")
		)
		(fp_line
			(start -0.7874 0.4064)
			(end 0.7874 0.4064)
			(stroke
				(width 0.1524)
				(type default)
			)
			(layer "B.SilkS")
		)
		(fp_line
			(start -0.7874 -0.4064)
			(end -0.7874 0.4064)
			(stroke
				(width 0.1524)
				(type default)
			)
			(layer "B.SilkS")
		)
		(fp_line
			(start 0.67945 0.3048)
			(end 0.67945 -0.305054)
			(stroke
				(width 0.1)
				(type default)
			)
			(layer "B.Fab")
		)
		(fp_line
			(start 0.67945 -0.305054)
			(end 0.12065 -0.305054)
			(stroke
				(width 0.1)
				(type default)
			)
			(layer "B.Fab")
		)
		(fp_line
			(start 0.12065 0.3048)
			(end 0.67945 0.3048)
			(stroke
				(width 0.1)
				(type default)
			)
			(layer "B.Fab")
		)
		(fp_line
			(start 0.12065 0.2794)
			(end 0.12065 0.3048)
			(stroke
				(width 0.1)
				(type default)
			)
			(layer "B.Fab")
		)
		(fp_line
			(start 0.12065 -0.2794)
			(end -0.12065 -0.2794)
			(stroke
				(width 0.1)
				(type default)
			)
			(layer "B.Fab")
		)
		(fp_line
			(start 0.12065 -0.305054)
			(end 0.12065 -0.2794)
			(stroke
				(width 0.1)
				(type default)
			)
			(layer "B.Fab")
		)
		(fp_line
			(start -0.120396 0.3048)
			(end -0.120396 0.2794)
			(stroke
				(width 0.1)
				(type default)
			)
			(layer "B.Fab")
		)
		(fp_line
			(start -0.120396 0.2794)
			(end 0.12065 0.2794)
			(stroke
				(width 0.1)
				(type default)
			)
			(layer "B.Fab")
		)
		(fp_line
			(start -0.12065 -0.2794)
			(end -0.12065 -0.3048)
			(stroke
				(width 0.1)
				(type default)
			)
			(layer "B.Fab")
		)
		(fp_line
			(start -0.12065 -0.3048)
			(end -0.67945 -0.3048)
			(stroke
				(width 0.1)
				(type default)
			)
			(layer "B.Fab")
		)
		(fp_line
			(start -0.67945 0.3048)
			(end -0.120396 0.3048)
			(stroke
				(width 0.1)
				(type default)
			)
			(layer "B.Fab")
		)
		(fp_line
			(start -0.67945 -0.3048)
			(end -0.67945 0.3048)
			(stroke
				(width 0.1)
				(type default)
			)
			(layer "B.Fab")
		)
		(pad "1" smd circle
			(at 0.40005 0)
			(size 0 0)
			(layers "B.Cu" "B.Mask" "B.Paste")
			(net "SMB_P52V_VPDB_SDA")
		)
		(pad "2" smd circle
			(at -0.40005 0)
			(size 0 0)
			(layers "B.Cu" "B.Mask" "B.Paste")
			(net "SMB_BRICK3_SDA")
		)
	)
	(footprint ""
		(layer "B.Cu")
		(at 134.493 -76.327 180)
		(property "Reference" "R164"
			(at 0 0 0)
			(layer "B.SilkS")
			(hide yes)
			(effects
				(font
					(size 1.27 1.27)
				)
				(justify mirror)
			)
		)
		(property "Value" ""
			(at 0 0 0)
			(layer "B.Fab")
			(effects
				(font
					(size 1.27 1.27)
				)
				(justify mirror)
			)
		)
		(duplicate_pad_numbers_are_jumpers no)
		(fp_line
			(start 0.7874 0.4064)
			(end 0.7874 -0.4064)
			(stroke
				(width 0.1524)
				(type default)
			)
			(layer "B.SilkS")
		)
		(fp_line
			(start 0.7874 -0.4064)
			(end -0.7874 -0.4064)
			(stroke
				(width 0.1524)
				(type default)
			)
			(layer "B.SilkS")
		)
		(fp_line
			(start -0.7874 0.4064)
			(end 0.7874 0.4064)
			(stroke
				(width 0.1524)
				(type default)
			)
			(layer "B.SilkS")
		)
		(fp_line
			(start -0.7874 -0.4064)
			(end -0.7874 0.4064)
			(stroke
				(width 0.1524)
				(type default)
			)
			(layer "B.SilkS")
		)
		(fp_line
			(start 0.67945 0.3048)
			(end 0.67945 -0.305054)
			(stroke
				(width 0.1)
				(type default)
			)
			(layer "B.Fab")
		)
		(fp_line
			(start 0.67945 -0.305054)
			(end 0.12065 -0.305054)
			(stroke
				(width 0.1)
				(type default)
			)
			(layer "B.Fab")
		)
		(fp_line
			(start 0.12065 0.3048)
			(end 0.67945 0.3048)
			(stroke
				(width 0.1)
				(type default)
			)
			(layer "B.Fab")
		)
		(fp_line
			(start 0.12065 0.2794)
			(end 0.12065 0.3048)
			(stroke
				(width 0.1)
				(type default)
			)
			(layer "B.Fab")
		)
		(fp_line
			(start 0.12065 -0.2794)
			(end -0.12065 -0.2794)
			(stroke
				(width 0.1)
				(type default)
			)
			(layer "B.Fab")
		)
		(fp_line
			(start 0.12065 -0.305054)
			(end 0.12065 -0.2794)
			(stroke
				(width 0.1)
				(type default)
			)
			(layer "B.Fab")
		)
		(fp_line
			(start -0.120396 0.3048)
			(end -0.120396 0.2794)
			(stroke
				(width 0.1)
				(type default)
			)
			(layer "B.Fab")
		)
		(fp_line
			(start -0.120396 0.2794)
			(end 0.12065 0.2794)
			(stroke
				(width 0.1)
				(type default)
			)
			(layer "B.Fab")
		)
		(fp_line
			(start -0.12065 -0.2794)
			(end -0.12065 -0.3048)
			(stroke
				(width 0.1)
				(type default)
			)
			(layer "B.Fab")
		)
		(fp_line
			(start -0.12065 -0.3048)
			(end -0.67945 -0.3048)
			(stroke
				(width 0.1)
				(type default)
			)
			(layer "B.Fab")
		)
		(fp_line
			(start -0.67945 0.3048)
			(end -0.120396 0.3048)
			(stroke
				(width 0.1)
				(type default)
			)
			(layer "B.Fab")
		)
		(fp_line
			(start -0.67945 -0.3048)
			(end -0.67945 0.3048)
			(stroke
				(width 0.1)
				(type default)
			)
			(layer "B.Fab")
		)
		(pad "1" smd circle
			(at 0.40005 0)
			(size 0 0)
			(layers "B.Cu" "B.Mask" "B.Paste")
			(net "SMB_P52V_VPDB_SDA")
		)
		(pad "2" smd circle
			(at -0.40005 0)
			(size 0 0)
			(layers "B.Cu" "B.Mask" "B.Paste")
			(net "SMB_BRICK0_SDA")
		)
	)
	(footprint ""
		(layer "B.Cu")
		(at 230.759 -79.502 -90)
		(property "Reference" "U5"
			(at 0 -1.87833 270)
			(unlocked yes)
			(layer "B.SilkS")
			(effects
				(font
					(size 0.7874 0.5842)
					(thickness 0.1524)
				)
				(justify left mirror)
			)
		)
		(property "Value" ""
			(at 0 0 90)
			(layer "B.Fab")
			(effects
				(font
					(size 1.27 1.27)
				)
				(justify mirror)
			)
		)
		(duplicate_pad_numbers_are_jumpers no)
		(fp_line
			(start -1.400048 1.100074)
			(end 1.400048 1.100074)
			(stroke
				(width 0.1524)
				(type default)
			)
			(layer "B.SilkS")
		)
		(fp_line
			(start 1.400048 1.100074)
			(end 1.400048 -1.100074)
			(stroke
				(width 0.1524)
				(type default)
			)
			(layer "B.SilkS")
		)
		(fp_line
			(start -1.400048 -1.100074)
			(end -1.400048 1.100074)
			(stroke
				(width 0.1524)
				(type default)
			)
			(layer "B.SilkS")
		)
		(fp_line
			(start -1.400048 -1.100074)
			(end 1.400048 -1.100074)
			(stroke
				(width 0.1524)
				(type default)
			)
			(layer "B.SilkS")
		)
		(fp_poly
			(pts
				(xy 0.874014 -1.336548) (xy 0.366014 -2.352548) (xy 1.382014 -2.352548)
			)
			(stroke
				(width 0)
				(type default)
			)
			(fill yes)
			(layer "B.SilkS")
		)
		(fp_line
			(start -0.674878 1.100074)
			(end 0.674878 1.100074)
			(stroke
				(width 0.1)
				(type default)
			)
			(layer "B.Fab")
		)
		(fp_line
			(start 0.674878 1.100074)
			(end 0.674878 -1.100074)
			(stroke
				(width 0.1)
				(type default)
			)
			(layer "B.Fab")
		)
		(fp_line
			(start -0.674878 -1.100074)
			(end -0.674878 1.100074)
			(stroke
				(width 0.1)
				(type default)
			)
			(layer "B.Fab")
		)
		(fp_line
			(start 0.674878 -1.100074)
			(end -0.674878 -1.100074)
			(stroke
				(width 0.1)
				(type default)
			)
			(layer "B.Fab")
		)
		(fp_poly
			(pts
				(xy 1.590548 -0.649986) (xy 2.606548 -1.157986) (xy 2.606548 -0.141986)
			)
			(stroke
				(width 0)
				(type default)
			)
			(fill yes)
			(layer "B.Fab")
		)
		(pad "1" smd rect
			(at 0.94996 -0.649986 180)
			(size 0.4318 0.6096)
			(layers "B.Cu" "B.Mask" "B.Paste")
			(net "PWRGD_P3V3_AUX_MB_R1")
		)
		(pad "2" smd rect
			(at 0.94996 0 180)
			(size 0.4318 0.6096)
			(layers "B.Cu" "B.Mask" "B.Paste")
			(net "FM_U5_VCC")
		)
		(pad "3" smd rect
			(at 0.94996 0.649986 180)
			(size 0.4318 0.6096)
			(layers "B.Cu" "B.Mask" "B.Paste")
			(net "GND")
		)
		(pad "4" smd rect
			(at -0.94996 0.649986 180)
			(size 0.4318 0.6096)
			(layers "B.Cu" "B.Mask" "B.Paste")
			(net "PWRGD_P3V3_AUX_MB_BUF_R")
		)
		(pad "5" smd rect
			(at -0.94996 -0.649986 180)
			(size 0.4318 0.6096)
			(layers "B.Cu" "B.Mask" "B.Paste")
			(net "P3V3_AUX")
		)
	)
	(footprint ""
		(layer "B.Cu")
		(at 241.808 -95.504 90)
		(property "Reference" "C36"
			(at 0 0 90)
			(layer "B.SilkS")
			(hide yes)
			(effects
				(font
					(size 1.27 1.27)
				)
				(justify mirror)
			)
		)
		(property "Value" ""
			(at 0 0 90)
			(layer "B.Fab")
			(effects
				(font
					(size 1.27 1.27)
				)
				(justify mirror)
			)
		)
		(duplicate_pad_numbers_are_jumpers no)
		(fp_line
			(start 2.2098 -0.9398)
			(end -2.2098 -0.9398)
			(stroke
				(width 0.1524)
				(type default)
			)
			(layer "B.SilkS")
		)
		(fp_line
			(start -2.2098 -0.9398)
			(end -2.2098 0.9398)
			(stroke
				(width 0.1524)
				(type default)
			)
			(layer "B.SilkS")
		)
		(fp_line
			(start 2.2098 0.9398)
			(end 2.2098 -0.9398)
			(stroke
				(width 0.1524)
				(type default)
			)
			(layer "B.SilkS")
		)
		(fp_line
			(start -2.2098 0.9398)
			(end 2.2098 0.9398)
			(stroke
				(width 0.1524)
				(type default)
			)
			(layer "B.SilkS")
		)
		(fp_line
			(start 1.700022 -0.899922)
			(end -1.700022 -0.899922)
			(stroke
				(width 0.1)
				(type default)
			)
			(layer "B.Fab")
		)
		(fp_line
			(start -1.700022 -0.899922)
			(end -1.700022 0.899922)
			(stroke
				(width 0.1)
				(type default)
			)
			(layer "B.Fab")
		)
		(fp_line
			(start 1.700022 0.899922)
			(end 1.700022 -0.899922)
			(stroke
				(width 0.1)
				(type default)
			)
			(layer "B.Fab")
		)
		(fp_line
			(start -1.700022 0.899922)
			(end 1.700022 0.899922)
			(stroke
				(width 0.1)
				(type default)
			)
			(layer "B.Fab")
		)
		(pad "1" smd rect
			(at 1.4732 0 90)
			(size 1.1684 1.5748)
			(layers "B.Cu" "B.Mask" "B.Paste")
			(net "P52V_HS")
		)
		(pad "2" smd rect
			(at -1.4732 0 90)
			(size 1.1684 1.5748)
			(layers "B.Cu" "B.Mask" "B.Paste")
			(net "GND")
		)
	)
	(footprint ""
		(layer "B.Cu")
		(at 289.941 -29.464 -90)
		(property "Reference" "R5916"
			(at 0 0 90)
			(layer "B.SilkS")
			(hide yes)
			(effects
				(font
					(size 1.27 1.27)
				)
				(justify mirror)
			)
		)
		(property "Value" ""
			(at 0 0 90)
			(layer "B.Fab")
			(effects
				(font
					(size 1.27 1.27)
				)
				(justify mirror)
			)
		)
		(duplicate_pad_numbers_are_jumpers no)
		(fp_line
			(start -0.7874 0.4064)
			(end 0.7874 0.4064)
			(stroke
				(width 0.1524)
				(type default)
			)
			(layer "B.SilkS")
		)
		(fp_line
			(start 0.7874 0.4064)
			(end 0.7874 -0.4064)
			(stroke
				(width 0.1524)
				(type default)
			)
			(layer "B.SilkS")
		)
		(fp_line
			(start -0.7874 -0.4064)
			(end -0.7874 0.4064)
			(stroke
				(width 0.1524)
				(type default)
			)
			(layer "B.SilkS")
		)
		(fp_line
			(start 0.7874 -0.4064)
			(end -0.7874 -0.4064)
			(stroke
				(width 0.1524)
				(type default)
			)
			(layer "B.SilkS")
		)
		(fp_line
			(start -0.67945 0.3048)
			(end -0.120396 0.3048)
			(stroke
				(width 0.1)
				(type default)
			)
			(layer "B.Fab")
		)
		(fp_line
			(start -0.120396 0.3048)
			(end -0.120396 0.2794)
			(stroke
				(width 0.1)
				(type default)
			)
			(layer "B.Fab")
		)
		(fp_line
			(start 0.12065 0.3048)
			(end 0.67945 0.3048)
			(stroke
				(width 0.1)
				(type default)
			)
			(layer "B.Fab")
		)
		(fp_line
			(start 0.67945 0.3048)
			(end 0.67945 -0.305054)
			(stroke
				(width 0.1)
				(type default)
			)
			(layer "B.Fab")
		)
		(fp_line
			(start -0.120396 0.2794)
			(end 0.12065 0.2794)
			(stroke
				(width 0.1)
				(type default)
			)
			(layer "B.Fab")
		)
		(fp_line
			(start 0.12065 0.2794)
			(end 0.12065 0.3048)
			(stroke
				(width 0.1)
				(type default)
			)
			(layer "B.Fab")
		)
		(fp_line
			(start -0.12065 -0.2794)
			(end -0.12065 -0.3048)
			(stroke
				(width 0.1)
				(type default)
			)
			(layer "B.Fab")
		)
		(fp_line
			(start 0.12065 -0.2794)
			(end -0.12065 -0.2794)
			(stroke
				(width 0.1)
				(type default)
			)
			(layer "B.Fab")
		)
		(fp_line
			(start -0.67945 -0.3048)
			(end -0.67945 0.3048)
			(stroke
				(width 0.1)
				(type default)
			)
			(layer "B.Fab")
		)
		(fp_line
			(start -0.12065 -0.3048)
			(end -0.67945 -0.3048)
			(stroke
				(width 0.1)
				(type default)
			)
			(layer "B.Fab")
		)
		(fp_line
			(start 0.12065 -0.305054)
			(end 0.12065 -0.2794)
			(stroke
				(width 0.1)
				(type default)
			)
			(layer "B.Fab")
		)
		(fp_line
			(start 0.67945 -0.305054)
			(end 0.12065 -0.305054)
			(stroke
				(width 0.1)
				(type default)
			)
			(layer "B.Fab")
		)
		(pad "1" smd circle
			(at 0.40005 0 90)
			(size 0 0)
			(layers "B.Cu" "B.Mask" "B.Paste")
			(net "FM_AC_PWR_CYCLE_BUF")
		)
		(pad "2" smd circle
			(at -0.40005 0 90)
			(size 0 0)
			(layers "B.Cu" "B.Mask" "B.Paste")
			(net "GND")
		)
	)
	(footprint ""
		(layer "B.Cu")
		(at 273.685 -29.337 90)
		(property "Reference" "R5917"
			(at 0 0 90)
			(layer "B.SilkS")
			(hide yes)
			(effects
				(font
					(size 1.27 1.27)
				)
				(justify mirror)
			)
		)
		(property "Value" ""
			(at 0 0 90)
			(layer "B.Fab")
			(effects
				(font
					(size 1.27 1.27)
				)
				(justify mirror)
			)
		)
		(duplicate_pad_numbers_are_jumpers no)
		(fp_line
			(start 0.7874 -0.4064)
			(end -0.7874 -0.4064)
			(stroke
				(width 0.1524)
				(type default)
			)
			(layer "B.SilkS")
		)
		(fp_line
			(start -0.7874 -0.4064)
			(end -0.7874 0.4064)
			(stroke
				(width 0.1524)
				(type default)
			)
			(layer "B.SilkS")
		)
		(fp_line
			(start 0.7874 0.4064)
			(end 0.7874 -0.4064)
			(stroke
				(width 0.1524)
				(type default)
			)
			(layer "B.SilkS")
		)
		(fp_line
			(start -0.7874 0.4064)
			(end 0.7874 0.4064)
			(stroke
				(width 0.1524)
				(type default)
			)
			(layer "B.SilkS")
		)
		(fp_line
			(start 0.67945 -0.305054)
			(end 0.12065 -0.305054)
			(stroke
				(width 0.1)
				(type default)
			)
			(layer "B.Fab")
		)
		(fp_line
			(start 0.12065 -0.305054)
			(end 0.12065 -0.2794)
			(stroke
				(width 0.1)
				(type default)
			)
			(layer "B.Fab")
		)
		(fp_line
			(start -0.12065 -0.3048)
			(end -0.67945 -0.3048)
			(stroke
				(width 0.1)
				(type default)
			)
			(layer "B.Fab")
		)
		(fp_line
			(start -0.67945 -0.3048)
			(end -0.67945 0.3048)
			(stroke
				(width 0.1)
				(type default)
			)
			(layer "B.Fab")
		)
		(fp_line
			(start 0.12065 -0.2794)
			(end -0.12065 -0.2794)
			(stroke
				(width 0.1)
				(type default)
			)
			(layer "B.Fab")
		)
		(fp_line
			(start -0.12065 -0.2794)
			(end -0.12065 -0.3048)
			(stroke
				(width 0.1)
				(type default)
			)
			(layer "B.Fab")
		)
		(fp_line
			(start 0.12065 0.2794)
			(end 0.12065 0.3048)
			(stroke
				(width 0.1)
				(type default)
			)
			(layer "B.Fab")
		)
		(fp_line
			(start -0.120396 0.2794)
			(end 0.12065 0.2794)
			(stroke
				(width 0.1)
				(type default)
			)
			(layer "B.Fab")
		)
		(fp_line
			(start 0.67945 0.3048)
			(end 0.67945 -0.305054)
			(stroke
				(width 0.1)
				(type default)
			)
			(layer "B.Fab")
		)
		(fp_line
			(start 0.12065 0.3048)
			(end 0.67945 0.3048)
			(stroke
				(width 0.1)
				(type default)
			)
			(layer "B.Fab")
		)
		(fp_line
			(start -0.120396 0.3048)
			(end -0.120396 0.2794)
			(stroke
				(width 0.1)
				(type default)
			)
			(layer "B.Fab")
		)
		(fp_line
			(start -0.67945 0.3048)
			(end -0.120396 0.3048)
			(stroke
				(width 0.1)
				(type default)
			)
			(layer "B.Fab")
		)
		(pad "1" smd circle
			(at 0.40005 0 270)
			(size 0 0)
			(layers "B.Cu" "B.Mask" "B.Paste")
			(net "FM_AC_PWR_CYCLE_BUF")
		)
		(pad "2" smd circle
			(at -0.40005 0 270)
			(size 0 0)
			(layers "B.Cu" "B.Mask" "B.Paste")
			(net "FM_AC_PWR_CYCLE_R_BUF")
		)
	)
	(footprint ""
		(layer "B.Cu")
		(at 216.662 -91.059 90)
		(property "Reference" "C8"
			(at 0 0 90)
			(layer "B.SilkS")
			(hide yes)
			(effects
				(font
					(size 1.27 1.27)
				)
				(justify mirror)
			)
		)
		(property "Value" ""
			(at 0 0 90)
			(layer "B.Fab")
			(effects
				(font
					(size 1.27 1.27)
				)
				(justify mirror)
			)
		)
		(duplicate_pad_numbers_are_jumpers no)
		(fp_line
			(start 0.7874 -0.4064)
			(end -0.7874 -0.4064)
			(stroke
				(width 0.1524)
				(type default)
			)
			(layer "B.SilkS")
		)
		(fp_line
			(start -0.7874 -0.4064)
			(end -0.7874 0.4064)
			(stroke
				(width 0.1524)
				(type default)
			)
			(layer "B.SilkS")
		)
		(fp_line
			(start 0.7874 0.4064)
			(end 0.7874 -0.4064)
			(stroke
				(width 0.1524)
				(type default)
			)
			(layer "B.SilkS")
		)
		(fp_line
			(start -0.7874 0.4064)
			(end 0.7874 0.4064)
			(stroke
				(width 0.1524)
				(type default)
			)
			(layer "B.SilkS")
		)
		(fp_line
			(start 0.67945 -0.305054)
			(end 0.12065 -0.305054)
			(stroke
				(width 0.1)
				(type default)
			)
			(layer "B.Fab")
		)
		(fp_line
			(start 0.12065 -0.305054)
			(end 0.12065 -0.2794)
			(stroke
				(width 0.1)
				(type default)
			)
			(layer "B.Fab")
		)
		(fp_line
			(start -0.12065 -0.3048)
			(end -0.67945 -0.3048)
			(stroke
				(width 0.1)
				(type default)
			)
			(layer "B.Fab")
		)
		(fp_line
			(start -0.67945 -0.3048)
			(end -0.67945 0.3048)
			(stroke
				(width 0.1)
				(type default)
			)
			(layer "B.Fab")
		)
		(fp_line
			(start 0.12065 -0.2794)
			(end -0.12065 -0.2794)
			(stroke
				(width 0.1)
				(type default)
			)
			(layer "B.Fab")
		)
		(fp_line
			(start -0.12065 -0.2794)
			(end -0.12065 -0.3048)
			(stroke
				(width 0.1)
				(type default)
			)
			(layer "B.Fab")
		)
		(fp_line
			(start 0.12065 0.2794)
			(end 0.12065 0.3048)
			(stroke
				(width 0.1)
				(type default)
			)
			(layer "B.Fab")
		)
		(fp_line
			(start -0.120396 0.2794)
			(end 0.12065 0.2794)
			(stroke
				(width 0.1)
				(type default)
			)
			(layer "B.Fab")
		)
		(fp_line
			(start 0.67945 0.3048)
			(end 0.67945 -0.305054)
			(stroke
				(width 0.1)
				(type default)
			)
			(layer "B.Fab")
		)
		(fp_line
			(start 0.12065 0.3048)
			(end 0.67945 0.3048)
			(stroke
				(width 0.1)
				(type default)
			)
			(layer "B.Fab")
		)
		(fp_line
			(start -0.120396 0.3048)
			(end -0.120396 0.2794)
			(stroke
				(width 0.1)
				(type default)
			)
			(layer "B.Fab")
		)
		(fp_line
			(start -0.67945 0.3048)
			(end -0.120396 0.3048)
			(stroke
				(width 0.1)
				(type default)
			)
			(layer "B.Fab")
		)
		(pad "1" smd circle
			(at 0.40005 0 270)
			(size 0 0)
			(layers "B.Cu" "B.Mask" "B.Paste")
			(net "GND")
		)
		(pad "2" smd circle
			(at -0.40005 0 270)
			(size 0 0)
			(layers "B.Cu" "B.Mask" "B.Paste")
			(net "P3V3_AUX")
		)
	)
	(footprint ""
		(layer "B.Cu")
		(at 197.358 -93.853)
		(property "Reference" "R113"
			(at 0 0 0)
			(layer "B.SilkS")
			(hide yes)
			(effects
				(font
					(size 1.27 1.27)
				)
				(justify mirror)
			)
		)
		(property "Value" ""
			(at 0 0 0)
			(layer "B.Fab")
			(effects
				(font
					(size 1.27 1.27)
				)
				(justify mirror)
			)
		)
		(duplicate_pad_numbers_are_jumpers no)
		(fp_line
			(start -0.7874 -0.4064)
			(end -0.7874 0.4064)
			(stroke
				(width 0.1524)
				(type default)
			)
			(layer "B.SilkS")
		)
		(fp_line
			(start -0.7874 0.4064)
			(end 0.7874 0.4064)
			(stroke
				(width 0.1524)
				(type default)
			)
			(layer "B.SilkS")
		)
		(fp_line
			(start 0.7874 -0.4064)
			(end -0.7874 -0.4064)
			(stroke
				(width 0.1524)
				(type default)
			)
			(layer "B.SilkS")
		)
		(fp_line
			(start 0.7874 0.4064)
			(end 0.7874 -0.4064)
			(stroke
				(width 0.1524)
				(type default)
			)
			(layer "B.SilkS")
		)
		(fp_line
			(start -0.67945 -0.3048)
			(end -0.67945 0.3048)
			(stroke
				(width 0.1)
				(type default)
			)
			(layer "B.Fab")
		)
		(fp_line
			(start -0.67945 0.3048)
			(end -0.120396 0.3048)
			(stroke
				(width 0.1)
				(type default)
			)
			(layer "B.Fab")
		)
		(fp_line
			(start -0.12065 -0.3048)
			(end -0.67945 -0.3048)
			(stroke
				(width 0.1)
				(type default)
			)
			(layer "B.Fab")
		)
		(fp_line
			(start -0.12065 -0.2794)
			(end -0.12065 -0.3048)
			(stroke
				(width 0.1)
				(type default)
			)
			(layer "B.Fab")
		)
		(fp_line
			(start -0.120396 0.2794)
			(end 0.12065 0.2794)
			(stroke
				(width 0.1)
				(type default)
			)
			(layer "B.Fab")
		)
		(fp_line
			(start -0.120396 0.3048)
			(end -0.120396 0.2794)
			(stroke
				(width 0.1)
				(type default)
			)
			(layer "B.Fab")
		)
		(fp_line
			(start 0.12065 -0.305054)
			(end 0.12065 -0.2794)
			(stroke
				(width 0.1)
				(type default)
			)
			(layer "B.Fab")
		)
		(fp_line
			(start 0.12065 -0.2794)
			(end -0.12065 -0.2794)
			(stroke
				(width 0.1)
				(type default)
			)
			(layer "B.Fab")
		)
		(fp_line
			(start 0.12065 0.2794)
			(end 0.12065 0.3048)
			(stroke
				(width 0.1)
				(type default)
			)
			(layer "B.Fab")
		)
		(fp_line
			(start 0.12065 0.3048)
			(end 0.67945 0.3048)
			(stroke
				(width 0.1)
				(type default)
			)
			(layer "B.Fab")
		)
		(fp_line
			(start 0.67945 -0.305054)
			(end 0.12065 -0.305054)
			(stroke
				(width 0.1)
				(type default)
			)
			(layer "B.Fab")
		)
		(fp_line
			(start 0.67945 0.3048)
			(end 0.67945 -0.305054)
			(stroke
				(width 0.1)
				(type default)
			)
			(layer "B.Fab")
		)
		(pad "1" smd circle
			(at 0.40005 0 180)
			(size 0 0)
			(layers "B.Cu" "B.Mask" "B.Paste")
			(net "RST_SMB_PDB_BUF_N")
		)
		(pad "2" smd circle
			(at -0.40005 0 180)
			(size 0 0)
			(layers "B.Cu" "B.Mask" "B.Paste")
			(net "RST_SMB_PDB_BUF_R1_N")
		)
	)
	(footprint ""
		(layer "B.Cu")
		(at 56.642 -78.613)
		(property "Reference" "R182"
			(at 0 0 0)
			(layer "B.SilkS")
			(hide yes)
			(effects
				(font
					(size 1.27 1.27)
				)
				(justify mirror)
			)
		)
		(property "Value" ""
			(at 0 0 0)
			(layer "B.Fab")
			(effects
				(font
					(size 1.27 1.27)
				)
				(justify mirror)
			)
		)
		(duplicate_pad_numbers_are_jumpers no)
		(fp_line
			(start -0.7874 -0.4064)
			(end -0.7874 0.4064)
			(stroke
				(width 0.1524)
				(type default)
			)
			(layer "B.SilkS")
		)
		(fp_line
			(start -0.7874 0.4064)
			(end 0.7874 0.4064)
			(stroke
				(width 0.1524)
				(type default)
			)
			(layer "B.SilkS")
		)
		(fp_line
			(start 0.7874 -0.4064)
			(end -0.7874 -0.4064)
			(stroke
				(width 0.1524)
				(type default)
			)
			(layer "B.SilkS")
		)
		(fp_line
			(start 0.7874 0.4064)
			(end 0.7874 -0.4064)
			(stroke
				(width 0.1524)
				(type default)
			)
			(layer "B.SilkS")
		)
		(fp_line
			(start -0.67945 -0.3048)
			(end -0.67945 0.3048)
			(stroke
				(width 0.1)
				(type default)
			)
			(layer "B.Fab")
		)
		(fp_line
			(start -0.67945 0.3048)
			(end -0.120396 0.3048)
			(stroke
				(width 0.1)
				(type default)
			)
			(layer "B.Fab")
		)
		(fp_line
			(start -0.12065 -0.3048)
			(end -0.67945 -0.3048)
			(stroke
				(width 0.1)
				(type default)
			)
			(layer "B.Fab")
		)
		(fp_line
			(start -0.12065 -0.2794)
			(end -0.12065 -0.3048)
			(stroke
				(width 0.1)
				(type default)
			)
			(layer "B.Fab")
		)
		(fp_line
			(start -0.120396 0.2794)
			(end 0.12065 0.2794)
			(stroke
				(width 0.1)
				(type default)
			)
			(layer "B.Fab")
		)
		(fp_line
			(start -0.120396 0.3048)
			(end -0.120396 0.2794)
			(stroke
				(width 0.1)
				(type default)
			)
			(layer "B.Fab")
		)
		(fp_line
			(start 0.12065 -0.305054)
			(end 0.12065 -0.2794)
			(stroke
				(width 0.1)
				(type default)
			)
			(layer "B.Fab")
		)
		(fp_line
			(start 0.12065 -0.2794)
			(end -0.12065 -0.2794)
			(stroke
				(width 0.1)
				(type default)
			)
			(layer "B.Fab")
		)
		(fp_line
			(start 0.12065 0.2794)
			(end 0.12065 0.3048)
			(stroke
				(width 0.1)
				(type default)
			)
			(layer "B.Fab")
		)
		(fp_line
			(start 0.12065 0.3048)
			(end 0.67945 0.3048)
			(stroke
				(width 0.1)
				(type default)
			)
			(layer "B.Fab")
		)
		(fp_line
			(start 0.67945 -0.305054)
			(end 0.12065 -0.305054)
			(stroke
				(width 0.1)
				(type default)
			)
			(layer "B.Fab")
		)
		(fp_line
			(start 0.67945 0.3048)
			(end 0.67945 -0.305054)
			(stroke
				(width 0.1)
				(type default)
			)
			(layer "B.Fab")
		)
		(pad "1" smd circle
			(at 0.40005 0 180)
			(size 0 0)
			(layers "B.Cu" "B.Mask" "B.Paste")
			(net "P3V3_AUX")
		)
		(pad "2" smd circle
			(at -0.40005 0 180)
			(size 0 0)
			(layers "B.Cu" "B.Mask" "B.Paste")
			(net "P12V_BRICK3_ALERT_N")
		)
	)
	(footprint ""
		(layer "B.Cu")
		(at 174.493174 -76.327 180)
		(property "Reference" "R196"
			(at 0 0 0)
			(layer "B.SilkS")
			(hide yes)
			(effects
				(font
					(size 1.27 1.27)
				)
				(justify mirror)
			)
		)
		(property "Value" ""
			(at 0 0 0)
			(layer "B.Fab")
			(effects
				(font
					(size 1.27 1.27)
				)
				(justify mirror)
			)
		)
		(duplicate_pad_numbers_are_jumpers no)
		(fp_line
			(start 0.7874 0.4064)
			(end 0.7874 -0.4064)
			(stroke
				(width 0.1524)
				(type default)
			)
			(layer "B.SilkS")
		)
		(fp_line
			(start 0.7874 -0.4064)
			(end -0.7874 -0.4064)
			(stroke
				(width 0.1524)
				(type default)
			)
			(layer "B.SilkS")
		)
		(fp_line
			(start -0.7874 0.4064)
			(end 0.7874 0.4064)
			(stroke
				(width 0.1524)
				(type default)
			)
			(layer "B.SilkS")
		)
		(fp_line
			(start -0.7874 -0.4064)
			(end -0.7874 0.4064)
			(stroke
				(width 0.1524)
				(type default)
			)
			(layer "B.SilkS")
		)
		(fp_line
			(start 0.67945 0.3048)
			(end 0.67945 -0.305054)
			(stroke
				(width 0.1)
				(type default)
			)
			(layer "B.Fab")
		)
		(fp_line
			(start 0.67945 -0.305054)
			(end 0.12065 -0.305054)
			(stroke
				(width 0.1)
				(type default)
			)
			(layer "B.Fab")
		)
		(fp_line
			(start 0.12065 0.3048)
			(end 0.67945 0.3048)
			(stroke
				(width 0.1)
				(type default)
			)
			(layer "B.Fab")
		)
		(fp_line
			(start 0.12065 0.2794)
			(end 0.12065 0.3048)
			(stroke
				(width 0.1)
				(type default)
			)
			(layer "B.Fab")
		)
		(fp_line
			(start 0.12065 -0.2794)
			(end -0.12065 -0.2794)
			(stroke
				(width 0.1)
				(type default)
			)
			(layer "B.Fab")
		)
		(fp_line
			(start 0.12065 -0.305054)
			(end 0.12065 -0.2794)
			(stroke
				(width 0.1)
				(type default)
			)
			(layer "B.Fab")
		)
		(fp_line
			(start -0.120396 0.3048)
			(end -0.120396 0.2794)
			(stroke
				(width 0.1)
				(type default)
			)
			(layer "B.Fab")
		)
		(fp_line
			(start -0.120396 0.2794)
			(end 0.12065 0.2794)
			(stroke
				(width 0.1)
				(type default)
			)
			(layer "B.Fab")
		)
		(fp_line
			(start -0.12065 -0.2794)
			(end -0.12065 -0.3048)
			(stroke
				(width 0.1)
				(type default)
			)
			(layer "B.Fab")
		)
		(fp_line
			(start -0.12065 -0.3048)
			(end -0.67945 -0.3048)
			(stroke
				(width 0.1)
				(type default)
			)
			(layer "B.Fab")
		)
		(fp_line
			(start -0.67945 0.3048)
			(end -0.120396 0.3048)
			(stroke
				(width 0.1)
				(type default)
			)
			(layer "B.Fab")
		)
		(fp_line
			(start -0.67945 -0.3048)
			(end -0.67945 0.3048)
			(stroke
				(width 0.1)
				(type default)
			)
			(layer "B.Fab")
		)
		(pad "1" smd circle
			(at 0.40005 0)
			(size 0 0)
			(layers "B.Cu" "B.Mask" "B.Paste")
			(net "SMB_P52V_VPDB_SDA")
		)
		(pad "2" smd circle
			(at -0.40005 0)
			(size 0 0)
			(layers "B.Cu" "B.Mask" "B.Paste")
			(net "SMB_BRICK2_SDA")
		)
	)
	(footprint ""
		(layer "B.Cu")
		(at 37.397436 -59.960002 -90)
		(property "Reference" "C92"
			(at 0 0 90)
			(layer "B.SilkS")
			(hide yes)
			(effects
				(font
					(size 1.27 1.27)
				)
				(justify mirror)
			)
		)
		(property "Value" ""
			(at 0 0 90)
			(layer "B.Fab")
			(effects
				(font
					(size 1.27 1.27)
				)
				(justify mirror)
			)
		)
		(duplicate_pad_numbers_are_jumpers no)
		(fp_line
			(start -1.524 0.762)
			(end 1.524 0.762)
			(stroke
				(width 0.1524)
				(type default)
			)
			(layer "B.SilkS")
		)
		(fp_line
			(start 1.524 0.762)
			(end 1.524 -0.762)
			(stroke
				(width 0.1524)
				(type default)
			)
			(layer "B.SilkS")
		)
		(fp_line
			(start -1.524 -0.762)
			(end -1.524 0.762)
			(stroke
				(width 0.1524)
				(type default)
			)
			(layer "B.SilkS")
		)
		(fp_line
			(start 1.524 -0.762)
			(end -1.524 -0.762)
			(stroke
				(width 0.1524)
				(type default)
			)
			(layer "B.SilkS")
		)
		(fp_line
			(start -1.1049 0.724916)
			(end -1.1049 -0.724916)
			(stroke
				(width 0.1)
				(type default)
			)
			(layer "B.Fab")
		)
		(fp_line
			(start 1.1049 0.724916)
			(end -1.1049 0.724916)
			(stroke
				(width 0.1)
				(type default)
			)
			(layer "B.Fab")
		)
		(fp_line
			(start -1.1049 -0.724916)
			(end 1.1049 -0.724916)
			(stroke
				(width 0.1)
				(type default)
			)
			(layer "B.Fab")
		)
		(fp_line
			(start 1.1049 -0.724916)
			(end 1.1049 0.724916)
			(stroke
				(width 0.1)
				(type default)
			)
			(layer "B.Fab")
		)
		(pad "1" smd rect
			(at 0.889 0 270)
			(size 1.016 1.27)
			(layers "B.Cu" "B.Mask" "B.Paste")
			(net "P12V_HPDB")
		)
		(pad "2" smd rect
			(at -0.889 0 270)
			(size 1.016 1.27)
			(layers "B.Cu" "B.Mask" "B.Paste")
			(net "GND")
		)
	)
	(footprint ""
		(layer "B.Cu")
		(at 276.352 -38.862 -90)
		(property "Reference" "U40"
			(at 0.92837 1.6891 0)
			(unlocked yes)
			(layer "B.SilkS")
			(effects
				(font
					(size 0.7874 0.5842)
					(thickness 0.1524)
				)
				(justify left mirror)
			)
		)
		(property "Value" ""
			(at 0 0 90)
			(layer "B.Fab")
			(effects
				(font
					(size 1.27 1.27)
				)
				(justify mirror)
			)
		)
		(duplicate_pad_numbers_are_jumpers no)
		(fp_line
			(start -1.603248 1.500124)
			(end 1.603248 1.500124)
			(stroke
				(width 0.1524)
				(type default)
			)
			(layer "B.SilkS")
		)
		(fp_line
			(start 1.603248 1.500124)
			(end 1.603248 -1.500124)
			(stroke
				(width 0.1524)
				(type default)
			)
			(layer "B.SilkS")
		)
		(fp_line
			(start -1.603248 -1.500124)
			(end -1.603248 1.500124)
			(stroke
				(width 0.1524)
				(type default)
			)
			(layer "B.SilkS")
		)
		(fp_line
			(start 1.603248 -1.500124)
			(end -1.603248 -1.500124)
			(stroke
				(width 0.1524)
				(type default)
			)
			(layer "B.SilkS")
		)
		(fp_line
			(start -0.700024 1.500124)
			(end -0.700024 0.219964)
			(stroke
				(width 0.1)
				(type default)
			)
			(layer "B.Fab")
		)
		(fp_line
			(start 0.700024 1.500124)
			(end -0.700024 1.500124)
			(stroke
				(width 0.1)
				(type default)
			)
			(layer "B.Fab")
		)
		(fp_line
			(start 0.700024 1.169924)
			(end 0.700024 1.500124)
			(stroke
				(width 0.1)
				(type default)
			)
			(layer "B.Fab")
		)
		(fp_line
			(start 1.249934 1.169924)
			(end 0.700024 1.169924)
			(stroke
				(width 0.1)
				(type default)
			)
			(layer "B.Fab")
		)
		(fp_line
			(start 0.6985 0.729996)
			(end 1.249934 0.729996)
			(stroke
				(width 0.1)
				(type default)
			)
			(layer "B.Fab")
		)
		(fp_line
			(start 1.249934 0.729996)
			(end 1.249934 1.169924)
			(stroke
				(width 0.1)
				(type default)
			)
			(layer "B.Fab")
		)
		(fp_line
			(start -1.249934 0.219964)
			(end -1.249934 -0.219964)
			(stroke
				(width 0.1)
				(type default)
			)
			(layer "B.Fab")
		)
		(fp_line
			(start -0.700024 0.219964)
			(end -1.249934 0.219964)
			(stroke
				(width 0.1)
				(type default)
			)
			(layer "B.Fab")
		)
		(fp_line
			(start -1.249934 -0.219964)
			(end -0.700024 -0.219964)
			(stroke
				(width 0.1)
				(type default)
			)
			(layer "B.Fab")
		)
		(fp_line
			(start -0.700024 -0.219964)
			(end -0.700024 -1.500124)
			(stroke
				(width 0.1)
				(type default)
			)
			(layer "B.Fab")
		)
		(fp_line
			(start 0.6985 -0.729996)
			(end 0.6985 0.729996)
			(stroke
				(width 0.1)
				(type default)
			)
			(layer "B.Fab")
		)
		(fp_line
			(start 1.249934 -0.729996)
			(end 0.6985 -0.729996)
			(stroke
				(width 0.1)
				(type default)
			)
			(layer "B.Fab")
		)
		(fp_line
			(start 0.700024 -1.169924)
			(end 1.249934 -1.169924)
			(stroke
				(width 0.1)
				(type default)
			)
			(layer "B.Fab")
		)
		(fp_line
			(start 1.249934 -1.169924)
			(end 1.249934 -0.729996)
			(stroke
				(width 0.1)
				(type default)
			)
			(layer "B.Fab")
		)
		(fp_line
			(start -0.700024 -1.500124)
			(end 0.700024 -1.500124)
			(stroke
				(width 0.1)
				(type default)
			)
			(layer "B.Fab")
		)
		(fp_line
			(start 0.700024 -1.500124)
			(end 0.700024 -1.169924)
			(stroke
				(width 0.1)
				(type default)
			)
			(layer "B.Fab")
		)
		(fp_rect
			(start 0.700024 1.500124)
			(end -0.700024 -1.500124)
			(stroke
				(width 0)
				(type default)
			)
			(fill no)
			(layer "B.Fab")
		)
		(pad "D" smd rect
			(at -0.999998 0 180)
			(size 0.8128 0.9144)
			(layers "B.Cu" "B.Mask" "B.Paste")
			(net "P52V_HS1_EN_BUF_DELAY")
		)
		(pad "G" smd rect
			(at 0.999998 -0.94996 180)
			(size 0.8128 0.9144)
			(layers "B.Cu" "B.Mask" "B.Paste")
			(net "P52V_HS1_EN_DELAY_N")
		)
		(pad "S" smd rect
			(at 0.999998 0.94996 180)
			(size 0.8128 0.9144)
			(layers "B.Cu" "B.Mask" "B.Paste")
			(net "GND")
		)
	)
	(footprint ""
		(layer "B.Cu")
		(at 240.538 -70.993 -90)
		(property "Reference" "R65"
			(at 0 0 90)
			(layer "B.SilkS")
			(hide yes)
			(effects
				(font
					(size 1.27 1.27)
				)
				(justify mirror)
			)
		)
		(property "Value" ""
			(at 0 0 90)
			(layer "B.Fab")
			(effects
				(font
					(size 1.27 1.27)
				)
				(justify mirror)
			)
		)
		(duplicate_pad_numbers_are_jumpers no)
		(fp_line
			(start -0.7874 0.4064)
			(end 0.7874 0.4064)
			(stroke
				(width 0.1524)
				(type default)
			)
			(layer "B.SilkS")
		)
		(fp_line
			(start 0.7874 0.4064)
			(end 0.7874 -0.4064)
			(stroke
				(width 0.1524)
				(type default)
			)
			(layer "B.SilkS")
		)
		(fp_line
			(start -0.7874 -0.4064)
			(end -0.7874 0.4064)
			(stroke
				(width 0.1524)
				(type default)
			)
			(layer "B.SilkS")
		)
		(fp_line
			(start 0.7874 -0.4064)
			(end -0.7874 -0.4064)
			(stroke
				(width 0.1524)
				(type default)
			)
			(layer "B.SilkS")
		)
		(fp_line
			(start -0.67945 0.3048)
			(end -0.120396 0.3048)
			(stroke
				(width 0.1)
				(type default)
			)
			(layer "B.Fab")
		)
		(fp_line
			(start -0.120396 0.3048)
			(end -0.120396 0.2794)
			(stroke
				(width 0.1)
				(type default)
			)
			(layer "B.Fab")
		)
		(fp_line
			(start 0.12065 0.3048)
			(end 0.67945 0.3048)
			(stroke
				(width 0.1)
				(type default)
			)
			(layer "B.Fab")
		)
		(fp_line
			(start 0.67945 0.3048)
			(end 0.67945 -0.305054)
			(stroke
				(width 0.1)
				(type default)
			)
			(layer "B.Fab")
		)
		(fp_line
			(start -0.120396 0.2794)
			(end 0.12065 0.2794)
			(stroke
				(width 0.1)
				(type default)
			)
			(layer "B.Fab")
		)
		(fp_line
			(start 0.12065 0.2794)
			(end 0.12065 0.3048)
			(stroke
				(width 0.1)
				(type default)
			)
			(layer "B.Fab")
		)
		(fp_line
			(start -0.12065 -0.2794)
			(end -0.12065 -0.3048)
			(stroke
				(width 0.1)
				(type default)
			)
			(layer "B.Fab")
		)
		(fp_line
			(start 0.12065 -0.2794)
			(end -0.12065 -0.2794)
			(stroke
				(width 0.1)
				(type default)
			)
			(layer "B.Fab")
		)
		(fp_line
			(start -0.67945 -0.3048)
			(end -0.67945 0.3048)
			(stroke
				(width 0.1)
				(type default)
			)
			(layer "B.Fab")
		)
		(fp_line
			(start -0.12065 -0.3048)
			(end -0.67945 -0.3048)
			(stroke
				(width 0.1)
				(type default)
			)
			(layer "B.Fab")
		)
		(fp_line
			(start 0.12065 -0.305054)
			(end 0.12065 -0.2794)
			(stroke
				(width 0.1)
				(type default)
			)
			(layer "B.Fab")
		)
		(fp_line
			(start 0.67945 -0.305054)
			(end 0.12065 -0.305054)
			(stroke
				(width 0.1)
				(type default)
			)
			(layer "B.Fab")
		)
		(pad "1" smd circle
			(at 0.40005 0 90)
			(size 0 0)
			(layers "B.Cu" "B.Mask" "B.Paste")
			(net "SMB_MB_PDB_R_SCL")
		)
		(pad "2" smd circle
			(at -0.40005 0 90)
			(size 0 0)
			(layers "B.Cu" "B.Mask" "B.Paste")
			(net "SMB_MB_PDB_SCL")
		)
	)
	(footprint ""
		(layer "B.Cu")
		(at 202.946 -89.408 180)
		(property "Reference" "R100"
			(at 0 0 0)
			(layer "B.SilkS")
			(hide yes)
			(effects
				(font
					(size 1.27 1.27)
				)
				(justify mirror)
			)
		)
		(property "Value" ""
			(at 0 0 0)
			(layer "B.Fab")
			(effects
				(font
					(size 1.27 1.27)
				)
				(justify mirror)
			)
		)
		(duplicate_pad_numbers_are_jumpers no)
		(fp_line
			(start 0.7874 0.4064)
			(end 0.7874 -0.4064)
			(stroke
				(width 0.1524)
				(type default)
			)
			(layer "B.SilkS")
		)
		(fp_line
			(start 0.7874 -0.4064)
			(end -0.7874 -0.4064)
			(stroke
				(width 0.1524)
				(type default)
			)
			(layer "B.SilkS")
		)
		(fp_line
			(start -0.7874 0.4064)
			(end 0.7874 0.4064)
			(stroke
				(width 0.1524)
				(type default)
			)
			(layer "B.SilkS")
		)
		(fp_line
			(start -0.7874 -0.4064)
			(end -0.7874 0.4064)
			(stroke
				(width 0.1524)
				(type default)
			)
			(layer "B.SilkS")
		)
		(fp_line
			(start 0.67945 0.3048)
			(end 0.67945 -0.305054)
			(stroke
				(width 0.1)
				(type default)
			)
			(layer "B.Fab")
		)
		(fp_line
			(start 0.67945 -0.305054)
			(end 0.12065 -0.305054)
			(stroke
				(width 0.1)
				(type default)
			)
			(layer "B.Fab")
		)
		(fp_line
			(start 0.12065 0.3048)
			(end 0.67945 0.3048)
			(stroke
				(width 0.1)
				(type default)
			)
			(layer "B.Fab")
		)
		(fp_line
			(start 0.12065 0.2794)
			(end 0.12065 0.3048)
			(stroke
				(width 0.1)
				(type default)
			)
			(layer "B.Fab")
		)
		(fp_line
			(start 0.12065 -0.2794)
			(end -0.12065 -0.2794)
			(stroke
				(width 0.1)
				(type default)
			)
			(layer "B.Fab")
		)
		(fp_line
			(start 0.12065 -0.305054)
			(end 0.12065 -0.2794)
			(stroke
				(width 0.1)
				(type default)
			)
			(layer "B.Fab")
		)
		(fp_line
			(start -0.120396 0.3048)
			(end -0.120396 0.2794)
			(stroke
				(width 0.1)
				(type default)
			)
			(layer "B.Fab")
		)
		(fp_line
			(start -0.120396 0.2794)
			(end 0.12065 0.2794)
			(stroke
				(width 0.1)
				(type default)
			)
			(layer "B.Fab")
		)
		(fp_line
			(start -0.12065 -0.2794)
			(end -0.12065 -0.3048)
			(stroke
				(width 0.1)
				(type default)
			)
			(layer "B.Fab")
		)
		(fp_line
			(start -0.12065 -0.3048)
			(end -0.67945 -0.3048)
			(stroke
				(width 0.1)
				(type default)
			)
			(layer "B.Fab")
		)
		(fp_line
			(start -0.67945 0.3048)
			(end -0.120396 0.3048)
			(stroke
				(width 0.1)
				(type default)
			)
			(layer "B.Fab")
		)
		(fp_line
			(start -0.67945 -0.3048)
			(end -0.67945 0.3048)
			(stroke
				(width 0.1)
				(type default)
			)
			(layer "B.Fab")
		)
		(pad "1" smd circle
			(at 0.40005 0)
			(size 0 0)
			(layers "B.Cu" "B.Mask" "B.Paste")
			(net "PU_9543_0_INT0")
		)
		(pad "2" smd circle
			(at -0.40005 0)
			(size 0 0)
			(layers "B.Cu" "B.Mask" "B.Paste")
			(net "P3V3_AUX")
		)
	)
	(footprint ""
		(layer "B.Cu")
		(at 291.719 -35.052)
		(property "Reference" "U36"
			(at -2.57937 1.1049 270)
			(unlocked yes)
			(layer "B.SilkS")
			(effects
				(font
					(size 0.7874 0.5842)
					(thickness 0.1524)
				)
				(justify left mirror)
			)
		)
		(property "Value" ""
			(at 0 0 0)
			(layer "B.Fab")
			(effects
				(font
					(size 1.27 1.27)
				)
				(justify mirror)
			)
		)
		(duplicate_pad_numbers_are_jumpers no)
		(fp_line
			(start -1.603248 -1.500124)
			(end -1.603248 1.500124)
			(stroke
				(width 0.1524)
				(type default)
			)
			(layer "B.SilkS")
		)
		(fp_line
			(start -1.603248 1.500124)
			(end 1.603248 1.500124)
			(stroke
				(width 0.1524)
				(type default)
			)
			(layer "B.SilkS")
		)
		(fp_line
			(start 1.603248 -1.500124)
			(end -1.603248 -1.500124)
			(stroke
				(width 0.1524)
				(type default)
			)
			(layer "B.SilkS")
		)
		(fp_line
			(start 1.603248 1.500124)
			(end 1.603248 -1.500124)
			(stroke
				(width 0.1524)
				(type default)
			)
			(layer "B.SilkS")
		)
		(fp_line
			(start -1.249934 -0.219964)
			(end -0.700024 -0.219964)
			(stroke
				(width 0.1)
				(type default)
			)
			(layer "B.Fab")
		)
		(fp_line
			(start -1.249934 0.219964)
			(end -1.249934 -0.219964)
			(stroke
				(width 0.1)
				(type default)
			)
			(layer "B.Fab")
		)
		(fp_line
			(start -0.700024 -1.500124)
			(end 0.700024 -1.500124)
			(stroke
				(width 0.1)
				(type default)
			)
			(layer "B.Fab")
		)
		(fp_line
			(start -0.700024 -0.219964)
			(end -0.700024 -1.500124)
			(stroke
				(width 0.1)
				(type default)
			)
			(layer "B.Fab")
		)
		(fp_line
			(start -0.700024 0.219964)
			(end -1.249934 0.219964)
			(stroke
				(width 0.1)
				(type default)
			)
			(layer "B.Fab")
		)
		(fp_line
			(start -0.700024 1.500124)
			(end -0.700024 0.219964)
			(stroke
				(width 0.1)
				(type default)
			)
			(layer "B.Fab")
		)
		(fp_line
			(start 0.6985 -0.729996)
			(end 0.6985 0.729996)
			(stroke
				(width 0.1)
				(type default)
			)
			(layer "B.Fab")
		)
		(fp_line
			(start 0.6985 0.729996)
			(end 1.249934 0.729996)
			(stroke
				(width 0.1)
				(type default)
			)
			(layer "B.Fab")
		)
		(fp_line
			(start 0.700024 -1.500124)
			(end 0.700024 -1.169924)
			(stroke
				(width 0.1)
				(type default)
			)
			(layer "B.Fab")
		)
		(fp_line
			(start 0.700024 -1.169924)
			(end 1.249934 -1.169924)
			(stroke
				(width 0.1)
				(type default)
			)
			(layer "B.Fab")
		)
		(fp_line
			(start 0.700024 1.169924)
			(end 0.700024 1.500124)
			(stroke
				(width 0.1)
				(type default)
			)
			(layer "B.Fab")
		)
		(fp_line
			(start 0.700024 1.500124)
			(end -0.700024 1.500124)
			(stroke
				(width 0.1)
				(type default)
			)
			(layer "B.Fab")
		)
		(fp_line
			(start 1.249934 -1.169924)
			(end 1.249934 -0.729996)
			(stroke
				(width 0.1)
				(type default)
			)
			(layer "B.Fab")
		)
		(fp_line
			(start 1.249934 -0.729996)
			(end 0.6985 -0.729996)
			(stroke
				(width 0.1)
				(type default)
			)
			(layer "B.Fab")
		)
		(fp_line
			(start 1.249934 0.729996)
			(end 1.249934 1.169924)
			(stroke
				(width 0.1)
				(type default)
			)
			(layer "B.Fab")
		)
		(fp_line
			(start 1.249934 1.169924)
			(end 0.700024 1.169924)
			(stroke
				(width 0.1)
				(type default)
			)
			(layer "B.Fab")
		)
		(fp_rect
			(start 0.700024 1.500124)
			(end -0.700024 -1.500124)
			(stroke
				(width 0)
				(type default)
			)
			(fill no)
			(layer "B.Fab")
		)
		(pad "D" smd rect
			(at -0.999998 0 270)
			(size 0.8128 0.9144)
			(layers "B.Cu" "B.Mask" "B.Paste")
			(net "FM_AC_PWR_CYCLE_BUF")
		)
		(pad "G" smd rect
			(at 0.999998 -0.94996 270)
			(size 0.8128 0.9144)
			(layers "B.Cu" "B.Mask" "B.Paste")
			(net "FM_AC_PWR_CYCLE_R1_N")
		)
		(pad "S" smd rect
			(at 0.999998 0.94996 270)
			(size 0.8128 0.9144)
			(layers "B.Cu" "B.Mask" "B.Paste")
			(net "GND")
		)
	)
	(footprint ""
		(layer "B.Cu")
		(at 96.849946 -114.046 90)
		(property "Reference" "C56"
			(at 0 0 90)
			(layer "B.SilkS")
			(hide yes)
			(effects
				(font
					(size 1.27 1.27)
				)
				(justify mirror)
			)
		)
		(property "Value" ""
			(at 0 0 90)
			(layer "B.Fab")
			(effects
				(font
					(size 1.27 1.27)
				)
				(justify mirror)
			)
		)
		(duplicate_pad_numbers_are_jumpers no)
		(fp_line
			(start 0.7874 -0.4064)
			(end -0.7874 -0.4064)
			(stroke
				(width 0.1524)
				(type default)
			)
			(layer "B.SilkS")
		)
		(fp_line
			(start -0.7874 -0.4064)
			(end -0.7874 0.4064)
			(stroke
				(width 0.1524)
				(type default)
			)
			(layer "B.SilkS")
		)
		(fp_line
			(start 0.7874 0.4064)
			(end 0.7874 -0.4064)
			(stroke
				(width 0.1524)
				(type default)
			)
			(layer "B.SilkS")
		)
		(fp_line
			(start -0.7874 0.4064)
			(end 0.7874 0.4064)
			(stroke
				(width 0.1524)
				(type default)
			)
			(layer "B.SilkS")
		)
		(fp_line
			(start 0.67945 -0.305054)
			(end 0.12065 -0.305054)
			(stroke
				(width 0.1)
				(type default)
			)
			(layer "B.Fab")
		)
		(fp_line
			(start 0.12065 -0.305054)
			(end 0.12065 -0.2794)
			(stroke
				(width 0.1)
				(type default)
			)
			(layer "B.Fab")
		)
		(fp_line
			(start -0.12065 -0.3048)
			(end -0.67945 -0.3048)
			(stroke
				(width 0.1)
				(type default)
			)
			(layer "B.Fab")
		)
		(fp_line
			(start -0.67945 -0.3048)
			(end -0.67945 0.3048)
			(stroke
				(width 0.1)
				(type default)
			)
			(layer "B.Fab")
		)
		(fp_line
			(start 0.12065 -0.2794)
			(end -0.12065 -0.2794)
			(stroke
				(width 0.1)
				(type default)
			)
			(layer "B.Fab")
		)
		(fp_line
			(start -0.12065 -0.2794)
			(end -0.12065 -0.3048)
			(stroke
				(width 0.1)
				(type default)
			)
			(layer "B.Fab")
		)
		(fp_line
			(start 0.12065 0.2794)
			(end 0.12065 0.3048)
			(stroke
				(width 0.1)
				(type default)
			)
			(layer "B.Fab")
		)
		(fp_line
			(start -0.120396 0.2794)
			(end 0.12065 0.2794)
			(stroke
				(width 0.1)
				(type default)
			)
			(layer "B.Fab")
		)
		(fp_line
			(start 0.67945 0.3048)
			(end 0.67945 -0.305054)
			(stroke
				(width 0.1)
				(type default)
			)
			(layer "B.Fab")
		)
		(fp_line
			(start 0.12065 0.3048)
			(end 0.67945 0.3048)
			(stroke
				(width 0.1)
				(type default)
			)
			(layer "B.Fab")
		)
		(fp_line
			(start -0.120396 0.3048)
			(end -0.120396 0.2794)
			(stroke
				(width 0.1)
				(type default)
			)
			(layer "B.Fab")
		)
		(fp_line
			(start -0.67945 0.3048)
			(end -0.120396 0.3048)
			(stroke
				(width 0.1)
				(type default)
			)
			(layer "B.Fab")
		)
		(pad "1" smd circle
			(at 0.40005 0 270)
			(size 0 0)
			(layers "B.Cu" "B.Mask" "B.Paste")
			(net "BRICK_P12V_1_EN_N")
		)
		(pad "2" smd circle
			(at -0.40005 0 270)
			(size 0 0)
			(layers "B.Cu" "B.Mask" "B.Paste")
			(net "GND")
		)
	)
	(footprint ""
		(layer "B.Cu")
		(at 220.98 -78.359 -90)
		(property "Reference" "R38"
			(at 0 0 90)
			(layer "B.SilkS")
			(hide yes)
			(effects
				(font
					(size 1.27 1.27)
				)
				(justify mirror)
			)
		)
		(property "Value" ""
			(at 0 0 90)
			(layer "B.Fab")
			(effects
				(font
					(size 1.27 1.27)
				)
				(justify mirror)
			)
		)
		(duplicate_pad_numbers_are_jumpers no)
		(fp_line
			(start -0.7874 0.4064)
			(end 0.7874 0.4064)
			(stroke
				(width 0.1524)
				(type default)
			)
			(layer "B.SilkS")
		)
		(fp_line
			(start 0.7874 0.4064)
			(end 0.7874 -0.4064)
			(stroke
				(width 0.1524)
				(type default)
			)
			(layer "B.SilkS")
		)
		(fp_line
			(start -0.7874 -0.4064)
			(end -0.7874 0.4064)
			(stroke
				(width 0.1524)
				(type default)
			)
			(layer "B.SilkS")
		)
		(fp_line
			(start 0.7874 -0.4064)
			(end -0.7874 -0.4064)
			(stroke
				(width 0.1524)
				(type default)
			)
			(layer "B.SilkS")
		)
		(fp_line
			(start -0.67945 0.3048)
			(end -0.120396 0.3048)
			(stroke
				(width 0.1)
				(type default)
			)
			(layer "B.Fab")
		)
		(fp_line
			(start -0.120396 0.3048)
			(end -0.120396 0.2794)
			(stroke
				(width 0.1)
				(type default)
			)
			(layer "B.Fab")
		)
		(fp_line
			(start 0.12065 0.3048)
			(end 0.67945 0.3048)
			(stroke
				(width 0.1)
				(type default)
			)
			(layer "B.Fab")
		)
		(fp_line
			(start 0.67945 0.3048)
			(end 0.67945 -0.305054)
			(stroke
				(width 0.1)
				(type default)
			)
			(layer "B.Fab")
		)
		(fp_line
			(start -0.120396 0.2794)
			(end 0.12065 0.2794)
			(stroke
				(width 0.1)
				(type default)
			)
			(layer "B.Fab")
		)
		(fp_line
			(start 0.12065 0.2794)
			(end 0.12065 0.3048)
			(stroke
				(width 0.1)
				(type default)
			)
			(layer "B.Fab")
		)
		(fp_line
			(start -0.12065 -0.2794)
			(end -0.12065 -0.3048)
			(stroke
				(width 0.1)
				(type default)
			)
			(layer "B.Fab")
		)
		(fp_line
			(start 0.12065 -0.2794)
			(end -0.12065 -0.2794)
			(stroke
				(width 0.1)
				(type default)
			)
			(layer "B.Fab")
		)
		(fp_line
			(start -0.67945 -0.3048)
			(end -0.67945 0.3048)
			(stroke
				(width 0.1)
				(type default)
			)
			(layer "B.Fab")
		)
		(fp_line
			(start -0.12065 -0.3048)
			(end -0.67945 -0.3048)
			(stroke
				(width 0.1)
				(type default)
			)
			(layer "B.Fab")
		)
		(fp_line
			(start 0.12065 -0.305054)
			(end 0.12065 -0.2794)
			(stroke
				(width 0.1)
				(type default)
			)
			(layer "B.Fab")
		)
		(fp_line
			(start 0.67945 -0.305054)
			(end 0.12065 -0.305054)
			(stroke
				(width 0.1)
				(type default)
			)
			(layer "B.Fab")
		)
		(pad "1" smd circle
			(at 0.40005 0 90)
			(size 0 0)
			(layers "B.Cu" "B.Mask" "B.Paste")
			(net "P3V3_AUX")
		)
		(pad "2" smd circle
			(at -0.40005 0 90)
			(size 0 0)
			(layers "B.Cu" "B.Mask" "B.Paste")
			(net "FRU_ADDR2")
		)
	)
	(footprint ""
		(layer "B.Cu")
		(at 202.946 -90.678)
		(property "Reference" "R102"
			(at 0 0 0)
			(layer "B.SilkS")
			(hide yes)
			(effects
				(font
					(size 1.27 1.27)
				)
				(justify mirror)
			)
		)
		(property "Value" ""
			(at 0 0 0)
			(layer "B.Fab")
			(effects
				(font
					(size 1.27 1.27)
				)
				(justify mirror)
			)
		)
		(duplicate_pad_numbers_are_jumpers no)
		(fp_line
			(start -0.7874 -0.4064)
			(end -0.7874 0.4064)
			(stroke
				(width 0.1524)
				(type default)
			)
			(layer "B.SilkS")
		)
		(fp_line
			(start -0.7874 0.4064)
			(end 0.7874 0.4064)
			(stroke
				(width 0.1524)
				(type default)
			)
			(layer "B.SilkS")
		)
		(fp_line
			(start 0.7874 -0.4064)
			(end -0.7874 -0.4064)
			(stroke
				(width 0.1524)
				(type default)
			)
			(layer "B.SilkS")
		)
		(fp_line
			(start 0.7874 0.4064)
			(end 0.7874 -0.4064)
			(stroke
				(width 0.1524)
				(type default)
			)
			(layer "B.SilkS")
		)
		(fp_line
			(start -0.67945 -0.3048)
			(end -0.67945 0.3048)
			(stroke
				(width 0.1)
				(type default)
			)
			(layer "B.Fab")
		)
		(fp_line
			(start -0.67945 0.3048)
			(end -0.120396 0.3048)
			(stroke
				(width 0.1)
				(type default)
			)
			(layer "B.Fab")
		)
		(fp_line
			(start -0.12065 -0.3048)
			(end -0.67945 -0.3048)
			(stroke
				(width 0.1)
				(type default)
			)
			(layer "B.Fab")
		)
		(fp_line
			(start -0.12065 -0.2794)
			(end -0.12065 -0.3048)
			(stroke
				(width 0.1)
				(type default)
			)
			(layer "B.Fab")
		)
		(fp_line
			(start -0.120396 0.2794)
			(end 0.12065 0.2794)
			(stroke
				(width 0.1)
				(type default)
			)
			(layer "B.Fab")
		)
		(fp_line
			(start -0.120396 0.3048)
			(end -0.120396 0.2794)
			(stroke
				(width 0.1)
				(type default)
			)
			(layer "B.Fab")
		)
		(fp_line
			(start 0.12065 -0.305054)
			(end 0.12065 -0.2794)
			(stroke
				(width 0.1)
				(type default)
			)
			(layer "B.Fab")
		)
		(fp_line
			(start 0.12065 -0.2794)
			(end -0.12065 -0.2794)
			(stroke
				(width 0.1)
				(type default)
			)
			(layer "B.Fab")
		)
		(fp_line
			(start 0.12065 0.2794)
			(end 0.12065 0.3048)
			(stroke
				(width 0.1)
				(type default)
			)
			(layer "B.Fab")
		)
		(fp_line
			(start 0.12065 0.3048)
			(end 0.67945 0.3048)
			(stroke
				(width 0.1)
				(type default)
			)
			(layer "B.Fab")
		)
		(fp_line
			(start 0.67945 -0.305054)
			(end 0.12065 -0.305054)
			(stroke
				(width 0.1)
				(type default)
			)
			(layer "B.Fab")
		)
		(fp_line
			(start 0.67945 0.3048)
			(end 0.67945 -0.305054)
			(stroke
				(width 0.1)
				(type default)
			)
			(layer "B.Fab")
		)
		(pad "1" smd circle
			(at 0.40005 0 180)
			(size 0 0)
			(layers "B.Cu" "B.Mask" "B.Paste")
			(net "P3V3_AUX")
		)
		(pad "2" smd circle
			(at -0.40005 0 180)
			(size 0 0)
			(layers "B.Cu" "B.Mask" "B.Paste")
			(net "PCA9543_MISC_A1")
		)
	)
	(footprint ""
		(layer "B.Cu")
		(at 276.733 -41.656)
		(property "Reference" "PC12"
			(at 0 0 0)
			(layer "B.SilkS")
			(hide yes)
			(effects
				(font
					(size 1.27 1.27)
				)
				(justify mirror)
			)
		)
		(property "Value" ""
			(at 0 0 0)
			(layer "B.Fab")
			(effects
				(font
					(size 1.27 1.27)
				)
				(justify mirror)
			)
		)
		(duplicate_pad_numbers_are_jumpers no)
		(fp_line
			(start -0.7874 -0.4064)
			(end -0.7874 0.4064)
			(stroke
				(width 0.1524)
				(type default)
			)
			(layer "B.SilkS")
		)
		(fp_line
			(start -0.7874 0.4064)
			(end 0.7874 0.4064)
			(stroke
				(width 0.1524)
				(type default)
			)
			(layer "B.SilkS")
		)
		(fp_line
			(start 0.7874 -0.4064)
			(end -0.7874 -0.4064)
			(stroke
				(width 0.1524)
				(type default)
			)
			(layer "B.SilkS")
		)
		(fp_line
			(start 0.7874 0.4064)
			(end 0.7874 -0.4064)
			(stroke
				(width 0.1524)
				(type default)
			)
			(layer "B.SilkS")
		)
		(fp_line
			(start -0.67945 -0.3048)
			(end -0.67945 0.3048)
			(stroke
				(width 0.1)
				(type default)
			)
			(layer "B.Fab")
		)
		(fp_line
			(start -0.67945 0.3048)
			(end -0.120396 0.3048)
			(stroke
				(width 0.1)
				(type default)
			)
			(layer "B.Fab")
		)
		(fp_line
			(start -0.12065 -0.3048)
			(end -0.67945 -0.3048)
			(stroke
				(width 0.1)
				(type default)
			)
			(layer "B.Fab")
		)
		(fp_line
			(start -0.12065 -0.2794)
			(end -0.12065 -0.3048)
			(stroke
				(width 0.1)
				(type default)
			)
			(layer "B.Fab")
		)
		(fp_line
			(start -0.120396 0.2794)
			(end 0.12065 0.2794)
			(stroke
				(width 0.1)
				(type default)
			)
			(layer "B.Fab")
		)
		(fp_line
			(start -0.120396 0.3048)
			(end -0.120396 0.2794)
			(stroke
				(width 0.1)
				(type default)
			)
			(layer "B.Fab")
		)
		(fp_line
			(start 0.12065 -0.305054)
			(end 0.12065 -0.2794)
			(stroke
				(width 0.1)
				(type default)
			)
			(layer "B.Fab")
		)
		(fp_line
			(start 0.12065 -0.2794)
			(end -0.12065 -0.2794)
			(stroke
				(width 0.1)
				(type default)
			)
			(layer "B.Fab")
		)
		(fp_line
			(start 0.12065 0.2794)
			(end 0.12065 0.3048)
			(stroke
				(width 0.1)
				(type default)
			)
			(layer "B.Fab")
		)
		(fp_line
			(start 0.12065 0.3048)
			(end 0.67945 0.3048)
			(stroke
				(width 0.1)
				(type default)
			)
			(layer "B.Fab")
		)
		(fp_line
			(start 0.67945 -0.305054)
			(end 0.12065 -0.305054)
			(stroke
				(width 0.1)
				(type default)
			)
			(layer "B.Fab")
		)
		(fp_line
			(start 0.67945 0.3048)
			(end 0.67945 -0.305054)
			(stroke
				(width 0.1)
				(type default)
			)
			(layer "B.Fab")
		)
		(pad "1" smd circle
			(at 0.40005 0 180)
			(size 0 0)
			(layers "B.Cu" "B.Mask" "B.Paste")
			(net "P52V_HS1_EFAULT")
		)
		(pad "2" smd circle
			(at -0.40005 0 180)
			(size 0 0)
			(layers "B.Cu" "B.Mask" "B.Paste")
			(net "GND_FIELD_SIGNAL")
		)
	)
	(footprint ""
		(layer "B.Cu")
		(at 208.661 -90.551 -90)
		(property "Reference" "R30"
			(at 0 0 90)
			(layer "B.SilkS")
			(hide yes)
			(effects
				(font
					(size 1.27 1.27)
				)
				(justify mirror)
			)
		)
		(property "Value" ""
			(at 0 0 90)
			(layer "B.Fab")
			(effects
				(font
					(size 1.27 1.27)
				)
				(justify mirror)
			)
		)
		(duplicate_pad_numbers_are_jumpers no)
		(fp_line
			(start -0.7874 0.4064)
			(end 0.7874 0.4064)
			(stroke
				(width 0.1524)
				(type default)
			)
			(layer "B.SilkS")
		)
		(fp_line
			(start 0.7874 0.4064)
			(end 0.7874 -0.4064)
			(stroke
				(width 0.1524)
				(type default)
			)
			(layer "B.SilkS")
		)
		(fp_line
			(start -0.7874 -0.4064)
			(end -0.7874 0.4064)
			(stroke
				(width 0.1524)
				(type default)
			)
			(layer "B.SilkS")
		)
		(fp_line
			(start 0.7874 -0.4064)
			(end -0.7874 -0.4064)
			(stroke
				(width 0.1524)
				(type default)
			)
			(layer "B.SilkS")
		)
		(fp_line
			(start -0.67945 0.3048)
			(end -0.120396 0.3048)
			(stroke
				(width 0.1)
				(type default)
			)
			(layer "B.Fab")
		)
		(fp_line
			(start -0.120396 0.3048)
			(end -0.120396 0.2794)
			(stroke
				(width 0.1)
				(type default)
			)
			(layer "B.Fab")
		)
		(fp_line
			(start 0.12065 0.3048)
			(end 0.67945 0.3048)
			(stroke
				(width 0.1)
				(type default)
			)
			(layer "B.Fab")
		)
		(fp_line
			(start 0.67945 0.3048)
			(end 0.67945 -0.305054)
			(stroke
				(width 0.1)
				(type default)
			)
			(layer "B.Fab")
		)
		(fp_line
			(start -0.120396 0.2794)
			(end 0.12065 0.2794)
			(stroke
				(width 0.1)
				(type default)
			)
			(layer "B.Fab")
		)
		(fp_line
			(start 0.12065 0.2794)
			(end 0.12065 0.3048)
			(stroke
				(width 0.1)
				(type default)
			)
			(layer "B.Fab")
		)
		(fp_line
			(start -0.12065 -0.2794)
			(end -0.12065 -0.3048)
			(stroke
				(width 0.1)
				(type default)
			)
			(layer "B.Fab")
		)
		(fp_line
			(start 0.12065 -0.2794)
			(end -0.12065 -0.2794)
			(stroke
				(width 0.1)
				(type default)
			)
			(layer "B.Fab")
		)
		(fp_line
			(start -0.67945 -0.3048)
			(end -0.67945 0.3048)
			(stroke
				(width 0.1)
				(type default)
			)
			(layer "B.Fab")
		)
		(fp_line
			(start -0.12065 -0.3048)
			(end -0.67945 -0.3048)
			(stroke
				(width 0.1)
				(type default)
			)
			(layer "B.Fab")
		)
		(fp_line
			(start 0.12065 -0.305054)
			(end 0.12065 -0.2794)
			(stroke
				(width 0.1)
				(type default)
			)
			(layer "B.Fab")
		)
		(fp_line
			(start 0.67945 -0.305054)
			(end 0.12065 -0.305054)
			(stroke
				(width 0.1)
				(type default)
			)
			(layer "B.Fab")
		)
		(pad "1" smd circle
			(at 0.40005 0 90)
			(size 0 0)
			(layers "B.Cu" "B.Mask" "B.Paste")
			(net "PWRGD_GPU_HSC_BUF")
		)
		(pad "2" smd circle
			(at -0.40005 0 90)
			(size 0 0)
			(layers "B.Cu" "B.Mask" "B.Paste")
			(net "PWRGD_GPU_HSC_BUF_R")
		)
	)
	(footprint ""
		(layer "B.Cu")
		(at 279.908 -46.609 180)
		(property "Reference" "R157"
			(at 0 0 0)
			(layer "B.SilkS")
			(hide yes)
			(effects
				(font
					(size 1.27 1.27)
				)
				(justify mirror)
			)
		)
		(property "Value" ""
			(at 0 0 0)
			(layer "B.Fab")
			(effects
				(font
					(size 1.27 1.27)
				)
				(justify mirror)
			)
		)
		(duplicate_pad_numbers_are_jumpers no)
		(fp_line
			(start 0.7874 0.4064)
			(end 0.7874 -0.4064)
			(stroke
				(width 0.1524)
				(type default)
			)
			(layer "B.SilkS")
		)
		(fp_line
			(start 0.7874 -0.4064)
			(end -0.7874 -0.4064)
			(stroke
				(width 0.1524)
				(type default)
			)
			(layer "B.SilkS")
		)
		(fp_line
			(start -0.7874 0.4064)
			(end 0.7874 0.4064)
			(stroke
				(width 0.1524)
				(type default)
			)
			(layer "B.SilkS")
		)
		(fp_line
			(start -0.7874 -0.4064)
			(end -0.7874 0.4064)
			(stroke
				(width 0.1524)
				(type default)
			)
			(layer "B.SilkS")
		)
		(fp_line
			(start 0.67945 0.3048)
			(end 0.67945 -0.305054)
			(stroke
				(width 0.1)
				(type default)
			)
			(layer "B.Fab")
		)
		(fp_line
			(start 0.67945 -0.305054)
			(end 0.12065 -0.305054)
			(stroke
				(width 0.1)
				(type default)
			)
			(layer "B.Fab")
		)
		(fp_line
			(start 0.12065 0.3048)
			(end 0.67945 0.3048)
			(stroke
				(width 0.1)
				(type default)
			)
			(layer "B.Fab")
		)
		(fp_line
			(start 0.12065 0.2794)
			(end 0.12065 0.3048)
			(stroke
				(width 0.1)
				(type default)
			)
			(layer "B.Fab")
		)
		(fp_line
			(start 0.12065 -0.2794)
			(end -0.12065 -0.2794)
			(stroke
				(width 0.1)
				(type default)
			)
			(layer "B.Fab")
		)
		(fp_line
			(start 0.12065 -0.305054)
			(end 0.12065 -0.2794)
			(stroke
				(width 0.1)
				(type default)
			)
			(layer "B.Fab")
		)
		(fp_line
			(start -0.120396 0.3048)
			(end -0.120396 0.2794)
			(stroke
				(width 0.1)
				(type default)
			)
			(layer "B.Fab")
		)
		(fp_line
			(start -0.120396 0.2794)
			(end 0.12065 0.2794)
			(stroke
				(width 0.1)
				(type default)
			)
			(layer "B.Fab")
		)
		(fp_line
			(start -0.12065 -0.2794)
			(end -0.12065 -0.3048)
			(stroke
				(width 0.1)
				(type default)
			)
			(layer "B.Fab")
		)
		(fp_line
			(start -0.12065 -0.3048)
			(end -0.67945 -0.3048)
			(stroke
				(width 0.1)
				(type default)
			)
			(layer "B.Fab")
		)
		(fp_line
			(start -0.67945 0.3048)
			(end -0.120396 0.3048)
			(stroke
				(width 0.1)
				(type default)
			)
			(layer "B.Fab")
		)
		(fp_line
			(start -0.67945 -0.3048)
			(end -0.67945 0.3048)
			(stroke
				(width 0.1)
				(type default)
			)
			(layer "B.Fab")
		)
		(pad "1" smd circle
			(at 0.40005 0)
			(size 0 0)
			(layers "B.Cu" "B.Mask" "B.Paste")
			(net "P52V_HS1_VCAP")
		)
		(pad "2" smd circle
			(at -0.40005 0)
			(size 0 0)
			(layers "B.Cu" "B.Mask" "B.Paste")
			(net "P52V_HS1_ADR1")
		)
	)
	(footprint ""
		(layer "B.Cu")
		(at 210.439 -87.884 -90)
		(property "Reference" "U6"
			(at 0.127 -2.00533 270)
			(unlocked yes)
			(layer "B.SilkS")
			(effects
				(font
					(size 0.7874 0.5842)
					(thickness 0.1524)
				)
				(justify left mirror)
			)
		)
		(property "Value" ""
			(at 0 0 90)
			(layer "B.Fab")
			(effects
				(font
					(size 1.27 1.27)
				)
				(justify mirror)
			)
		)
		(duplicate_pad_numbers_are_jumpers no)
		(fp_line
			(start -1.400048 1.100074)
			(end 1.400048 1.100074)
			(stroke
				(width 0.1524)
				(type default)
			)
			(layer "B.SilkS")
		)
		(fp_line
			(start 1.400048 1.100074)
			(end 1.400048 -1.100074)
			(stroke
				(width 0.1524)
				(type default)
			)
			(layer "B.SilkS")
		)
		(fp_line
			(start -1.400048 -1.100074)
			(end -1.400048 1.100074)
			(stroke
				(width 0.1524)
				(type default)
			)
			(layer "B.SilkS")
		)
		(fp_line
			(start -1.400048 -1.100074)
			(end 1.400048 -1.100074)
			(stroke
				(width 0.1524)
				(type default)
			)
			(layer "B.SilkS")
		)
		(fp_poly
			(pts
				(xy 1.001014 -1.463548) (xy 0.493014 -2.479548) (xy 1.509014 -2.479548)
			)
			(stroke
				(width 0)
				(type default)
			)
			(fill yes)
			(layer "B.SilkS")
		)
		(fp_line
			(start -0.674878 1.100074)
			(end 0.674878 1.100074)
			(stroke
				(width 0.1)
				(type default)
			)
			(layer "B.Fab")
		)
		(fp_line
			(start 0.674878 1.100074)
			(end 0.674878 -1.100074)
			(stroke
				(width 0.1)
				(type default)
			)
			(layer "B.Fab")
		)
		(fp_line
			(start -0.674878 -1.100074)
			(end -0.674878 1.100074)
			(stroke
				(width 0.1)
				(type default)
			)
			(layer "B.Fab")
		)
		(fp_line
			(start 0.674878 -1.100074)
			(end -0.674878 -1.100074)
			(stroke
				(width 0.1)
				(type default)
			)
			(layer "B.Fab")
		)
		(fp_poly
			(pts
				(xy 1.590548 -0.649986) (xy 2.606548 -1.157986) (xy 2.606548 -0.141986)
			)
			(stroke
				(width 0)
				(type default)
			)
			(fill yes)
			(layer "B.Fab")
		)
		(pad "1" smd rect
			(at 0.94996 -0.649986 180)
			(size 0.4318 0.6096)
			(layers "B.Cu" "B.Mask" "B.Paste")
			(net "NC_U6")
		)
		(pad "2" smd rect
			(at 0.94996 0 180)
			(size 0.4318 0.6096)
			(layers "B.Cu" "B.Mask" "B.Paste")
			(net "PWRGD_GPU_HSC_R")
		)
		(pad "3" smd rect
			(at 0.94996 0.649986 180)
			(size 0.4318 0.6096)
			(layers "B.Cu" "B.Mask" "B.Paste")
			(net "GND")
		)
		(pad "4" smd rect
			(at -0.94996 0.649986 180)
			(size 0.4318 0.6096)
			(layers "B.Cu" "B.Mask" "B.Paste")
			(net "PWRGD_GPU_HSC_BUF")
		)
		(pad "5" smd rect
			(at -0.94996 -0.649986 180)
			(size 0.4318 0.6096)
			(layers "B.Cu" "B.Mask" "B.Paste")
			(net "P3V3_AUX")
		)
	)
	(footprint ""
		(layer "B.Cu")
		(at 212.344 -67.183 90)
		(property "Reference" "R94"
			(at 0 0 90)
			(layer "B.SilkS")
			(hide yes)
			(effects
				(font
					(size 1.27 1.27)
				)
				(justify mirror)
			)
		)
		(property "Value" ""
			(at 0 0 90)
			(layer "B.Fab")
			(effects
				(font
					(size 1.27 1.27)
				)
				(justify mirror)
			)
		)
		(duplicate_pad_numbers_are_jumpers no)
		(fp_line
			(start 0.7874 -0.4064)
			(end -0.7874 -0.4064)
			(stroke
				(width 0.1524)
				(type default)
			)
			(layer "B.SilkS")
		)
		(fp_line
			(start -0.7874 -0.4064)
			(end -0.7874 0.4064)
			(stroke
				(width 0.1524)
				(type default)
			)
			(layer "B.SilkS")
		)
		(fp_line
			(start 0.7874 0.4064)
			(end 0.7874 -0.4064)
			(stroke
				(width 0.1524)
				(type default)
			)
			(layer "B.SilkS")
		)
		(fp_line
			(start -0.7874 0.4064)
			(end 0.7874 0.4064)
			(stroke
				(width 0.1524)
				(type default)
			)
			(layer "B.SilkS")
		)
		(fp_line
			(start 0.67945 -0.305054)
			(end 0.12065 -0.305054)
			(stroke
				(width 0.1)
				(type default)
			)
			(layer "B.Fab")
		)
		(fp_line
			(start 0.12065 -0.305054)
			(end 0.12065 -0.2794)
			(stroke
				(width 0.1)
				(type default)
			)
			(layer "B.Fab")
		)
		(fp_line
			(start -0.12065 -0.3048)
			(end -0.67945 -0.3048)
			(stroke
				(width 0.1)
				(type default)
			)
			(layer "B.Fab")
		)
		(fp_line
			(start -0.67945 -0.3048)
			(end -0.67945 0.3048)
			(stroke
				(width 0.1)
				(type default)
			)
			(layer "B.Fab")
		)
		(fp_line
			(start 0.12065 -0.2794)
			(end -0.12065 -0.2794)
			(stroke
				(width 0.1)
				(type default)
			)
			(layer "B.Fab")
		)
		(fp_line
			(start -0.12065 -0.2794)
			(end -0.12065 -0.3048)
			(stroke
				(width 0.1)
				(type default)
			)
			(layer "B.Fab")
		)
		(fp_line
			(start 0.12065 0.2794)
			(end 0.12065 0.3048)
			(stroke
				(width 0.1)
				(type default)
			)
			(layer "B.Fab")
		)
		(fp_line
			(start -0.120396 0.2794)
			(end 0.12065 0.2794)
			(stroke
				(width 0.1)
				(type default)
			)
			(layer "B.Fab")
		)
		(fp_line
			(start 0.67945 0.3048)
			(end 0.67945 -0.305054)
			(stroke
				(width 0.1)
				(type default)
			)
			(layer "B.Fab")
		)
		(fp_line
			(start 0.12065 0.3048)
			(end 0.67945 0.3048)
			(stroke
				(width 0.1)
				(type default)
			)
			(layer "B.Fab")
		)
		(fp_line
			(start -0.120396 0.3048)
			(end -0.120396 0.2794)
			(stroke
				(width 0.1)
				(type default)
			)
			(layer "B.Fab")
		)
		(fp_line
			(start -0.67945 0.3048)
			(end -0.120396 0.3048)
			(stroke
				(width 0.1)
				(type default)
			)
			(layer "B.Fab")
		)
		(pad "1" smd circle
			(at 0.40005 0 270)
			(size 0 0)
			(layers "B.Cu" "B.Mask" "B.Paste")
			(net "SKU_ID_1")
		)
		(pad "2" smd circle
			(at -0.40005 0 270)
			(size 0 0)
			(layers "B.Cu" "B.Mask" "B.Paste")
			(net "GND")
		)
	)
	(footprint ""
		(layer "B.Cu")
		(at 211.455 -90.551 90)
		(property "Reference" "C7"
			(at 0 0 90)
			(layer "B.SilkS")
			(hide yes)
			(effects
				(font
					(size 1.27 1.27)
				)
				(justify mirror)
			)
		)
		(property "Value" ""
			(at 0 0 90)
			(layer "B.Fab")
			(effects
				(font
					(size 1.27 1.27)
				)
				(justify mirror)
			)
		)
		(duplicate_pad_numbers_are_jumpers no)
		(fp_line
			(start 0.7874 -0.4064)
			(end -0.7874 -0.4064)
			(stroke
				(width 0.1524)
				(type default)
			)
			(layer "B.SilkS")
		)
		(fp_line
			(start -0.7874 -0.4064)
			(end -0.7874 0.4064)
			(stroke
				(width 0.1524)
				(type default)
			)
			(layer "B.SilkS")
		)
		(fp_line
			(start 0.7874 0.4064)
			(end 0.7874 -0.4064)
			(stroke
				(width 0.1524)
				(type default)
			)
			(layer "B.SilkS")
		)
		(fp_line
			(start -0.7874 0.4064)
			(end 0.7874 0.4064)
			(stroke
				(width 0.1524)
				(type default)
			)
			(layer "B.SilkS")
		)
		(fp_line
			(start 0.67945 -0.305054)
			(end 0.12065 -0.305054)
			(stroke
				(width 0.1)
				(type default)
			)
			(layer "B.Fab")
		)
		(fp_line
			(start 0.12065 -0.305054)
			(end 0.12065 -0.2794)
			(stroke
				(width 0.1)
				(type default)
			)
			(layer "B.Fab")
		)
		(fp_line
			(start -0.12065 -0.3048)
			(end -0.67945 -0.3048)
			(stroke
				(width 0.1)
				(type default)
			)
			(layer "B.Fab")
		)
		(fp_line
			(start -0.67945 -0.3048)
			(end -0.67945 0.3048)
			(stroke
				(width 0.1)
				(type default)
			)
			(layer "B.Fab")
		)
		(fp_line
			(start 0.12065 -0.2794)
			(end -0.12065 -0.2794)
			(stroke
				(width 0.1)
				(type default)
			)
			(layer "B.Fab")
		)
		(fp_line
			(start -0.12065 -0.2794)
			(end -0.12065 -0.3048)
			(stroke
				(width 0.1)
				(type default)
			)
			(layer "B.Fab")
		)
		(fp_line
			(start 0.12065 0.2794)
			(end 0.12065 0.3048)
			(stroke
				(width 0.1)
				(type default)
			)
			(layer "B.Fab")
		)
		(fp_line
			(start -0.120396 0.2794)
			(end 0.12065 0.2794)
			(stroke
				(width 0.1)
				(type default)
			)
			(layer "B.Fab")
		)
		(fp_line
			(start 0.67945 0.3048)
			(end 0.67945 -0.305054)
			(stroke
				(width 0.1)
				(type default)
			)
			(layer "B.Fab")
		)
		(fp_line
			(start 0.12065 0.3048)
			(end 0.67945 0.3048)
			(stroke
				(width 0.1)
				(type default)
			)
			(layer "B.Fab")
		)
		(fp_line
			(start -0.120396 0.3048)
			(end -0.120396 0.2794)
			(stroke
				(width 0.1)
				(type default)
			)
			(layer "B.Fab")
		)
		(fp_line
			(start -0.67945 0.3048)
			(end -0.120396 0.3048)
			(stroke
				(width 0.1)
				(type default)
			)
			(layer "B.Fab")
		)
		(pad "1" smd circle
			(at 0.40005 0 270)
			(size 0 0)
			(layers "B.Cu" "B.Mask" "B.Paste")
			(net "GND")
		)
		(pad "2" smd circle
			(at -0.40005 0 270)
			(size 0 0)
			(layers "B.Cu" "B.Mask" "B.Paste")
			(net "P3V3_AUX")
		)
	)
	(footprint ""
		(layer "B.Cu")
		(at 287.528 -45.466 -90)
		(property "Reference" "R5904"
			(at 0 0 90)
			(layer "B.SilkS")
			(hide yes)
			(effects
				(font
					(size 1.27 1.27)
				)
				(justify mirror)
			)
		)
		(property "Value" ""
			(at 0 0 90)
			(layer "B.Fab")
			(effects
				(font
					(size 1.27 1.27)
				)
				(justify mirror)
			)
		)
		(duplicate_pad_numbers_are_jumpers no)
		(fp_line
			(start -0.7874 0.4064)
			(end 0.7874 0.4064)
			(stroke
				(width 0.1524)
				(type default)
			)
			(layer "B.SilkS")
		)
		(fp_line
			(start 0.7874 0.4064)
			(end 0.7874 -0.4064)
			(stroke
				(width 0.1524)
				(type default)
			)
			(layer "B.SilkS")
		)
		(fp_line
			(start -0.7874 -0.4064)
			(end -0.7874 0.4064)
			(stroke
				(width 0.1524)
				(type default)
			)
			(layer "B.SilkS")
		)
		(fp_line
			(start 0.7874 -0.4064)
			(end -0.7874 -0.4064)
			(stroke
				(width 0.1524)
				(type default)
			)
			(layer "B.SilkS")
		)
		(fp_line
			(start -0.67945 0.3048)
			(end -0.120396 0.3048)
			(stroke
				(width 0.1)
				(type default)
			)
			(layer "B.Fab")
		)
		(fp_line
			(start -0.120396 0.3048)
			(end -0.120396 0.2794)
			(stroke
				(width 0.1)
				(type default)
			)
			(layer "B.Fab")
		)
		(fp_line
			(start 0.12065 0.3048)
			(end 0.67945 0.3048)
			(stroke
				(width 0.1)
				(type default)
			)
			(layer "B.Fab")
		)
		(fp_line
			(start 0.67945 0.3048)
			(end 0.67945 -0.305054)
			(stroke
				(width 0.1)
				(type default)
			)
			(layer "B.Fab")
		)
		(fp_line
			(start -0.120396 0.2794)
			(end 0.12065 0.2794)
			(stroke
				(width 0.1)
				(type default)
			)
			(layer "B.Fab")
		)
		(fp_line
			(start 0.12065 0.2794)
			(end 0.12065 0.3048)
			(stroke
				(width 0.1)
				(type default)
			)
			(layer "B.Fab")
		)
		(fp_line
			(start -0.12065 -0.2794)
			(end -0.12065 -0.3048)
			(stroke
				(width 0.1)
				(type default)
			)
			(layer "B.Fab")
		)
		(fp_line
			(start 0.12065 -0.2794)
			(end -0.12065 -0.2794)
			(stroke
				(width 0.1)
				(type default)
			)
			(layer "B.Fab")
		)
		(fp_line
			(start -0.67945 -0.3048)
			(end -0.67945 0.3048)
			(stroke
				(width 0.1)
				(type default)
			)
			(layer "B.Fab")
		)
		(fp_line
			(start -0.12065 -0.3048)
			(end -0.67945 -0.3048)
			(stroke
				(width 0.1)
				(type default)
			)
			(layer "B.Fab")
		)
		(fp_line
			(start 0.12065 -0.305054)
			(end 0.12065 -0.2794)
			(stroke
				(width 0.1)
				(type default)
			)
			(layer "B.Fab")
		)
		(fp_line
			(start 0.67945 -0.305054)
			(end 0.12065 -0.305054)
			(stroke
				(width 0.1)
				(type default)
			)
			(layer "B.Fab")
		)
		(pad "1" smd circle
			(at 0.40005 0 90)
			(size 0 0)
			(layers "B.Cu" "B.Mask" "B.Paste")
			(net "FM_AC_PWR_CYCLE_N")
		)
		(pad "2" smd circle
			(at -0.40005 0 90)
			(size 0 0)
			(layers "B.Cu" "B.Mask" "B.Paste")
			(net "FM_AC_PWR_CYCLE_R_N")
		)
	)
	(footprint ""
		(layer "B.Cu")
		(at 236.982 -73.533 -90)
		(property "Reference" "C14"
			(at 0 0 90)
			(layer "B.SilkS")
			(hide yes)
			(effects
				(font
					(size 1.27 1.27)
				)
				(justify mirror)
			)
		)
		(property "Value" ""
			(at 0 0 90)
			(layer "B.Fab")
			(effects
				(font
					(size 1.27 1.27)
				)
				(justify mirror)
			)
		)
		(duplicate_pad_numbers_are_jumpers no)
		(fp_line
			(start -0.7874 0.4064)
			(end 0.7874 0.4064)
			(stroke
				(width 0.1524)
				(type default)
			)
			(layer "B.SilkS")
		)
		(fp_line
			(start 0.7874 0.4064)
			(end 0.7874 -0.4064)
			(stroke
				(width 0.1524)
				(type default)
			)
			(layer "B.SilkS")
		)
		(fp_line
			(start -0.7874 -0.4064)
			(end -0.7874 0.4064)
			(stroke
				(width 0.1524)
				(type default)
			)
			(layer "B.SilkS")
		)
		(fp_line
			(start 0.7874 -0.4064)
			(end -0.7874 -0.4064)
			(stroke
				(width 0.1524)
				(type default)
			)
			(layer "B.SilkS")
		)
		(fp_line
			(start -0.67945 0.3048)
			(end -0.120396 0.3048)
			(stroke
				(width 0.1)
				(type default)
			)
			(layer "B.Fab")
		)
		(fp_line
			(start -0.120396 0.3048)
			(end -0.120396 0.2794)
			(stroke
				(width 0.1)
				(type default)
			)
			(layer "B.Fab")
		)
		(fp_line
			(start 0.12065 0.3048)
			(end 0.67945 0.3048)
			(stroke
				(width 0.1)
				(type default)
			)
			(layer "B.Fab")
		)
		(fp_line
			(start 0.67945 0.3048)
			(end 0.67945 -0.305054)
			(stroke
				(width 0.1)
				(type default)
			)
			(layer "B.Fab")
		)
		(fp_line
			(start -0.120396 0.2794)
			(end 0.12065 0.2794)
			(stroke
				(width 0.1)
				(type default)
			)
			(layer "B.Fab")
		)
		(fp_line
			(start 0.12065 0.2794)
			(end 0.12065 0.3048)
			(stroke
				(width 0.1)
				(type default)
			)
			(layer "B.Fab")
		)
		(fp_line
			(start -0.12065 -0.2794)
			(end -0.12065 -0.3048)
			(stroke
				(width 0.1)
				(type default)
			)
			(layer "B.Fab")
		)
		(fp_line
			(start 0.12065 -0.2794)
			(end -0.12065 -0.2794)
			(stroke
				(width 0.1)
				(type default)
			)
			(layer "B.Fab")
		)
		(fp_line
			(start -0.67945 -0.3048)
			(end -0.67945 0.3048)
			(stroke
				(width 0.1)
				(type default)
			)
			(layer "B.Fab")
		)
		(fp_line
			(start -0.12065 -0.3048)
			(end -0.67945 -0.3048)
			(stroke
				(width 0.1)
				(type default)
			)
			(layer "B.Fab")
		)
		(fp_line
			(start 0.12065 -0.305054)
			(end 0.12065 -0.2794)
			(stroke
				(width 0.1)
				(type default)
			)
			(layer "B.Fab")
		)
		(fp_line
			(start 0.67945 -0.305054)
			(end 0.12065 -0.305054)
			(stroke
				(width 0.1)
				(type default)
			)
			(layer "B.Fab")
		)
		(pad "1" smd circle
			(at 0.40005 0 90)
			(size 0 0)
			(layers "B.Cu" "B.Mask" "B.Paste")
			(net "RST_SMB_PDB_R_N")
		)
		(pad "2" smd circle
			(at -0.40005 0 90)
			(size 0 0)
			(layers "B.Cu" "B.Mask" "B.Paste")
			(net "GND")
		)
	)
	(footprint ""
		(layer "B.Cu")
		(at 220.726 -90.043 -90)
		(property "Reference" "R42"
			(at 0 0 90)
			(layer "B.SilkS")
			(hide yes)
			(effects
				(font
					(size 1.27 1.27)
				)
				(justify mirror)
			)
		)
		(property "Value" ""
			(at 0 0 90)
			(layer "B.Fab")
			(effects
				(font
					(size 1.27 1.27)
				)
				(justify mirror)
			)
		)
		(duplicate_pad_numbers_are_jumpers no)
		(fp_line
			(start -0.7874 0.4064)
			(end 0.7874 0.4064)
			(stroke
				(width 0.1524)
				(type default)
			)
			(layer "B.SilkS")
		)
		(fp_line
			(start 0.7874 0.4064)
			(end 0.7874 -0.4064)
			(stroke
				(width 0.1524)
				(type default)
			)
			(layer "B.SilkS")
		)
		(fp_line
			(start -0.7874 -0.4064)
			(end -0.7874 0.4064)
			(stroke
				(width 0.1524)
				(type default)
			)
			(layer "B.SilkS")
		)
		(fp_line
			(start 0.7874 -0.4064)
			(end -0.7874 -0.4064)
			(stroke
				(width 0.1524)
				(type default)
			)
			(layer "B.SilkS")
		)
		(fp_line
			(start -0.67945 0.3048)
			(end -0.120396 0.3048)
			(stroke
				(width 0.1)
				(type default)
			)
			(layer "B.Fab")
		)
		(fp_line
			(start -0.120396 0.3048)
			(end -0.120396 0.2794)
			(stroke
				(width 0.1)
				(type default)
			)
			(layer "B.Fab")
		)
		(fp_line
			(start 0.12065 0.3048)
			(end 0.67945 0.3048)
			(stroke
				(width 0.1)
				(type default)
			)
			(layer "B.Fab")
		)
		(fp_line
			(start 0.67945 0.3048)
			(end 0.67945 -0.305054)
			(stroke
				(width 0.1)
				(type default)
			)
			(layer "B.Fab")
		)
		(fp_line
			(start -0.120396 0.2794)
			(end 0.12065 0.2794)
			(stroke
				(width 0.1)
				(type default)
			)
			(layer "B.Fab")
		)
		(fp_line
			(start 0.12065 0.2794)
			(end 0.12065 0.3048)
			(stroke
				(width 0.1)
				(type default)
			)
			(layer "B.Fab")
		)
		(fp_line
			(start -0.12065 -0.2794)
			(end -0.12065 -0.3048)
			(stroke
				(width 0.1)
				(type default)
			)
			(layer "B.Fab")
		)
		(fp_line
			(start 0.12065 -0.2794)
			(end -0.12065 -0.2794)
			(stroke
				(width 0.1)
				(type default)
			)
			(layer "B.Fab")
		)
		(fp_line
			(start -0.67945 -0.3048)
			(end -0.67945 0.3048)
			(stroke
				(width 0.1)
				(type default)
			)
			(layer "B.Fab")
		)
		(fp_line
			(start -0.12065 -0.3048)
			(end -0.67945 -0.3048)
			(stroke
				(width 0.1)
				(type default)
			)
			(layer "B.Fab")
		)
		(fp_line
			(start 0.12065 -0.305054)
			(end 0.12065 -0.2794)
			(stroke
				(width 0.1)
				(type default)
			)
			(layer "B.Fab")
		)
		(fp_line
			(start 0.67945 -0.305054)
			(end 0.12065 -0.305054)
			(stroke
				(width 0.1)
				(type default)
			)
			(layer "B.Fab")
		)
		(pad "1" smd circle
			(at 0.40005 0 90)
			(size 0 0)
			(layers "B.Cu" "B.Mask" "B.Paste")
			(net "SMB_FRU_CLK")
		)
		(pad "2" smd circle
			(at -0.40005 0 90)
			(size 0 0)
			(layers "B.Cu" "B.Mask" "B.Paste")
			(net "SMB_VPDB_MISC_SCL")
		)
	)
	(footprint ""
		(layer "B.Cu")
		(at 189.611 -86.995)
		(property "Reference" "R106"
			(at 0 0 0)
			(layer "B.SilkS")
			(hide yes)
			(effects
				(font
					(size 1.27 1.27)
				)
				(justify mirror)
			)
		)
		(property "Value" ""
			(at 0 0 0)
			(layer "B.Fab")
			(effects
				(font
					(size 1.27 1.27)
				)
				(justify mirror)
			)
		)
		(duplicate_pad_numbers_are_jumpers no)
		(fp_line
			(start -0.7874 -0.4064)
			(end -0.7874 0.4064)
			(stroke
				(width 0.1524)
				(type default)
			)
			(layer "B.SilkS")
		)
		(fp_line
			(start -0.7874 0.4064)
			(end 0.7874 0.4064)
			(stroke
				(width 0.1524)
				(type default)
			)
			(layer "B.SilkS")
		)
		(fp_line
			(start 0.7874 -0.4064)
			(end -0.7874 -0.4064)
			(stroke
				(width 0.1524)
				(type default)
			)
			(layer "B.SilkS")
		)
		(fp_line
			(start 0.7874 0.4064)
			(end 0.7874 -0.4064)
			(stroke
				(width 0.1524)
				(type default)
			)
			(layer "B.SilkS")
		)
		(fp_line
			(start -0.67945 -0.3048)
			(end -0.67945 0.3048)
			(stroke
				(width 0.1)
				(type default)
			)
			(layer "B.Fab")
		)
		(fp_line
			(start -0.67945 0.3048)
			(end -0.120396 0.3048)
			(stroke
				(width 0.1)
				(type default)
			)
			(layer "B.Fab")
		)
		(fp_line
			(start -0.12065 -0.3048)
			(end -0.67945 -0.3048)
			(stroke
				(width 0.1)
				(type default)
			)
			(layer "B.Fab")
		)
		(fp_line
			(start -0.12065 -0.2794)
			(end -0.12065 -0.3048)
			(stroke
				(width 0.1)
				(type default)
			)
			(layer "B.Fab")
		)
		(fp_line
			(start -0.120396 0.2794)
			(end 0.12065 0.2794)
			(stroke
				(width 0.1)
				(type default)
			)
			(layer "B.Fab")
		)
		(fp_line
			(start -0.120396 0.3048)
			(end -0.120396 0.2794)
			(stroke
				(width 0.1)
				(type default)
			)
			(layer "B.Fab")
		)
		(fp_line
			(start 0.12065 -0.305054)
			(end 0.12065 -0.2794)
			(stroke
				(width 0.1)
				(type default)
			)
			(layer "B.Fab")
		)
		(fp_line
			(start 0.12065 -0.2794)
			(end -0.12065 -0.2794)
			(stroke
				(width 0.1)
				(type default)
			)
			(layer "B.Fab")
		)
		(fp_line
			(start 0.12065 0.2794)
			(end 0.12065 0.3048)
			(stroke
				(width 0.1)
				(type default)
			)
			(layer "B.Fab")
		)
		(fp_line
			(start 0.12065 0.3048)
			(end 0.67945 0.3048)
			(stroke
				(width 0.1)
				(type default)
			)
			(layer "B.Fab")
		)
		(fp_line
			(start 0.67945 -0.305054)
			(end 0.12065 -0.305054)
			(stroke
				(width 0.1)
				(type default)
			)
			(layer "B.Fab")
		)
		(fp_line
			(start 0.67945 0.3048)
			(end 0.67945 -0.305054)
			(stroke
				(width 0.1)
				(type default)
			)
			(layer "B.Fab")
		)
		(pad "1" smd circle
			(at 0.40005 0 180)
			(size 0 0)
			(layers "B.Cu" "B.Mask" "B.Paste")
			(net "PU_9543_1_INT1")
		)
		(pad "2" smd circle
			(at -0.40005 0 180)
			(size 0 0)
			(layers "B.Cu" "B.Mask" "B.Paste")
			(net "P3V3_AUX")
		)
	)
	(footprint ""
		(layer "B.Cu")
		(at 220.98 -75.057 -90)
		(property "Reference" "R43"
			(at 0 0 90)
			(layer "B.SilkS")
			(hide yes)
			(effects
				(font
					(size 1.27 1.27)
				)
				(justify mirror)
			)
		)
		(property "Value" ""
			(at 0 0 90)
			(layer "B.Fab")
			(effects
				(font
					(size 1.27 1.27)
				)
				(justify mirror)
			)
		)
		(duplicate_pad_numbers_are_jumpers no)
		(fp_line
			(start -0.7874 0.4064)
			(end 0.7874 0.4064)
			(stroke
				(width 0.1524)
				(type default)
			)
			(layer "B.SilkS")
		)
		(fp_line
			(start 0.7874 0.4064)
			(end 0.7874 -0.4064)
			(stroke
				(width 0.1524)
				(type default)
			)
			(layer "B.SilkS")
		)
		(fp_line
			(start -0.7874 -0.4064)
			(end -0.7874 0.4064)
			(stroke
				(width 0.1524)
				(type default)
			)
			(layer "B.SilkS")
		)
		(fp_line
			(start 0.7874 -0.4064)
			(end -0.7874 -0.4064)
			(stroke
				(width 0.1524)
				(type default)
			)
			(layer "B.SilkS")
		)
		(fp_line
			(start -0.67945 0.3048)
			(end -0.120396 0.3048)
			(stroke
				(width 0.1)
				(type default)
			)
			(layer "B.Fab")
		)
		(fp_line
			(start -0.120396 0.3048)
			(end -0.120396 0.2794)
			(stroke
				(width 0.1)
				(type default)
			)
			(layer "B.Fab")
		)
		(fp_line
			(start 0.12065 0.3048)
			(end 0.67945 0.3048)
			(stroke
				(width 0.1)
				(type default)
			)
			(layer "B.Fab")
		)
		(fp_line
			(start 0.67945 0.3048)
			(end 0.67945 -0.305054)
			(stroke
				(width 0.1)
				(type default)
			)
			(layer "B.Fab")
		)
		(fp_line
			(start -0.120396 0.2794)
			(end 0.12065 0.2794)
			(stroke
				(width 0.1)
				(type default)
			)
			(layer "B.Fab")
		)
		(fp_line
			(start 0.12065 0.2794)
			(end 0.12065 0.3048)
			(stroke
				(width 0.1)
				(type default)
			)
			(layer "B.Fab")
		)
		(fp_line
			(start -0.12065 -0.2794)
			(end -0.12065 -0.3048)
			(stroke
				(width 0.1)
				(type default)
			)
			(layer "B.Fab")
		)
		(fp_line
			(start 0.12065 -0.2794)
			(end -0.12065 -0.2794)
			(stroke
				(width 0.1)
				(type default)
			)
			(layer "B.Fab")
		)
		(fp_line
			(start -0.67945 -0.3048)
			(end -0.67945 0.3048)
			(stroke
				(width 0.1)
				(type default)
			)
			(layer "B.Fab")
		)
		(fp_line
			(start -0.12065 -0.3048)
			(end -0.67945 -0.3048)
			(stroke
				(width 0.1)
				(type default)
			)
			(layer "B.Fab")
		)
		(fp_line
			(start 0.12065 -0.305054)
			(end 0.12065 -0.2794)
			(stroke
				(width 0.1)
				(type default)
			)
			(layer "B.Fab")
		)
		(fp_line
			(start 0.67945 -0.305054)
			(end 0.12065 -0.305054)
			(stroke
				(width 0.1)
				(type default)
			)
			(layer "B.Fab")
		)
		(pad "1" smd circle
			(at 0.40005 0 90)
			(size 0 0)
			(layers "B.Cu" "B.Mask" "B.Paste")
			(net "GND")
		)
		(pad "2" smd circle
			(at -0.40005 0 90)
			(size 0 0)
			(layers "B.Cu" "B.Mask" "B.Paste")
			(net "FRU_ADDR2")
		)
	)
	(footprint ""
		(layer "B.Cu")
		(at 191.36868 -161.464498 -90)
		(property "Reference" "J13"
			(at 3.5052 -5.552948 270)
			(unlocked yes)
			(layer "B.SilkS")
			(effects
				(font
					(size 0.7874 0.5842)
					(thickness 0.1524)
				)
				(justify left mirror)
			)
		)
		(property "Value" ""
			(at 0 0 90)
			(layer "B.Fab")
			(effects
				(font
					(size 1.27 1.27)
				)
				(justify mirror)
			)
		)
		(duplicate_pad_numbers_are_jumpers no)
		(fp_line
			(start 0 4.011168)
			(end 3.330702 -4.771136)
			(stroke
				(width 0.1524)
				(type default)
			)
			(layer "B.SilkS")
		)
		(fp_line
			(start -3.330702 -4.771136)
			(end 0 4.011168)
			(stroke
				(width 0.1524)
				(type default)
			)
			(layer "B.SilkS")
		)
		(fp_line
			(start 3.330702 -4.771136)
			(end -3.330702 -4.771136)
			(stroke
				(width 0.1524)
				(type default)
			)
			(layer "B.SilkS")
		)
		(fp_line
			(start 0 4.011168)
			(end 3.330702 -4.771136)
			(stroke
				(width 0.1)
				(type default)
			)
			(layer "B.Fab")
		)
		(fp_line
			(start -3.330702 -4.771136)
			(end 0 4.011168)
			(stroke
				(width 0.1)
				(type default)
			)
			(layer "B.Fab")
		)
		(fp_line
			(start 3.330702 -4.771136)
			(end -3.330702 -4.771136)
			(stroke
				(width 0.1)
				(type default)
			)
			(layer "B.Fab")
		)
		(pad "1" thru_hole circle
			(at 0 0 90)
			(size 2.159 2.159)
			(drill 1.7018)
			(layers "*.Cu" "*.Mask")
			(remove_unused_layers no)
			(net "GND3")
			(clearance 0.0254)
			(thermal_gap 0.0254)
		)
		(pad "2" thru_hole circle
			(at 1.27 -3.348736 90)
			(size 2.159 2.159)
			(drill 1.7018)
			(layers "*.Cu" "*.Mask")
			(remove_unused_layers no)
			(net "TDR_SE_50_OHM_IN2")
			(clearance 0.0254)
			(thermal_gap 0.0254)
		)
		(pad "3" thru_hole circle
			(at -1.27 -3.348736 90)
			(size 2.159 2.159)
			(drill 1.7018)
			(layers "*.Cu" "*.Mask")
			(remove_unused_layers no)
			(net "TDR_SE_50_OHM_IN2")
			(clearance 0.0254)
			(thermal_gap 0.0254)
		)
	)
	(footprint ""
		(layer "B.Cu")
		(at 183.896 -76.708 -90)
		(property "Reference" "PR323"
			(at 0 0 90)
			(layer "B.SilkS")
			(hide yes)
			(effects
				(font
					(size 1.27 1.27)
				)
				(justify mirror)
			)
		)
		(property "Value" ""
			(at 0 0 90)
			(layer "B.Fab")
			(effects
				(font
					(size 1.27 1.27)
				)
				(justify mirror)
			)
		)
		(duplicate_pad_numbers_are_jumpers no)
		(fp_line
			(start -0.7874 0.4064)
			(end 0.7874 0.4064)
			(stroke
				(width 0.1524)
				(type default)
			)
			(layer "B.SilkS")
		)
		(fp_line
			(start 0.7874 0.4064)
			(end 0.7874 -0.4064)
			(stroke
				(width 0.1524)
				(type default)
			)
			(layer "B.SilkS")
		)
		(fp_line
			(start -0.7874 -0.4064)
			(end -0.7874 0.4064)
			(stroke
				(width 0.1524)
				(type default)
			)
			(layer "B.SilkS")
		)
		(fp_line
			(start 0.7874 -0.4064)
			(end -0.7874 -0.4064)
			(stroke
				(width 0.1524)
				(type default)
			)
			(layer "B.SilkS")
		)
		(fp_line
			(start -0.67945 0.3048)
			(end -0.120396 0.3048)
			(stroke
				(width 0.1)
				(type default)
			)
			(layer "B.Fab")
		)
		(fp_line
			(start -0.120396 0.3048)
			(end -0.120396 0.2794)
			(stroke
				(width 0.1)
				(type default)
			)
			(layer "B.Fab")
		)
		(fp_line
			(start 0.12065 0.3048)
			(end 0.67945 0.3048)
			(stroke
				(width 0.1)
				(type default)
			)
			(layer "B.Fab")
		)
		(fp_line
			(start 0.67945 0.3048)
			(end 0.67945 -0.305054)
			(stroke
				(width 0.1)
				(type default)
			)
			(layer "B.Fab")
		)
		(fp_line
			(start -0.120396 0.2794)
			(end 0.12065 0.2794)
			(stroke
				(width 0.1)
				(type default)
			)
			(layer "B.Fab")
		)
		(fp_line
			(start 0.12065 0.2794)
			(end 0.12065 0.3048)
			(stroke
				(width 0.1)
				(type default)
			)
			(layer "B.Fab")
		)
		(fp_line
			(start -0.12065 -0.2794)
			(end -0.12065 -0.3048)
			(stroke
				(width 0.1)
				(type default)
			)
			(layer "B.Fab")
		)
		(fp_line
			(start 0.12065 -0.2794)
			(end -0.12065 -0.2794)
			(stroke
				(width 0.1)
				(type default)
			)
			(layer "B.Fab")
		)
		(fp_line
			(start -0.67945 -0.3048)
			(end -0.67945 0.3048)
			(stroke
				(width 0.1)
				(type default)
			)
			(layer "B.Fab")
		)
		(fp_line
			(start -0.12065 -0.3048)
			(end -0.67945 -0.3048)
			(stroke
				(width 0.1)
				(type default)
			)
			(layer "B.Fab")
		)
		(fp_line
			(start 0.12065 -0.305054)
			(end 0.12065 -0.2794)
			(stroke
				(width 0.1)
				(type default)
			)
			(layer "B.Fab")
		)
		(fp_line
			(start 0.67945 -0.305054)
			(end 0.12065 -0.305054)
			(stroke
				(width 0.1)
				(type default)
			)
			(layer "B.Fab")
		)
		(pad "1" smd circle
			(at 0.40005 0 90)
			(size 0 0)
			(layers "B.Cu" "B.Mask" "B.Paste")
			(net "P12V_MB2_SENSE+")
		)
		(pad "2" smd circle
			(at -0.40005 0 90)
			(size 0 0)
			(layers "B.Cu" "B.Mask" "B.Paste")
			(net "P12V_MB1_SENSE+")
		)
	)
	(footprint ""
		(layer "B.Cu")
		(at 56.850026 -116.078 -90)
		(property "Reference" "R177"
			(at 0 0 90)
			(layer "B.SilkS")
			(hide yes)
			(effects
				(font
					(size 1.27 1.27)
				)
				(justify mirror)
			)
		)
		(property "Value" ""
			(at 0 0 90)
			(layer "B.Fab")
			(effects
				(font
					(size 1.27 1.27)
				)
				(justify mirror)
			)
		)
		(duplicate_pad_numbers_are_jumpers no)
		(fp_line
			(start -0.7874 0.4064)
			(end 0.7874 0.4064)
			(stroke
				(width 0.1524)
				(type default)
			)
			(layer "B.SilkS")
		)
		(fp_line
			(start 0.7874 0.4064)
			(end 0.7874 -0.4064)
			(stroke
				(width 0.1524)
				(type default)
			)
			(layer "B.SilkS")
		)
		(fp_line
			(start -0.7874 -0.4064)
			(end -0.7874 0.4064)
			(stroke
				(width 0.1524)
				(type default)
			)
			(layer "B.SilkS")
		)
		(fp_line
			(start 0.7874 -0.4064)
			(end -0.7874 -0.4064)
			(stroke
				(width 0.1524)
				(type default)
			)
			(layer "B.SilkS")
		)
		(fp_line
			(start -0.67945 0.3048)
			(end -0.120396 0.3048)
			(stroke
				(width 0.1)
				(type default)
			)
			(layer "B.Fab")
		)
		(fp_line
			(start -0.120396 0.3048)
			(end -0.120396 0.2794)
			(stroke
				(width 0.1)
				(type default)
			)
			(layer "B.Fab")
		)
		(fp_line
			(start 0.12065 0.3048)
			(end 0.67945 0.3048)
			(stroke
				(width 0.1)
				(type default)
			)
			(layer "B.Fab")
		)
		(fp_line
			(start 0.67945 0.3048)
			(end 0.67945 -0.305054)
			(stroke
				(width 0.1)
				(type default)
			)
			(layer "B.Fab")
		)
		(fp_line
			(start -0.120396 0.2794)
			(end 0.12065 0.2794)
			(stroke
				(width 0.1)
				(type default)
			)
			(layer "B.Fab")
		)
		(fp_line
			(start 0.12065 0.2794)
			(end 0.12065 0.3048)
			(stroke
				(width 0.1)
				(type default)
			)
			(layer "B.Fab")
		)
		(fp_line
			(start -0.12065 -0.2794)
			(end -0.12065 -0.3048)
			(stroke
				(width 0.1)
				(type default)
			)
			(layer "B.Fab")
		)
		(fp_line
			(start 0.12065 -0.2794)
			(end -0.12065 -0.2794)
			(stroke
				(width 0.1)
				(type default)
			)
			(layer "B.Fab")
		)
		(fp_line
			(start -0.67945 -0.3048)
			(end -0.67945 0.3048)
			(stroke
				(width 0.1)
				(type default)
			)
			(layer "B.Fab")
		)
		(fp_line
			(start -0.12065 -0.3048)
			(end -0.67945 -0.3048)
			(stroke
				(width 0.1)
				(type default)
			)
			(layer "B.Fab")
		)
		(fp_line
			(start 0.12065 -0.305054)
			(end 0.12065 -0.2794)
			(stroke
				(width 0.1)
				(type default)
			)
			(layer "B.Fab")
		)
		(fp_line
			(start 0.67945 -0.305054)
			(end 0.12065 -0.305054)
			(stroke
				(width 0.1)
				(type default)
			)
			(layer "B.Fab")
		)
		(pad "1" smd circle
			(at 0.40005 0 90)
			(size 0 0)
			(layers "B.Cu" "B.Mask" "B.Paste")
			(net "BRICK_P12V_1_EN_N")
		)
		(pad "2" smd circle
			(at -0.40005 0 90)
			(size 0 0)
			(layers "B.Cu" "B.Mask" "B.Paste")
			(net "BRICK_P12V3_ON_OFF_R")
		)
	)
	(footprint ""
		(layer "B.Cu")
		(at 107.319826 -113.792)
		(property "Reference" "U24"
			(at -0.512826 -2.38633 0)
			(unlocked yes)
			(layer "B.SilkS")
			(effects
				(font
					(size 0.7874 0.5842)
					(thickness 0.1524)
				)
				(justify left mirror)
			)
		)
		(property "Value" ""
			(at 0 0 0)
			(layer "B.Fab")
			(effects
				(font
					(size 1.27 1.27)
				)
				(justify mirror)
			)
		)
		(duplicate_pad_numbers_are_jumpers no)
		(fp_line
			(start -1.603248 -1.500124)
			(end -1.603248 1.500124)
			(stroke
				(width 0.1524)
				(type default)
			)
			(layer "B.SilkS")
		)
		(fp_line
			(start -1.603248 1.500124)
			(end 1.603248 1.500124)
			(stroke
				(width 0.1524)
				(type default)
			)
			(layer "B.SilkS")
		)
		(fp_line
			(start 1.603248 -1.500124)
			(end -1.603248 -1.500124)
			(stroke
				(width 0.1524)
				(type default)
			)
			(layer "B.SilkS")
		)
		(fp_line
			(start 1.603248 1.500124)
			(end 1.603248 -1.500124)
			(stroke
				(width 0.1524)
				(type default)
			)
			(layer "B.SilkS")
		)
		(fp_line
			(start -1.249934 -0.219964)
			(end -0.700024 -0.219964)
			(stroke
				(width 0.1)
				(type default)
			)
			(layer "B.Fab")
		)
		(fp_line
			(start -1.249934 0.219964)
			(end -1.249934 -0.219964)
			(stroke
				(width 0.1)
				(type default)
			)
			(layer "B.Fab")
		)
		(fp_line
			(start -0.700024 -1.500124)
			(end 0.700024 -1.500124)
			(stroke
				(width 0.1)
				(type default)
			)
			(layer "B.Fab")
		)
		(fp_line
			(start -0.700024 -0.219964)
			(end -0.700024 -1.500124)
			(stroke
				(width 0.1)
				(type default)
			)
			(layer "B.Fab")
		)
		(fp_line
			(start -0.700024 0.219964)
			(end -1.249934 0.219964)
			(stroke
				(width 0.1)
				(type default)
			)
			(layer "B.Fab")
		)
		(fp_line
			(start -0.700024 1.500124)
			(end -0.700024 0.219964)
			(stroke
				(width 0.1)
				(type default)
			)
			(layer "B.Fab")
		)
		(fp_line
			(start 0.6985 -0.729996)
			(end 0.6985 0.729996)
			(stroke
				(width 0.1)
				(type default)
			)
			(layer "B.Fab")
		)
		(fp_line
			(start 0.6985 0.729996)
			(end 1.249934 0.729996)
			(stroke
				(width 0.1)
				(type default)
			)
			(layer "B.Fab")
		)
		(fp_line
			(start 0.700024 -1.500124)
			(end 0.700024 -1.169924)
			(stroke
				(width 0.1)
				(type default)
			)
			(layer "B.Fab")
		)
		(fp_line
			(start 0.700024 -1.169924)
			(end 1.249934 -1.169924)
			(stroke
				(width 0.1)
				(type default)
			)
			(layer "B.Fab")
		)
		(fp_line
			(start 0.700024 1.169924)
			(end 0.700024 1.500124)
			(stroke
				(width 0.1)
				(type default)
			)
			(layer "B.Fab")
		)
		(fp_line
			(start 0.700024 1.500124)
			(end -0.700024 1.500124)
			(stroke
				(width 0.1)
				(type default)
			)
			(layer "B.Fab")
		)
		(fp_line
			(start 1.249934 -1.169924)
			(end 1.249934 -0.729996)
			(stroke
				(width 0.1)
				(type default)
			)
			(layer "B.Fab")
		)
		(fp_line
			(start 1.249934 -0.729996)
			(end 0.6985 -0.729996)
			(stroke
				(width 0.1)
				(type default)
			)
			(layer "B.Fab")
		)
		(fp_line
			(start 1.249934 0.729996)
			(end 1.249934 1.169924)
			(stroke
				(width 0.1)
				(type default)
			)
			(layer "B.Fab")
		)
		(fp_line
			(start 1.249934 1.169924)
			(end 0.700024 1.169924)
			(stroke
				(width 0.1)
				(type default)
			)
			(layer "B.Fab")
		)
		(fp_rect
			(start 0.700024 1.500124)
			(end -0.700024 -1.500124)
			(stroke
				(width 0)
				(type default)
			)
			(fill no)
			(layer "B.Fab")
		)
		(pad "D" smd rect
			(at -0.999998 0 270)
			(size 0.8128 0.9144)
			(layers "B.Cu" "B.Mask" "B.Paste")
			(net "BRICK_P12V_EN_R_N")
		)
		(pad "G" smd rect
			(at 0.999998 -0.94996 270)
			(size 0.8128 0.9144)
			(layers "B.Cu" "B.Mask" "B.Paste")
			(net "P12V_BRICK0_PWRGD")
		)
		(pad "S" smd rect
			(at 0.999998 0.94996 270)
			(size 0.8128 0.9144)
			(layers "B.Cu" "B.Mask" "B.Paste")
			(net "GND")
		)
	)
	(footprint ""
		(layer "B.Cu")
		(at 53.594 -6.604)
		(property "Reference" ""
			(at 0 0 0)
			(layer "B.SilkS")
			(hide yes)
			(effects
				(font
					(size 1.27 1.27)
				)
				(justify mirror)
			)
		)
		(property "Value" ""
			(at 0 0 0)
			(layer "B.Fab")
			(effects
				(font
					(size 1.27 1.27)
				)
				(justify mirror)
			)
		)
		(duplicate_pad_numbers_are_jumpers no)
		(pad "1" smd circle
			(at 0 0 180)
			(size 0.9906 0.9906)
			(layers "B.Cu" "B.Mask" "B.Paste")
			(net "Net_153")
		)
		(zone
			(layer "B.Cu")
			(hatch none 0.5)
			(connect_pads
				(clearance 0)
			)
			(min_thickness 0.25)
			(keepout
				(tracks not_allowed)
				(vias allowed)
				(pads allowed)
				(copperpour not_allowed)
				(footprints allowed)
			)
			(placement
				(enabled no)
				(sheetname "")
			)
			(fill
				(thermal_gap 0.5)
				(thermal_bridge_width 0.5)
				(island_removal_mode 0)
			)
			(polygon
				(pts
					(arc
						(start 55.2196 -6.604)
						(mid 51.9684 -6.604)
						(end 55.2196 -6.604)
					)
				)
			)
		)
	)
	(footprint ""
		(layer "B.Cu")
		(at 213.614 -69.723 -90)
		(property "Reference" "R92"
			(at 0 0 90)
			(layer "B.SilkS")
			(hide yes)
			(effects
				(font
					(size 1.27 1.27)
				)
				(justify mirror)
			)
		)
		(property "Value" ""
			(at 0 0 90)
			(layer "B.Fab")
			(effects
				(font
					(size 1.27 1.27)
				)
				(justify mirror)
			)
		)
		(duplicate_pad_numbers_are_jumpers no)
		(fp_line
			(start -0.7874 0.4064)
			(end 0.7874 0.4064)
			(stroke
				(width 0.1524)
				(type default)
			)
			(layer "B.SilkS")
		)
		(fp_line
			(start 0.7874 0.4064)
			(end 0.7874 -0.4064)
			(stroke
				(width 0.1524)
				(type default)
			)
			(layer "B.SilkS")
		)
		(fp_line
			(start -0.7874 -0.4064)
			(end -0.7874 0.4064)
			(stroke
				(width 0.1524)
				(type default)
			)
			(layer "B.SilkS")
		)
		(fp_line
			(start 0.7874 -0.4064)
			(end -0.7874 -0.4064)
			(stroke
				(width 0.1524)
				(type default)
			)
			(layer "B.SilkS")
		)
		(fp_line
			(start -0.67945 0.3048)
			(end -0.120396 0.3048)
			(stroke
				(width 0.1)
				(type default)
			)
			(layer "B.Fab")
		)
		(fp_line
			(start -0.120396 0.3048)
			(end -0.120396 0.2794)
			(stroke
				(width 0.1)
				(type default)
			)
			(layer "B.Fab")
		)
		(fp_line
			(start 0.12065 0.3048)
			(end 0.67945 0.3048)
			(stroke
				(width 0.1)
				(type default)
			)
			(layer "B.Fab")
		)
		(fp_line
			(start 0.67945 0.3048)
			(end 0.67945 -0.305054)
			(stroke
				(width 0.1)
				(type default)
			)
			(layer "B.Fab")
		)
		(fp_line
			(start -0.120396 0.2794)
			(end 0.12065 0.2794)
			(stroke
				(width 0.1)
				(type default)
			)
			(layer "B.Fab")
		)
		(fp_line
			(start 0.12065 0.2794)
			(end 0.12065 0.3048)
			(stroke
				(width 0.1)
				(type default)
			)
			(layer "B.Fab")
		)
		(fp_line
			(start -0.12065 -0.2794)
			(end -0.12065 -0.3048)
			(stroke
				(width 0.1)
				(type default)
			)
			(layer "B.Fab")
		)
		(fp_line
			(start 0.12065 -0.2794)
			(end -0.12065 -0.2794)
			(stroke
				(width 0.1)
				(type default)
			)
			(layer "B.Fab")
		)
		(fp_line
			(start -0.67945 -0.3048)
			(end -0.67945 0.3048)
			(stroke
				(width 0.1)
				(type default)
			)
			(layer "B.Fab")
		)
		(fp_line
			(start -0.12065 -0.3048)
			(end -0.67945 -0.3048)
			(stroke
				(width 0.1)
				(type default)
			)
			(layer "B.Fab")
		)
		(fp_line
			(start 0.12065 -0.305054)
			(end 0.12065 -0.2794)
			(stroke
				(width 0.1)
				(type default)
			)
			(layer "B.Fab")
		)
		(fp_line
			(start 0.67945 -0.305054)
			(end 0.12065 -0.305054)
			(stroke
				(width 0.1)
				(type default)
			)
			(layer "B.Fab")
		)
		(pad "1" smd circle
			(at 0.40005 0 90)
			(size 0 0)
			(layers "B.Cu" "B.Mask" "B.Paste")
			(net "P3V3_AUX")
		)
		(pad "2" smd circle
			(at -0.40005 0 90)
			(size 0 0)
			(layers "B.Cu" "B.Mask" "B.Paste")
			(net "SKU_ID_0")
		)
	)
	(footprint ""
		(layer "B.Cu")
		(at 266.192 -31.877)
		(property "Reference" "PR212"
			(at 0 0 0)
			(layer "B.SilkS")
			(hide yes)
			(effects
				(font
					(size 1.27 1.27)
				)
				(justify mirror)
			)
		)
		(property "Value" ""
			(at 0 0 0)
			(layer "B.Fab")
			(effects
				(font
					(size 1.27 1.27)
				)
				(justify mirror)
			)
		)
		(duplicate_pad_numbers_are_jumpers no)
		(fp_line
			(start -0.7874 -0.4064)
			(end -0.7874 0.4064)
			(stroke
				(width 0.1524)
				(type default)
			)
			(layer "B.SilkS")
		)
		(fp_line
			(start -0.7874 0.4064)
			(end 0.7874 0.4064)
			(stroke
				(width 0.1524)
				(type default)
			)
			(layer "B.SilkS")
		)
		(fp_line
			(start 0.7874 -0.4064)
			(end -0.7874 -0.4064)
			(stroke
				(width 0.1524)
				(type default)
			)
			(layer "B.SilkS")
		)
		(fp_line
			(start 0.7874 0.4064)
			(end 0.7874 -0.4064)
			(stroke
				(width 0.1524)
				(type default)
			)
			(layer "B.SilkS")
		)
		(fp_line
			(start -0.67945 -0.3048)
			(end -0.67945 0.3048)
			(stroke
				(width 0.1)
				(type default)
			)
			(layer "B.Fab")
		)
		(fp_line
			(start -0.67945 0.3048)
			(end -0.120396 0.3048)
			(stroke
				(width 0.1)
				(type default)
			)
			(layer "B.Fab")
		)
		(fp_line
			(start -0.12065 -0.3048)
			(end -0.67945 -0.3048)
			(stroke
				(width 0.1)
				(type default)
			)
			(layer "B.Fab")
		)
		(fp_line
			(start -0.12065 -0.2794)
			(end -0.12065 -0.3048)
			(stroke
				(width 0.1)
				(type default)
			)
			(layer "B.Fab")
		)
		(fp_line
			(start -0.120396 0.2794)
			(end 0.12065 0.2794)
			(stroke
				(width 0.1)
				(type default)
			)
			(layer "B.Fab")
		)
		(fp_line
			(start -0.120396 0.3048)
			(end -0.120396 0.2794)
			(stroke
				(width 0.1)
				(type default)
			)
			(layer "B.Fab")
		)
		(fp_line
			(start 0.12065 -0.305054)
			(end 0.12065 -0.2794)
			(stroke
				(width 0.1)
				(type default)
			)
			(layer "B.Fab")
		)
		(fp_line
			(start 0.12065 -0.2794)
			(end -0.12065 -0.2794)
			(stroke
				(width 0.1)
				(type default)
			)
			(layer "B.Fab")
		)
		(fp_line
			(start 0.12065 0.2794)
			(end 0.12065 0.3048)
			(stroke
				(width 0.1)
				(type default)
			)
			(layer "B.Fab")
		)
		(fp_line
			(start 0.12065 0.3048)
			(end 0.67945 0.3048)
			(stroke
				(width 0.1)
				(type default)
			)
			(layer "B.Fab")
		)
		(fp_line
			(start 0.67945 -0.305054)
			(end 0.12065 -0.305054)
			(stroke
				(width 0.1)
				(type default)
			)
			(layer "B.Fab")
		)
		(fp_line
			(start 0.67945 0.3048)
			(end 0.67945 -0.305054)
			(stroke
				(width 0.1)
				(type default)
			)
			(layer "B.Fab")
		)
		(pad "1" smd circle
			(at 0.40005 0 180)
			(size 0 0)
			(layers "B.Cu" "B.Mask" "B.Paste")
			(net "P52V_HS1_SIO")
		)
		(pad "2" smd circle
			(at -0.40005 0 180)
			(size 0 0)
			(layers "B.Cu" "B.Mask" "B.Paste")
			(net "P52V_HS1_INTVCC")
		)
	)
	(footprint ""
		(layer "B.Cu")
		(at 279.908 -45.72 180)
		(property "Reference" "R156"
			(at 0 0 0)
			(layer "B.SilkS")
			(hide yes)
			(effects
				(font
					(size 1.27 1.27)
				)
				(justify mirror)
			)
		)
		(property "Value" ""
			(at 0 0 0)
			(layer "B.Fab")
			(effects
				(font
					(size 1.27 1.27)
				)
				(justify mirror)
			)
		)
		(duplicate_pad_numbers_are_jumpers no)
		(fp_line
			(start 0.7874 0.4064)
			(end 0.7874 -0.4064)
			(stroke
				(width 0.1524)
				(type default)
			)
			(layer "B.SilkS")
		)
		(fp_line
			(start 0.7874 -0.4064)
			(end -0.7874 -0.4064)
			(stroke
				(width 0.1524)
				(type default)
			)
			(layer "B.SilkS")
		)
		(fp_line
			(start -0.7874 0.4064)
			(end 0.7874 0.4064)
			(stroke
				(width 0.1524)
				(type default)
			)
			(layer "B.SilkS")
		)
		(fp_line
			(start -0.7874 -0.4064)
			(end -0.7874 0.4064)
			(stroke
				(width 0.1524)
				(type default)
			)
			(layer "B.SilkS")
		)
		(fp_line
			(start 0.67945 0.3048)
			(end 0.67945 -0.305054)
			(stroke
				(width 0.1)
				(type default)
			)
			(layer "B.Fab")
		)
		(fp_line
			(start 0.67945 -0.305054)
			(end 0.12065 -0.305054)
			(stroke
				(width 0.1)
				(type default)
			)
			(layer "B.Fab")
		)
		(fp_line
			(start 0.12065 0.3048)
			(end 0.67945 0.3048)
			(stroke
				(width 0.1)
				(type default)
			)
			(layer "B.Fab")
		)
		(fp_line
			(start 0.12065 0.2794)
			(end 0.12065 0.3048)
			(stroke
				(width 0.1)
				(type default)
			)
			(layer "B.Fab")
		)
		(fp_line
			(start 0.12065 -0.2794)
			(end -0.12065 -0.2794)
			(stroke
				(width 0.1)
				(type default)
			)
			(layer "B.Fab")
		)
		(fp_line
			(start 0.12065 -0.305054)
			(end 0.12065 -0.2794)
			(stroke
				(width 0.1)
				(type default)
			)
			(layer "B.Fab")
		)
		(fp_line
			(start -0.120396 0.3048)
			(end -0.120396 0.2794)
			(stroke
				(width 0.1)
				(type default)
			)
			(layer "B.Fab")
		)
		(fp_line
			(start -0.120396 0.2794)
			(end 0.12065 0.2794)
			(stroke
				(width 0.1)
				(type default)
			)
			(layer "B.Fab")
		)
		(fp_line
			(start -0.12065 -0.2794)
			(end -0.12065 -0.3048)
			(stroke
				(width 0.1)
				(type default)
			)
			(layer "B.Fab")
		)
		(fp_line
			(start -0.12065 -0.3048)
			(end -0.67945 -0.3048)
			(stroke
				(width 0.1)
				(type default)
			)
			(layer "B.Fab")
		)
		(fp_line
			(start -0.67945 0.3048)
			(end -0.120396 0.3048)
			(stroke
				(width 0.1)
				(type default)
			)
			(layer "B.Fab")
		)
		(fp_line
			(start -0.67945 -0.3048)
			(end -0.67945 0.3048)
			(stroke
				(width 0.1)
				(type default)
			)
			(layer "B.Fab")
		)
		(pad "1" smd circle
			(at 0.40005 0)
			(size 0 0)
			(layers "B.Cu" "B.Mask" "B.Paste")
			(net "P52V_HS1_VCAP")
		)
		(pad "2" smd circle
			(at -0.40005 0)
			(size 0 0)
			(layers "B.Cu" "B.Mask" "B.Paste")
			(net "P52V_HS1_ADR0")
		)
	)
	(footprint ""
		(layer "B.Cu")
		(at 139.065 -78.867)
		(property "Reference" "R161"
			(at 0 0 0)
			(layer "B.SilkS")
			(hide yes)
			(effects
				(font
					(size 1.27 1.27)
				)
				(justify mirror)
			)
		)
		(property "Value" ""
			(at 0 0 0)
			(layer "B.Fab")
			(effects
				(font
					(size 1.27 1.27)
				)
				(justify mirror)
			)
		)
		(duplicate_pad_numbers_are_jumpers no)
		(fp_line
			(start -0.7874 -0.4064)
			(end -0.7874 0.4064)
			(stroke
				(width 0.1524)
				(type default)
			)
			(layer "B.SilkS")
		)
		(fp_line
			(start -0.7874 0.4064)
			(end 0.7874 0.4064)
			(stroke
				(width 0.1524)
				(type default)
			)
			(layer "B.SilkS")
		)
		(fp_line
			(start 0.7874 -0.4064)
			(end -0.7874 -0.4064)
			(stroke
				(width 0.1524)
				(type default)
			)
			(layer "B.SilkS")
		)
		(fp_line
			(start 0.7874 0.4064)
			(end 0.7874 -0.4064)
			(stroke
				(width 0.1524)
				(type default)
			)
			(layer "B.SilkS")
		)
		(fp_line
			(start -0.67945 -0.3048)
			(end -0.67945 0.3048)
			(stroke
				(width 0.1)
				(type default)
			)
			(layer "B.Fab")
		)
		(fp_line
			(start -0.67945 0.3048)
			(end -0.120396 0.3048)
			(stroke
				(width 0.1)
				(type default)
			)
			(layer "B.Fab")
		)
		(fp_line
			(start -0.12065 -0.3048)
			(end -0.67945 -0.3048)
			(stroke
				(width 0.1)
				(type default)
			)
			(layer "B.Fab")
		)
		(fp_line
			(start -0.12065 -0.2794)
			(end -0.12065 -0.3048)
			(stroke
				(width 0.1)
				(type default)
			)
			(layer "B.Fab")
		)
		(fp_line
			(start -0.120396 0.2794)
			(end 0.12065 0.2794)
			(stroke
				(width 0.1)
				(type default)
			)
			(layer "B.Fab")
		)
		(fp_line
			(start -0.120396 0.3048)
			(end -0.120396 0.2794)
			(stroke
				(width 0.1)
				(type default)
			)
			(layer "B.Fab")
		)
		(fp_line
			(start 0.12065 -0.305054)
			(end 0.12065 -0.2794)
			(stroke
				(width 0.1)
				(type default)
			)
			(layer "B.Fab")
		)
		(fp_line
			(start 0.12065 -0.2794)
			(end -0.12065 -0.2794)
			(stroke
				(width 0.1)
				(type default)
			)
			(layer "B.Fab")
		)
		(fp_line
			(start 0.12065 0.2794)
			(end 0.12065 0.3048)
			(stroke
				(width 0.1)
				(type default)
			)
			(layer "B.Fab")
		)
		(fp_line
			(start 0.12065 0.3048)
			(end 0.67945 0.3048)
			(stroke
				(width 0.1)
				(type default)
			)
			(layer "B.Fab")
		)
		(fp_line
			(start 0.67945 -0.305054)
			(end 0.12065 -0.305054)
			(stroke
				(width 0.1)
				(type default)
			)
			(layer "B.Fab")
		)
		(fp_line
			(start 0.67945 0.3048)
			(end 0.67945 -0.305054)
			(stroke
				(width 0.1)
				(type default)
			)
			(layer "B.Fab")
		)
		(pad "1" smd circle
			(at 0.40005 0 180)
			(size 0 0)
			(layers "B.Cu" "B.Mask" "B.Paste")
			(net "P3V3_AUX")
		)
		(pad "2" smd circle
			(at -0.40005 0 180)
			(size 0 0)
			(layers "B.Cu" "B.Mask" "B.Paste")
			(net "SMB_P52V_VPDB_SCL")
		)
	)
	(footprint ""
		(layer "B.Cu")
		(at 225.552 -70.993 -90)
		(property "Reference" "R71"
			(at 0 0 90)
			(layer "B.SilkS")
			(hide yes)
			(effects
				(font
					(size 1.27 1.27)
				)
				(justify mirror)
			)
		)
		(property "Value" ""
			(at 0 0 90)
			(layer "B.Fab")
			(effects
				(font
					(size 1.27 1.27)
				)
				(justify mirror)
			)
		)
		(duplicate_pad_numbers_are_jumpers no)
		(fp_line
			(start -0.7874 0.4064)
			(end 0.7874 0.4064)
			(stroke
				(width 0.1524)
				(type default)
			)
			(layer "B.SilkS")
		)
		(fp_line
			(start 0.7874 0.4064)
			(end 0.7874 -0.4064)
			(stroke
				(width 0.1524)
				(type default)
			)
			(layer "B.SilkS")
		)
		(fp_line
			(start -0.7874 -0.4064)
			(end -0.7874 0.4064)
			(stroke
				(width 0.1524)
				(type default)
			)
			(layer "B.SilkS")
		)
		(fp_line
			(start 0.7874 -0.4064)
			(end -0.7874 -0.4064)
			(stroke
				(width 0.1524)
				(type default)
			)
			(layer "B.SilkS")
		)
		(fp_line
			(start -0.67945 0.3048)
			(end -0.120396 0.3048)
			(stroke
				(width 0.1)
				(type default)
			)
			(layer "B.Fab")
		)
		(fp_line
			(start -0.120396 0.3048)
			(end -0.120396 0.2794)
			(stroke
				(width 0.1)
				(type default)
			)
			(layer "B.Fab")
		)
		(fp_line
			(start 0.12065 0.3048)
			(end 0.67945 0.3048)
			(stroke
				(width 0.1)
				(type default)
			)
			(layer "B.Fab")
		)
		(fp_line
			(start 0.67945 0.3048)
			(end 0.67945 -0.305054)
			(stroke
				(width 0.1)
				(type default)
			)
			(layer "B.Fab")
		)
		(fp_line
			(start -0.120396 0.2794)
			(end 0.12065 0.2794)
			(stroke
				(width 0.1)
				(type default)
			)
			(layer "B.Fab")
		)
		(fp_line
			(start 0.12065 0.2794)
			(end 0.12065 0.3048)
			(stroke
				(width 0.1)
				(type default)
			)
			(layer "B.Fab")
		)
		(fp_line
			(start -0.12065 -0.2794)
			(end -0.12065 -0.3048)
			(stroke
				(width 0.1)
				(type default)
			)
			(layer "B.Fab")
		)
		(fp_line
			(start 0.12065 -0.2794)
			(end -0.12065 -0.2794)
			(stroke
				(width 0.1)
				(type default)
			)
			(layer "B.Fab")
		)
		(fp_line
			(start -0.67945 -0.3048)
			(end -0.67945 0.3048)
			(stroke
				(width 0.1)
				(type default)
			)
			(layer "B.Fab")
		)
		(fp_line
			(start -0.12065 -0.3048)
			(end -0.67945 -0.3048)
			(stroke
				(width 0.1)
				(type default)
			)
			(layer "B.Fab")
		)
		(fp_line
			(start 0.12065 -0.305054)
			(end 0.12065 -0.2794)
			(stroke
				(width 0.1)
				(type default)
			)
			(layer "B.Fab")
		)
		(fp_line
			(start 0.67945 -0.305054)
			(end 0.12065 -0.305054)
			(stroke
				(width 0.1)
				(type default)
			)
			(layer "B.Fab")
		)
		(pad "1" smd circle
			(at 0.40005 0 90)
			(size 0 0)
			(layers "B.Cu" "B.Mask" "B.Paste")
			(net "GPU_HSC_R_EN")
		)
		(pad "2" smd circle
			(at -0.40005 0 90)
			(size 0 0)
			(layers "B.Cu" "B.Mask" "B.Paste")
			(net "GPU_HSC_EN")
		)
	)
	(footprint ""
		(layer "B.Cu")
		(at 189.611 -83.439)
		(property "Reference" "R128"
			(at 0 0 0)
			(layer "B.SilkS")
			(hide yes)
			(effects
				(font
					(size 1.27 1.27)
				)
				(justify mirror)
			)
		)
		(property "Value" ""
			(at 0 0 0)
			(layer "B.Fab")
			(effects
				(font
					(size 1.27 1.27)
				)
				(justify mirror)
			)
		)
		(duplicate_pad_numbers_are_jumpers no)
		(fp_line
			(start -0.7874 -0.4064)
			(end -0.7874 0.4064)
			(stroke
				(width 0.1524)
				(type default)
			)
			(layer "B.SilkS")
		)
		(fp_line
			(start -0.7874 0.4064)
			(end 0.7874 0.4064)
			(stroke
				(width 0.1524)
				(type default)
			)
			(layer "B.SilkS")
		)
		(fp_line
			(start 0.7874 -0.4064)
			(end -0.7874 -0.4064)
			(stroke
				(width 0.1524)
				(type default)
			)
			(layer "B.SilkS")
		)
		(fp_line
			(start 0.7874 0.4064)
			(end 0.7874 -0.4064)
			(stroke
				(width 0.1524)
				(type default)
			)
			(layer "B.SilkS")
		)
		(fp_line
			(start -0.67945 -0.3048)
			(end -0.67945 0.3048)
			(stroke
				(width 0.1)
				(type default)
			)
			(layer "B.Fab")
		)
		(fp_line
			(start -0.67945 0.3048)
			(end -0.120396 0.3048)
			(stroke
				(width 0.1)
				(type default)
			)
			(layer "B.Fab")
		)
		(fp_line
			(start -0.12065 -0.3048)
			(end -0.67945 -0.3048)
			(stroke
				(width 0.1)
				(type default)
			)
			(layer "B.Fab")
		)
		(fp_line
			(start -0.12065 -0.2794)
			(end -0.12065 -0.3048)
			(stroke
				(width 0.1)
				(type default)
			)
			(layer "B.Fab")
		)
		(fp_line
			(start -0.120396 0.2794)
			(end 0.12065 0.2794)
			(stroke
				(width 0.1)
				(type default)
			)
			(layer "B.Fab")
		)
		(fp_line
			(start -0.120396 0.3048)
			(end -0.120396 0.2794)
			(stroke
				(width 0.1)
				(type default)
			)
			(layer "B.Fab")
		)
		(fp_line
			(start 0.12065 -0.305054)
			(end 0.12065 -0.2794)
			(stroke
				(width 0.1)
				(type default)
			)
			(layer "B.Fab")
		)
		(fp_line
			(start 0.12065 -0.2794)
			(end -0.12065 -0.2794)
			(stroke
				(width 0.1)
				(type default)
			)
			(layer "B.Fab")
		)
		(fp_line
			(start 0.12065 0.2794)
			(end 0.12065 0.3048)
			(stroke
				(width 0.1)
				(type default)
			)
			(layer "B.Fab")
		)
		(fp_line
			(start 0.12065 0.3048)
			(end 0.67945 0.3048)
			(stroke
				(width 0.1)
				(type default)
			)
			(layer "B.Fab")
		)
		(fp_line
			(start 0.67945 -0.305054)
			(end 0.12065 -0.305054)
			(stroke
				(width 0.1)
				(type default)
			)
			(layer "B.Fab")
		)
		(fp_line
			(start 0.67945 0.3048)
			(end 0.67945 -0.305054)
			(stroke
				(width 0.1)
				(type default)
			)
			(layer "B.Fab")
		)
		(pad "1" smd circle
			(at 0.40005 0 180)
			(size 0 0)
			(layers "B.Cu" "B.Mask" "B.Paste")
			(net "SMB_P52V_VPDB_SDA")
		)
		(pad "2" smd circle
			(at -0.40005 0 180)
			(size 0 0)
			(layers "B.Cu" "B.Mask" "B.Paste")
			(net "P3V3_AUX")
		)
	)
	(footprint ""
		(layer "B.Cu")
		(at 189.611 -89.7128)
		(property "Reference" "R131"
			(at 0 0 0)
			(layer "B.SilkS")
			(hide yes)
			(effects
				(font
					(size 1.27 1.27)
				)
				(justify mirror)
			)
		)
		(property "Value" ""
			(at 0 0 0)
			(layer "B.Fab")
			(effects
				(font
					(size 1.27 1.27)
				)
				(justify mirror)
			)
		)
		(duplicate_pad_numbers_are_jumpers no)
		(fp_line
			(start -0.7874 -0.4064)
			(end -0.7874 0.4064)
			(stroke
				(width 0.1524)
				(type default)
			)
			(layer "B.SilkS")
		)
		(fp_line
			(start -0.7874 0.4064)
			(end 0.7874 0.4064)
			(stroke
				(width 0.1524)
				(type default)
			)
			(layer "B.SilkS")
		)
		(fp_line
			(start 0.7874 -0.4064)
			(end -0.7874 -0.4064)
			(stroke
				(width 0.1524)
				(type default)
			)
			(layer "B.SilkS")
		)
		(fp_line
			(start 0.7874 0.4064)
			(end 0.7874 -0.4064)
			(stroke
				(width 0.1524)
				(type default)
			)
			(layer "B.SilkS")
		)
		(fp_line
			(start -0.67945 -0.3048)
			(end -0.67945 0.3048)
			(stroke
				(width 0.1)
				(type default)
			)
			(layer "B.Fab")
		)
		(fp_line
			(start -0.67945 0.3048)
			(end -0.120396 0.3048)
			(stroke
				(width 0.1)
				(type default)
			)
			(layer "B.Fab")
		)
		(fp_line
			(start -0.12065 -0.3048)
			(end -0.67945 -0.3048)
			(stroke
				(width 0.1)
				(type default)
			)
			(layer "B.Fab")
		)
		(fp_line
			(start -0.12065 -0.2794)
			(end -0.12065 -0.3048)
			(stroke
				(width 0.1)
				(type default)
			)
			(layer "B.Fab")
		)
		(fp_line
			(start -0.120396 0.2794)
			(end 0.12065 0.2794)
			(stroke
				(width 0.1)
				(type default)
			)
			(layer "B.Fab")
		)
		(fp_line
			(start -0.120396 0.3048)
			(end -0.120396 0.2794)
			(stroke
				(width 0.1)
				(type default)
			)
			(layer "B.Fab")
		)
		(fp_line
			(start 0.12065 -0.305054)
			(end 0.12065 -0.2794)
			(stroke
				(width 0.1)
				(type default)
			)
			(layer "B.Fab")
		)
		(fp_line
			(start 0.12065 -0.2794)
			(end -0.12065 -0.2794)
			(stroke
				(width 0.1)
				(type default)
			)
			(layer "B.Fab")
		)
		(fp_line
			(start 0.12065 0.2794)
			(end 0.12065 0.3048)
			(stroke
				(width 0.1)
				(type default)
			)
			(layer "B.Fab")
		)
		(fp_line
			(start 0.12065 0.3048)
			(end 0.67945 0.3048)
			(stroke
				(width 0.1)
				(type default)
			)
			(layer "B.Fab")
		)
		(fp_line
			(start 0.67945 -0.305054)
			(end 0.12065 -0.305054)
			(stroke
				(width 0.1)
				(type default)
			)
			(layer "B.Fab")
		)
		(fp_line
			(start 0.67945 0.3048)
			(end 0.67945 -0.305054)
			(stroke
				(width 0.1)
				(type default)
			)
			(layer "B.Fab")
		)
		(pad "1" smd circle
			(at 0.40005 0 180)
			(size 0 0)
			(layers "B.Cu" "B.Mask" "B.Paste")
			(net "SMB_P52V_HPDB_SCL")
		)
		(pad "2" smd circle
			(at -0.40005 0 180)
			(size 0 0)
			(layers "B.Cu" "B.Mask" "B.Paste")
			(net "P3V3_AUX")
		)
	)
	(footprint ""
		(layer "B.Cu")
		(at 273.5072 -103.759 90)
		(property "Reference" "R5860"
			(at 0 0 90)
			(layer "B.SilkS")
			(hide yes)
			(effects
				(font
					(size 1.27 1.27)
				)
				(justify mirror)
			)
		)
		(property "Value" ""
			(at 0 0 90)
			(layer "B.Fab")
			(effects
				(font
					(size 1.27 1.27)
				)
				(justify mirror)
			)
		)
		(duplicate_pad_numbers_are_jumpers no)
		(fp_line
			(start 0.7874 -0.4064)
			(end -0.7874 -0.4064)
			(stroke
				(width 0.1524)
				(type default)
			)
			(layer "B.SilkS")
		)
		(fp_line
			(start -0.7874 -0.4064)
			(end -0.7874 0.4064)
			(stroke
				(width 0.1524)
				(type default)
			)
			(layer "B.SilkS")
		)
		(fp_line
			(start 0.7874 0.4064)
			(end 0.7874 -0.4064)
			(stroke
				(width 0.1524)
				(type default)
			)
			(layer "B.SilkS")
		)
		(fp_line
			(start -0.7874 0.4064)
			(end 0.7874 0.4064)
			(stroke
				(width 0.1524)
				(type default)
			)
			(layer "B.SilkS")
		)
		(fp_line
			(start 0.67945 -0.305054)
			(end 0.12065 -0.305054)
			(stroke
				(width 0.1)
				(type default)
			)
			(layer "B.Fab")
		)
		(fp_line
			(start 0.12065 -0.305054)
			(end 0.12065 -0.2794)
			(stroke
				(width 0.1)
				(type default)
			)
			(layer "B.Fab")
		)
		(fp_line
			(start -0.12065 -0.3048)
			(end -0.67945 -0.3048)
			(stroke
				(width 0.1)
				(type default)
			)
			(layer "B.Fab")
		)
		(fp_line
			(start -0.67945 -0.3048)
			(end -0.67945 0.3048)
			(stroke
				(width 0.1)
				(type default)
			)
			(layer "B.Fab")
		)
		(fp_line
			(start 0.12065 -0.2794)
			(end -0.12065 -0.2794)
			(stroke
				(width 0.1)
				(type default)
			)
			(layer "B.Fab")
		)
		(fp_line
			(start -0.12065 -0.2794)
			(end -0.12065 -0.3048)
			(stroke
				(width 0.1)
				(type default)
			)
			(layer "B.Fab")
		)
		(fp_line
			(start 0.12065 0.2794)
			(end 0.12065 0.3048)
			(stroke
				(width 0.1)
				(type default)
			)
			(layer "B.Fab")
		)
		(fp_line
			(start -0.120396 0.2794)
			(end 0.12065 0.2794)
			(stroke
				(width 0.1)
				(type default)
			)
			(layer "B.Fab")
		)
		(fp_line
			(start 0.67945 0.3048)
			(end 0.67945 -0.305054)
			(stroke
				(width 0.1)
				(type default)
			)
			(layer "B.Fab")
		)
		(fp_line
			(start 0.12065 0.3048)
			(end 0.67945 0.3048)
			(stroke
				(width 0.1)
				(type default)
			)
			(layer "B.Fab")
		)
		(fp_line
			(start -0.120396 0.3048)
			(end -0.120396 0.2794)
			(stroke
				(width 0.1)
				(type default)
			)
			(layer "B.Fab")
		)
		(fp_line
			(start -0.67945 0.3048)
			(end -0.120396 0.3048)
			(stroke
				(width 0.1)
				(type default)
			)
			(layer "B.Fab")
		)
		(pad "1" smd circle
			(at 0.40005 0 270)
			(size 0 0)
			(layers "B.Cu" "B.Mask" "B.Paste")
			(net "P52V_HS1_GATE1_R")
		)
		(pad "2" smd circle
			(at -0.40005 0 270)
			(size 0 0)
			(layers "B.Cu" "B.Mask" "B.Paste")
			(net "P52V_HS1_1272_GATE")
		)
	)
	(footprint ""
		(layer "B.Cu")
		(at 227.076 -74.93 180)
		(property "Reference" "U27"
			(at -0.508 2.25933 0)
			(unlocked yes)
			(layer "B.SilkS")
			(effects
				(font
					(size 0.7874 0.5842)
					(thickness 0.1524)
				)
				(justify left mirror)
			)
		)
		(property "Value" ""
			(at 0 0 0)
			(layer "B.Fab")
			(effects
				(font
					(size 1.27 1.27)
				)
				(justify mirror)
			)
		)
		(duplicate_pad_numbers_are_jumpers no)
		(fp_line
			(start 1.603248 1.500124)
			(end 1.603248 -1.500124)
			(stroke
				(width 0.1524)
				(type default)
			)
			(layer "B.SilkS")
		)
		(fp_line
			(start 1.603248 -1.500124)
			(end -1.603248 -1.500124)
			(stroke
				(width 0.1524)
				(type default)
			)
			(layer "B.SilkS")
		)
		(fp_line
			(start -1.603248 1.500124)
			(end 1.603248 1.500124)
			(stroke
				(width 0.1524)
				(type default)
			)
			(layer "B.SilkS")
		)
		(fp_line
			(start -1.603248 -1.500124)
			(end -1.603248 1.500124)
			(stroke
				(width 0.1524)
				(type default)
			)
			(layer "B.SilkS")
		)
		(fp_line
			(start 1.249934 1.169924)
			(end 0.700024 1.169924)
			(stroke
				(width 0.1)
				(type default)
			)
			(layer "B.Fab")
		)
		(fp_line
			(start 1.249934 0.729996)
			(end 1.249934 1.169924)
			(stroke
				(width 0.1)
				(type default)
			)
			(layer "B.Fab")
		)
		(fp_line
			(start 1.249934 -0.729996)
			(end 0.6985 -0.729996)
			(stroke
				(width 0.1)
				(type default)
			)
			(layer "B.Fab")
		)
		(fp_line
			(start 1.249934 -1.169924)
			(end 1.249934 -0.729996)
			(stroke
				(width 0.1)
				(type default)
			)
			(layer "B.Fab")
		)
		(fp_line
			(start 0.700024 1.500124)
			(end -0.700024 1.500124)
			(stroke
				(width 0.1)
				(type default)
			)
			(layer "B.Fab")
		)
		(fp_line
			(start 0.700024 1.169924)
			(end 0.700024 1.500124)
			(stroke
				(width 0.1)
				(type default)
			)
			(layer "B.Fab")
		)
		(fp_line
			(start 0.700024 -1.169924)
			(end 1.249934 -1.169924)
			(stroke
				(width 0.1)
				(type default)
			)
			(layer "B.Fab")
		)
		(fp_line
			(start 0.700024 -1.500124)
			(end 0.700024 -1.169924)
			(stroke
				(width 0.1)
				(type default)
			)
			(layer "B.Fab")
		)
		(fp_line
			(start 0.6985 0.729996)
			(end 1.249934 0.729996)
			(stroke
				(width 0.1)
				(type default)
			)
			(layer "B.Fab")
		)
		(fp_line
			(start 0.6985 -0.729996)
			(end 0.6985 0.729996)
			(stroke
				(width 0.1)
				(type default)
			)
			(layer "B.Fab")
		)
		(fp_line
			(start -0.700024 1.500124)
			(end -0.700024 0.219964)
			(stroke
				(width 0.1)
				(type default)
			)
			(layer "B.Fab")
		)
		(fp_line
			(start -0.700024 0.219964)
			(end -1.249934 0.219964)
			(stroke
				(width 0.1)
				(type default)
			)
			(layer "B.Fab")
		)
		(fp_line
			(start -0.700024 -0.219964)
			(end -0.700024 -1.500124)
			(stroke
				(width 0.1)
				(type default)
			)
			(layer "B.Fab")
		)
		(fp_line
			(start -0.700024 -1.500124)
			(end 0.700024 -1.500124)
			(stroke
				(width 0.1)
				(type default)
			)
			(layer "B.Fab")
		)
		(fp_line
			(start -1.249934 0.219964)
			(end -1.249934 -0.219964)
			(stroke
				(width 0.1)
				(type default)
			)
			(layer "B.Fab")
		)
		(fp_line
			(start -1.249934 -0.219964)
			(end -0.700024 -0.219964)
			(stroke
				(width 0.1)
				(type default)
			)
			(layer "B.Fab")
		)
		(fp_rect
			(start 0.700024 -1.500124)
			(end -0.700024 1.500124)
			(stroke
				(width 0)
				(type default)
			)
			(fill no)
			(layer "B.Fab")
		)
		(pad "D" smd rect
			(at -0.999998 0 90)
			(size 0.8128 0.9144)
			(layers "B.Cu" "B.Mask" "B.Paste")
			(net "P12V_BRICK_PWRGD_N")
		)
		(pad "G" smd rect
			(at 0.999998 -0.94996 90)
			(size 0.8128 0.9144)
			(layers "B.Cu" "B.Mask" "B.Paste")
			(net "P12V_BRICK_PWRGD")
		)
		(pad "S" smd rect
			(at 0.999998 0.94996 90)
			(size 0.8128 0.9144)
			(layers "B.Cu" "B.Mask" "B.Paste")
			(net "GND")
		)
	)
	(footprint ""
		(layer "B.Cu")
		(at 278.388318 -154.315668 90)
		(property "Reference" "J11"
			(at 1.386332 -5.633974 270)
			(unlocked yes)
			(layer "B.SilkS")
			(effects
				(font
					(size 0.7874 0.5842)
					(thickness 0.1524)
				)
				(justify left mirror)
			)
		)
		(property "Value" ""
			(at 0 0 90)
			(layer "B.Fab")
			(effects
				(font
					(size 1.27 1.27)
				)
				(justify mirror)
			)
		)
		(duplicate_pad_numbers_are_jumpers no)
		(fp_line
			(start 3.330702 -4.771136)
			(end -3.330702 -4.771136)
			(stroke
				(width 0.1524)
				(type default)
			)
			(layer "B.SilkS")
		)
		(fp_line
			(start -3.330702 -4.771136)
			(end 0 4.011168)
			(stroke
				(width 0.1524)
				(type default)
			)
			(layer "B.SilkS")
		)
		(fp_line
			(start 0 4.011168)
			(end 3.330702 -4.771136)
			(stroke
				(width 0.1524)
				(type default)
			)
			(layer "B.SilkS")
		)
		(fp_line
			(start 3.330702 -4.771136)
			(end -3.330702 -4.771136)
			(stroke
				(width 0.1)
				(type default)
			)
			(layer "B.Fab")
		)
		(fp_line
			(start -3.330702 -4.771136)
			(end 0 4.011168)
			(stroke
				(width 0.1)
				(type default)
			)
			(layer "B.Fab")
		)
		(fp_line
			(start 0 4.011168)
			(end 3.330702 -4.771136)
			(stroke
				(width 0.1)
				(type default)
			)
			(layer "B.Fab")
		)
		(pad "1" thru_hole circle
			(at 0 0 270)
			(size 2.159 2.159)
			(drill 1.7018)
			(layers "*.Cu" "*.Mask")
			(remove_unused_layers no)
			(net "GND3")
			(clearance 0.0254)
			(thermal_gap 0.0254)
		)
		(pad "2" thru_hole circle
			(at 1.27 -3.348736 270)
			(size 2.159 2.159)
			(drill 1.7018)
			(layers "*.Cu" "*.Mask")
			(remove_unused_layers no)
			(net "TDR_SE_50_OHM_BOT")
			(clearance 0.0254)
			(thermal_gap 0.0254)
		)
		(pad "3" thru_hole circle
			(at -1.27 -3.348736 270)
			(size 2.159 2.159)
			(drill 1.7018)
			(layers "*.Cu" "*.Mask")
			(remove_unused_layers no)
			(net "TDR_SE_50_OHM_BOT")
			(clearance 0.0254)
			(thermal_gap 0.0254)
		)
	)
	(footprint ""
		(layer "B.Cu")
		(at 277.709122 -105.268522 90)
		(property "Reference" "PC8"
			(at 0 0 90)
			(layer "B.SilkS")
			(hide yes)
			(effects
				(font
					(size 1.27 1.27)
				)
				(justify mirror)
			)
		)
		(property "Value" ""
			(at 0 0 90)
			(layer "B.Fab")
			(effects
				(font
					(size 1.27 1.27)
				)
				(justify mirror)
			)
		)
		(duplicate_pad_numbers_are_jumpers no)
		(fp_line
			(start 1.2954 -0.5842)
			(end -1.2954 -0.5842)
			(stroke
				(width 0.1524)
				(type default)
			)
			(layer "B.SilkS")
		)
		(fp_line
			(start -1.2954 -0.5842)
			(end -1.2954 0.5842)
			(stroke
				(width 0.1524)
				(type default)
			)
			(layer "B.SilkS")
		)
		(fp_line
			(start 1.2954 0.5842)
			(end 1.2954 -0.5842)
			(stroke
				(width 0.1524)
				(type default)
			)
			(layer "B.SilkS")
		)
		(fp_line
			(start -1.2954 0.5842)
			(end 1.2954 0.5842)
			(stroke
				(width 0.1524)
				(type default)
			)
			(layer "B.SilkS")
		)
		(fp_line
			(start 0.8636 -0.4572)
			(end -0.8636 -0.4572)
			(stroke
				(width 0.1)
				(type default)
			)
			(layer "B.Fab")
		)
		(fp_line
			(start -0.8636 -0.4572)
			(end -0.8636 -0.4064)
			(stroke
				(width 0.1)
				(type default)
			)
			(layer "B.Fab")
		)
		(fp_line
			(start 1.1938 -0.4064)
			(end 0.8636 -0.4064)
			(stroke
				(width 0.1)
				(type default)
			)
			(layer "B.Fab")
		)
		(fp_line
			(start 0.8636 -0.4064)
			(end 0.8636 -0.4572)
			(stroke
				(width 0.1)
				(type default)
			)
			(layer "B.Fab")
		)
		(fp_line
			(start -0.8636 -0.4064)
			(end -1.1938 -0.4064)
			(stroke
				(width 0.1)
				(type default)
			)
			(layer "B.Fab")
		)
		(fp_line
			(start -1.1938 -0.4064)
			(end -1.1938 0.4064)
			(stroke
				(width 0.1)
				(type default)
			)
			(layer "B.Fab")
		)
		(fp_line
			(start 1.1938 0.4064)
			(end 1.1938 -0.4064)
			(stroke
				(width 0.1)
				(type default)
			)
			(layer "B.Fab")
		)
		(fp_line
			(start 0.8636 0.4064)
			(end 1.1938 0.4064)
			(stroke
				(width 0.1)
				(type default)
			)
			(layer "B.Fab")
		)
		(fp_line
			(start -0.8636 0.4064)
			(end -0.8636 0.4572)
			(stroke
				(width 0.1)
				(type default)
			)
			(layer "B.Fab")
		)
		(fp_line
			(start -1.1938 0.4064)
			(end -0.8636 0.4064)
			(stroke
				(width 0.1)
				(type default)
			)
			(layer "B.Fab")
		)
		(fp_line
			(start 0.8636 0.4572)
			(end 0.8636 0.4064)
			(stroke
				(width 0.1)
				(type default)
			)
			(layer "B.Fab")
		)
		(fp_line
			(start -0.8636 0.4572)
			(end 0.8636 0.4572)
			(stroke
				(width 0.1)
				(type default)
			)
			(layer "B.Fab")
		)
		(pad "1" smd rect
			(at 0.7366 0)
			(size 0.7112 0.8128)
			(layers "B.Cu" "B.Mask" "B.Paste")
			(net "GND")
		)
		(pad "2" smd rect
			(at -0.7366 0)
			(size 0.7112 0.8128)
			(layers "B.Cu" "B.Mask" "B.Paste")
			(net "P52V_HS1_GATE_R1")
		)
	)
	(footprint ""
		(layer "B.Cu")
		(at 214.884 -67.183 90)
		(property "Reference" "R136"
			(at 0 0 90)
			(layer "B.SilkS")
			(hide yes)
			(effects
				(font
					(size 1.27 1.27)
				)
				(justify mirror)
			)
		)
		(property "Value" ""
			(at 0 0 90)
			(layer "B.Fab")
			(effects
				(font
					(size 1.27 1.27)
				)
				(justify mirror)
			)
		)
		(duplicate_pad_numbers_are_jumpers no)
		(fp_line
			(start 0.7874 -0.4064)
			(end -0.7874 -0.4064)
			(stroke
				(width 0.1524)
				(type default)
			)
			(layer "B.SilkS")
		)
		(fp_line
			(start -0.7874 -0.4064)
			(end -0.7874 0.4064)
			(stroke
				(width 0.1524)
				(type default)
			)
			(layer "B.SilkS")
		)
		(fp_line
			(start 0.7874 0.4064)
			(end 0.7874 -0.4064)
			(stroke
				(width 0.1524)
				(type default)
			)
			(layer "B.SilkS")
		)
		(fp_line
			(start -0.7874 0.4064)
			(end 0.7874 0.4064)
			(stroke
				(width 0.1524)
				(type default)
			)
			(layer "B.SilkS")
		)
		(fp_line
			(start 0.67945 -0.305054)
			(end 0.12065 -0.305054)
			(stroke
				(width 0.1)
				(type default)
			)
			(layer "B.Fab")
		)
		(fp_line
			(start 0.12065 -0.305054)
			(end 0.12065 -0.2794)
			(stroke
				(width 0.1)
				(type default)
			)
			(layer "B.Fab")
		)
		(fp_line
			(start -0.12065 -0.3048)
			(end -0.67945 -0.3048)
			(stroke
				(width 0.1)
				(type default)
			)
			(layer "B.Fab")
		)
		(fp_line
			(start -0.67945 -0.3048)
			(end -0.67945 0.3048)
			(stroke
				(width 0.1)
				(type default)
			)
			(layer "B.Fab")
		)
		(fp_line
			(start 0.12065 -0.2794)
			(end -0.12065 -0.2794)
			(stroke
				(width 0.1)
				(type default)
			)
			(layer "B.Fab")
		)
		(fp_line
			(start -0.12065 -0.2794)
			(end -0.12065 -0.3048)
			(stroke
				(width 0.1)
				(type default)
			)
			(layer "B.Fab")
		)
		(fp_line
			(start 0.12065 0.2794)
			(end 0.12065 0.3048)
			(stroke
				(width 0.1)
				(type default)
			)
			(layer "B.Fab")
		)
		(fp_line
			(start -0.120396 0.2794)
			(end 0.12065 0.2794)
			(stroke
				(width 0.1)
				(type default)
			)
			(layer "B.Fab")
		)
		(fp_line
			(start 0.67945 0.3048)
			(end 0.67945 -0.305054)
			(stroke
				(width 0.1)
				(type default)
			)
			(layer "B.Fab")
		)
		(fp_line
			(start 0.12065 0.3048)
			(end 0.67945 0.3048)
			(stroke
				(width 0.1)
				(type default)
			)
			(layer "B.Fab")
		)
		(fp_line
			(start -0.120396 0.3048)
			(end -0.120396 0.2794)
			(stroke
				(width 0.1)
				(type default)
			)
			(layer "B.Fab")
		)
		(fp_line
			(start -0.67945 0.3048)
			(end -0.120396 0.3048)
			(stroke
				(width 0.1)
				(type default)
			)
			(layer "B.Fab")
		)
		(pad "1" smd circle
			(at 0.40005 0 270)
			(size 0 0)
			(layers "B.Cu" "B.Mask" "B.Paste")
			(net "BOARD_ID_2")
		)
		(pad "2" smd circle
			(at -0.40005 0 270)
			(size 0 0)
			(layers "B.Cu" "B.Mask" "B.Paste")
			(net "GND")
		)
	)
	(footprint ""
		(layer "B.Cu")
		(at 176.850294 -116.078 -90)
		(property "Reference" "R195"
			(at 0 0 90)
			(layer "B.SilkS")
			(hide yes)
			(effects
				(font
					(size 1.27 1.27)
				)
				(justify mirror)
			)
		)
		(property "Value" ""
			(at 0 0 90)
			(layer "B.Fab")
			(effects
				(font
					(size 1.27 1.27)
				)
				(justify mirror)
			)
		)
		(duplicate_pad_numbers_are_jumpers no)
		(fp_line
			(start -0.7874 0.4064)
			(end 0.7874 0.4064)
			(stroke
				(width 0.1524)
				(type default)
			)
			(layer "B.SilkS")
		)
		(fp_line
			(start 0.7874 0.4064)
			(end 0.7874 -0.4064)
			(stroke
				(width 0.1524)
				(type default)
			)
			(layer "B.SilkS")
		)
		(fp_line
			(start -0.7874 -0.4064)
			(end -0.7874 0.4064)
			(stroke
				(width 0.1524)
				(type default)
			)
			(layer "B.SilkS")
		)
		(fp_line
			(start 0.7874 -0.4064)
			(end -0.7874 -0.4064)
			(stroke
				(width 0.1524)
				(type default)
			)
			(layer "B.SilkS")
		)
		(fp_line
			(start -0.67945 0.3048)
			(end -0.120396 0.3048)
			(stroke
				(width 0.1)
				(type default)
			)
			(layer "B.Fab")
		)
		(fp_line
			(start -0.120396 0.3048)
			(end -0.120396 0.2794)
			(stroke
				(width 0.1)
				(type default)
			)
			(layer "B.Fab")
		)
		(fp_line
			(start 0.12065 0.3048)
			(end 0.67945 0.3048)
			(stroke
				(width 0.1)
				(type default)
			)
			(layer "B.Fab")
		)
		(fp_line
			(start 0.67945 0.3048)
			(end 0.67945 -0.305054)
			(stroke
				(width 0.1)
				(type default)
			)
			(layer "B.Fab")
		)
		(fp_line
			(start -0.120396 0.2794)
			(end 0.12065 0.2794)
			(stroke
				(width 0.1)
				(type default)
			)
			(layer "B.Fab")
		)
		(fp_line
			(start 0.12065 0.2794)
			(end 0.12065 0.3048)
			(stroke
				(width 0.1)
				(type default)
			)
			(layer "B.Fab")
		)
		(fp_line
			(start -0.12065 -0.2794)
			(end -0.12065 -0.3048)
			(stroke
				(width 0.1)
				(type default)
			)
			(layer "B.Fab")
		)
		(fp_line
			(start 0.12065 -0.2794)
			(end -0.12065 -0.2794)
			(stroke
				(width 0.1)
				(type default)
			)
			(layer "B.Fab")
		)
		(fp_line
			(start -0.67945 -0.3048)
			(end -0.67945 0.3048)
			(stroke
				(width 0.1)
				(type default)
			)
			(layer "B.Fab")
		)
		(fp_line
			(start -0.12065 -0.3048)
			(end -0.67945 -0.3048)
			(stroke
				(width 0.1)
				(type default)
			)
			(layer "B.Fab")
		)
		(fp_line
			(start 0.12065 -0.305054)
			(end 0.12065 -0.2794)
			(stroke
				(width 0.1)
				(type default)
			)
			(layer "B.Fab")
		)
		(fp_line
			(start 0.67945 -0.305054)
			(end 0.12065 -0.305054)
			(stroke
				(width 0.1)
				(type default)
			)
			(layer "B.Fab")
		)
		(pad "1" smd circle
			(at 0.40005 0 90)
			(size 0 0)
			(layers "B.Cu" "B.Mask" "B.Paste")
			(net "BRICK_P12V_1_EN_N")
		)
		(pad "2" smd circle
			(at -0.40005 0 90)
			(size 0 0)
			(layers "B.Cu" "B.Mask" "B.Paste")
			(net "BRICK_P12V2_ON_OFF_R")
		)
	)
	(footprint ""
		(layer "B.Cu")
		(at 276.733 -42.545)
		(property "Reference" "PR37"
			(at 0 0 0)
			(layer "B.SilkS")
			(hide yes)
			(effects
				(font
					(size 1.27 1.27)
				)
				(justify mirror)
			)
		)
		(property "Value" ""
			(at 0 0 0)
			(layer "B.Fab")
			(effects
				(font
					(size 1.27 1.27)
				)
				(justify mirror)
			)
		)
		(duplicate_pad_numbers_are_jumpers no)
		(fp_line
			(start -0.7874 -0.4064)
			(end -0.7874 0.4064)
			(stroke
				(width 0.1524)
				(type default)
			)
			(layer "B.SilkS")
		)
		(fp_line
			(start -0.7874 0.4064)
			(end 0.7874 0.4064)
			(stroke
				(width 0.1524)
				(type default)
			)
			(layer "B.SilkS")
		)
		(fp_line
			(start 0.7874 -0.4064)
			(end -0.7874 -0.4064)
			(stroke
				(width 0.1524)
				(type default)
			)
			(layer "B.SilkS")
		)
		(fp_line
			(start 0.7874 0.4064)
			(end 0.7874 -0.4064)
			(stroke
				(width 0.1524)
				(type default)
			)
			(layer "B.SilkS")
		)
		(fp_line
			(start -0.67945 -0.3048)
			(end -0.67945 0.3048)
			(stroke
				(width 0.1)
				(type default)
			)
			(layer "B.Fab")
		)
		(fp_line
			(start -0.67945 0.3048)
			(end -0.120396 0.3048)
			(stroke
				(width 0.1)
				(type default)
			)
			(layer "B.Fab")
		)
		(fp_line
			(start -0.12065 -0.3048)
			(end -0.67945 -0.3048)
			(stroke
				(width 0.1)
				(type default)
			)
			(layer "B.Fab")
		)
		(fp_line
			(start -0.12065 -0.2794)
			(end -0.12065 -0.3048)
			(stroke
				(width 0.1)
				(type default)
			)
			(layer "B.Fab")
		)
		(fp_line
			(start -0.120396 0.2794)
			(end 0.12065 0.2794)
			(stroke
				(width 0.1)
				(type default)
			)
			(layer "B.Fab")
		)
		(fp_line
			(start -0.120396 0.3048)
			(end -0.120396 0.2794)
			(stroke
				(width 0.1)
				(type default)
			)
			(layer "B.Fab")
		)
		(fp_line
			(start 0.12065 -0.305054)
			(end 0.12065 -0.2794)
			(stroke
				(width 0.1)
				(type default)
			)
			(layer "B.Fab")
		)
		(fp_line
			(start 0.12065 -0.2794)
			(end -0.12065 -0.2794)
			(stroke
				(width 0.1)
				(type default)
			)
			(layer "B.Fab")
		)
		(fp_line
			(start 0.12065 0.2794)
			(end 0.12065 0.3048)
			(stroke
				(width 0.1)
				(type default)
			)
			(layer "B.Fab")
		)
		(fp_line
			(start 0.12065 0.3048)
			(end 0.67945 0.3048)
			(stroke
				(width 0.1)
				(type default)
			)
			(layer "B.Fab")
		)
		(fp_line
			(start 0.67945 -0.305054)
			(end 0.12065 -0.305054)
			(stroke
				(width 0.1)
				(type default)
			)
			(layer "B.Fab")
		)
		(fp_line
			(start 0.67945 0.3048)
			(end 0.67945 -0.305054)
			(stroke
				(width 0.1)
				(type default)
			)
			(layer "B.Fab")
		)
		(pad "1" smd circle
			(at 0.40005 0 180)
			(size 0 0)
			(layers "B.Cu" "B.Mask" "B.Paste")
			(net "P52V_HS1_EFAULT")
		)
		(pad "2" smd circle
			(at -0.40005 0 180)
			(size 0 0)
			(layers "B.Cu" "B.Mask" "B.Paste")
			(net "GND_FIELD_SIGNAL")
		)
	)
	(footprint ""
		(layer "B.Cu")
		(at 212.344 -84.455 180)
		(property "Reference" "R189"
			(at 0 0 0)
			(layer "B.SilkS")
			(hide yes)
			(effects
				(font
					(size 1.27 1.27)
				)
				(justify mirror)
			)
		)
		(property "Value" ""
			(at 0 0 0)
			(layer "B.Fab")
			(effects
				(font
					(size 1.27 1.27)
				)
				(justify mirror)
			)
		)
		(duplicate_pad_numbers_are_jumpers no)
		(fp_line
			(start 0.7874 0.4064)
			(end 0.7874 -0.4064)
			(stroke
				(width 0.1524)
				(type default)
			)
			(layer "B.SilkS")
		)
		(fp_line
			(start 0.7874 -0.4064)
			(end -0.7874 -0.4064)
			(stroke
				(width 0.1524)
				(type default)
			)
			(layer "B.SilkS")
		)
		(fp_line
			(start -0.7874 0.4064)
			(end 0.7874 0.4064)
			(stroke
				(width 0.1524)
				(type default)
			)
			(layer "B.SilkS")
		)
		(fp_line
			(start -0.7874 -0.4064)
			(end -0.7874 0.4064)
			(stroke
				(width 0.1524)
				(type default)
			)
			(layer "B.SilkS")
		)
		(fp_line
			(start 0.67945 0.3048)
			(end 0.67945 -0.305054)
			(stroke
				(width 0.1)
				(type default)
			)
			(layer "B.Fab")
		)
		(fp_line
			(start 0.67945 -0.305054)
			(end 0.12065 -0.305054)
			(stroke
				(width 0.1)
				(type default)
			)
			(layer "B.Fab")
		)
		(fp_line
			(start 0.12065 0.3048)
			(end 0.67945 0.3048)
			(stroke
				(width 0.1)
				(type default)
			)
			(layer "B.Fab")
		)
		(fp_line
			(start 0.12065 0.2794)
			(end 0.12065 0.3048)
			(stroke
				(width 0.1)
				(type default)
			)
			(layer "B.Fab")
		)
		(fp_line
			(start 0.12065 -0.2794)
			(end -0.12065 -0.2794)
			(stroke
				(width 0.1)
				(type default)
			)
			(layer "B.Fab")
		)
		(fp_line
			(start 0.12065 -0.305054)
			(end 0.12065 -0.2794)
			(stroke
				(width 0.1)
				(type default)
			)
			(layer "B.Fab")
		)
		(fp_line
			(start -0.120396 0.3048)
			(end -0.120396 0.2794)
			(stroke
				(width 0.1)
				(type default)
			)
			(layer "B.Fab")
		)
		(fp_line
			(start -0.120396 0.2794)
			(end 0.12065 0.2794)
			(stroke
				(width 0.1)
				(type default)
			)
			(layer "B.Fab")
		)
		(fp_line
			(start -0.12065 -0.2794)
			(end -0.12065 -0.3048)
			(stroke
				(width 0.1)
				(type default)
			)
			(layer "B.Fab")
		)
		(fp_line
			(start -0.12065 -0.3048)
			(end -0.67945 -0.3048)
			(stroke
				(width 0.1)
				(type default)
			)
			(layer "B.Fab")
		)
		(fp_line
			(start -0.67945 0.3048)
			(end -0.120396 0.3048)
			(stroke
				(width 0.1)
				(type default)
			)
			(layer "B.Fab")
		)
		(fp_line
			(start -0.67945 -0.3048)
			(end -0.67945 0.3048)
			(stroke
				(width 0.1)
				(type default)
			)
			(layer "B.Fab")
		)
		(pad "1" smd circle
			(at 0.40005 0)
			(size 0 0)
			(layers "B.Cu" "B.Mask" "B.Paste")
			(net "PWRGD_GPU_HSC")
		)
		(pad "2" smd circle
			(at -0.40005 0)
			(size 0 0)
			(layers "B.Cu" "B.Mask" "B.Paste")
			(net "PWRGD_GPU_HSC_BUF_R")
		)
	)
	(footprint ""
		(layer "B.Cu")
		(at 98.806 -77.47 180)
		(property "Reference" "C57"
			(at 0 0 0)
			(layer "B.SilkS")
			(hide yes)
			(effects
				(font
					(size 1.27 1.27)
				)
				(justify mirror)
			)
		)
		(property "Value" ""
			(at 0 0 0)
			(layer "B.Fab")
			(effects
				(font
					(size 1.27 1.27)
				)
				(justify mirror)
			)
		)
		(duplicate_pad_numbers_are_jumpers no)
		(fp_line
			(start 0.7874 0.4064)
			(end 0.7874 -0.4064)
			(stroke
				(width 0.1524)
				(type default)
			)
			(layer "B.SilkS")
		)
		(fp_line
			(start 0.7874 -0.4064)
			(end -0.7874 -0.4064)
			(stroke
				(width 0.1524)
				(type default)
			)
			(layer "B.SilkS")
		)
		(fp_line
			(start -0.7874 0.4064)
			(end 0.7874 0.4064)
			(stroke
				(width 0.1524)
				(type default)
			)
			(layer "B.SilkS")
		)
		(fp_line
			(start -0.7874 -0.4064)
			(end -0.7874 0.4064)
			(stroke
				(width 0.1524)
				(type default)
			)
			(layer "B.SilkS")
		)
		(fp_line
			(start 0.67945 0.3048)
			(end 0.67945 -0.305054)
			(stroke
				(width 0.1)
				(type default)
			)
			(layer "B.Fab")
		)
		(fp_line
			(start 0.67945 -0.305054)
			(end 0.12065 -0.305054)
			(stroke
				(width 0.1)
				(type default)
			)
			(layer "B.Fab")
		)
		(fp_line
			(start 0.12065 0.3048)
			(end 0.67945 0.3048)
			(stroke
				(width 0.1)
				(type default)
			)
			(layer "B.Fab")
		)
		(fp_line
			(start 0.12065 0.2794)
			(end 0.12065 0.3048)
			(stroke
				(width 0.1)
				(type default)
			)
			(layer "B.Fab")
		)
		(fp_line
			(start 0.12065 -0.2794)
			(end -0.12065 -0.2794)
			(stroke
				(width 0.1)
				(type default)
			)
			(layer "B.Fab")
		)
		(fp_line
			(start 0.12065 -0.305054)
			(end 0.12065 -0.2794)
			(stroke
				(width 0.1)
				(type default)
			)
			(layer "B.Fab")
		)
		(fp_line
			(start -0.120396 0.3048)
			(end -0.120396 0.2794)
			(stroke
				(width 0.1)
				(type default)
			)
			(layer "B.Fab")
		)
		(fp_line
			(start -0.120396 0.2794)
			(end 0.12065 0.2794)
			(stroke
				(width 0.1)
				(type default)
			)
			(layer "B.Fab")
		)
		(fp_line
			(start -0.12065 -0.2794)
			(end -0.12065 -0.3048)
			(stroke
				(width 0.1)
				(type default)
			)
			(layer "B.Fab")
		)
		(fp_line
			(start -0.12065 -0.3048)
			(end -0.67945 -0.3048)
			(stroke
				(width 0.1)
				(type default)
			)
			(layer "B.Fab")
		)
		(fp_line
			(start -0.67945 0.3048)
			(end -0.120396 0.3048)
			(stroke
				(width 0.1)
				(type default)
			)
			(layer "B.Fab")
		)
		(fp_line
			(start -0.67945 -0.3048)
			(end -0.67945 0.3048)
			(stroke
				(width 0.1)
				(type default)
			)
			(layer "B.Fab")
		)
		(pad "1" smd circle
			(at 0.40005 0)
			(size 0 0)
			(layers "B.Cu" "B.Mask" "B.Paste")
			(net "SMB_P52V_VPDB_SDA")
		)
		(pad "2" smd circle
			(at -0.40005 0)
			(size 0 0)
			(layers "B.Cu" "B.Mask" "B.Paste")
			(net "GND")
		)
	)
	(footprint ""
		(layer "B.Cu")
		(at 229.87 -70.993 -90)
		(property "Reference" "C17"
			(at 0 0 90)
			(layer "B.SilkS")
			(hide yes)
			(effects
				(font
					(size 1.27 1.27)
				)
				(justify mirror)
			)
		)
		(property "Value" ""
			(at 0 0 90)
			(layer "B.Fab")
			(effects
				(font
					(size 1.27 1.27)
				)
				(justify mirror)
			)
		)
		(duplicate_pad_numbers_are_jumpers no)
		(fp_line
			(start -0.7874 0.4064)
			(end 0.7874 0.4064)
			(stroke
				(width 0.1524)
				(type default)
			)
			(layer "B.SilkS")
		)
		(fp_line
			(start 0.7874 0.4064)
			(end 0.7874 -0.4064)
			(stroke
				(width 0.1524)
				(type default)
			)
			(layer "B.SilkS")
		)
		(fp_line
			(start -0.7874 -0.4064)
			(end -0.7874 0.4064)
			(stroke
				(width 0.1524)
				(type default)
			)
			(layer "B.SilkS")
		)
		(fp_line
			(start 0.7874 -0.4064)
			(end -0.7874 -0.4064)
			(stroke
				(width 0.1524)
				(type default)
			)
			(layer "B.SilkS")
		)
		(fp_line
			(start -0.67945 0.3048)
			(end -0.120396 0.3048)
			(stroke
				(width 0.1)
				(type default)
			)
			(layer "B.Fab")
		)
		(fp_line
			(start -0.120396 0.3048)
			(end -0.120396 0.2794)
			(stroke
				(width 0.1)
				(type default)
			)
			(layer "B.Fab")
		)
		(fp_line
			(start 0.12065 0.3048)
			(end 0.67945 0.3048)
			(stroke
				(width 0.1)
				(type default)
			)
			(layer "B.Fab")
		)
		(fp_line
			(start 0.67945 0.3048)
			(end 0.67945 -0.305054)
			(stroke
				(width 0.1)
				(type default)
			)
			(layer "B.Fab")
		)
		(fp_line
			(start -0.120396 0.2794)
			(end 0.12065 0.2794)
			(stroke
				(width 0.1)
				(type default)
			)
			(layer "B.Fab")
		)
		(fp_line
			(start 0.12065 0.2794)
			(end 0.12065 0.3048)
			(stroke
				(width 0.1)
				(type default)
			)
			(layer "B.Fab")
		)
		(fp_line
			(start -0.12065 -0.2794)
			(end -0.12065 -0.3048)
			(stroke
				(width 0.1)
				(type default)
			)
			(layer "B.Fab")
		)
		(fp_line
			(start 0.12065 -0.2794)
			(end -0.12065 -0.2794)
			(stroke
				(width 0.1)
				(type default)
			)
			(layer "B.Fab")
		)
		(fp_line
			(start -0.67945 -0.3048)
			(end -0.67945 0.3048)
			(stroke
				(width 0.1)
				(type default)
			)
			(layer "B.Fab")
		)
		(fp_line
			(start -0.12065 -0.3048)
			(end -0.67945 -0.3048)
			(stroke
				(width 0.1)
				(type default)
			)
			(layer "B.Fab")
		)
		(fp_line
			(start 0.12065 -0.305054)
			(end 0.12065 -0.2794)
			(stroke
				(width 0.1)
				(type default)
			)
			(layer "B.Fab")
		)
		(fp_line
			(start 0.67945 -0.305054)
			(end 0.12065 -0.305054)
			(stroke
				(width 0.1)
				(type default)
			)
			(layer "B.Fab")
		)
		(pad "1" smd circle
			(at 0.40005 0 90)
			(size 0 0)
			(layers "B.Cu" "B.Mask" "B.Paste")
			(net "FAN_PWR_R_EN")
		)
		(pad "2" smd circle
			(at -0.40005 0 90)
			(size 0 0)
			(layers "B.Cu" "B.Mask" "B.Paste")
			(net "GND")
		)
	)
	(footprint ""
		(layer "B.Cu")
		(at 207.264 -69.723 -90)
		(property "Reference" "R117"
			(at 0 0 90)
			(layer "B.SilkS")
			(hide yes)
			(effects
				(font
					(size 1.27 1.27)
				)
				(justify mirror)
			)
		)
		(property "Value" ""
			(at 0 0 90)
			(layer "B.Fab")
			(effects
				(font
					(size 1.27 1.27)
				)
				(justify mirror)
			)
		)
		(duplicate_pad_numbers_are_jumpers no)
		(fp_line
			(start -0.7874 0.4064)
			(end 0.7874 0.4064)
			(stroke
				(width 0.1524)
				(type default)
			)
			(layer "B.SilkS")
		)
		(fp_line
			(start 0.7874 0.4064)
			(end 0.7874 -0.4064)
			(stroke
				(width 0.1524)
				(type default)
			)
			(layer "B.SilkS")
		)
		(fp_line
			(start -0.7874 -0.4064)
			(end -0.7874 0.4064)
			(stroke
				(width 0.1524)
				(type default)
			)
			(layer "B.SilkS")
		)
		(fp_line
			(start 0.7874 -0.4064)
			(end -0.7874 -0.4064)
			(stroke
				(width 0.1524)
				(type default)
			)
			(layer "B.SilkS")
		)
		(fp_line
			(start -0.67945 0.3048)
			(end -0.120396 0.3048)
			(stroke
				(width 0.1)
				(type default)
			)
			(layer "B.Fab")
		)
		(fp_line
			(start -0.120396 0.3048)
			(end -0.120396 0.2794)
			(stroke
				(width 0.1)
				(type default)
			)
			(layer "B.Fab")
		)
		(fp_line
			(start 0.12065 0.3048)
			(end 0.67945 0.3048)
			(stroke
				(width 0.1)
				(type default)
			)
			(layer "B.Fab")
		)
		(fp_line
			(start 0.67945 0.3048)
			(end 0.67945 -0.305054)
			(stroke
				(width 0.1)
				(type default)
			)
			(layer "B.Fab")
		)
		(fp_line
			(start -0.120396 0.2794)
			(end 0.12065 0.2794)
			(stroke
				(width 0.1)
				(type default)
			)
			(layer "B.Fab")
		)
		(fp_line
			(start 0.12065 0.2794)
			(end 0.12065 0.3048)
			(stroke
				(width 0.1)
				(type default)
			)
			(layer "B.Fab")
		)
		(fp_line
			(start -0.12065 -0.2794)
			(end -0.12065 -0.3048)
			(stroke
				(width 0.1)
				(type default)
			)
			(layer "B.Fab")
		)
		(fp_line
			(start 0.12065 -0.2794)
			(end -0.12065 -0.2794)
			(stroke
				(width 0.1)
				(type default)
			)
			(layer "B.Fab")
		)
		(fp_line
			(start -0.67945 -0.3048)
			(end -0.67945 0.3048)
			(stroke
				(width 0.1)
				(type default)
			)
			(layer "B.Fab")
		)
		(fp_line
			(start -0.12065 -0.3048)
			(end -0.67945 -0.3048)
			(stroke
				(width 0.1)
				(type default)
			)
			(layer "B.Fab")
		)
		(fp_line
			(start 0.12065 -0.305054)
			(end 0.12065 -0.2794)
			(stroke
				(width 0.1)
				(type default)
			)
			(layer "B.Fab")
		)
		(fp_line
			(start 0.67945 -0.305054)
			(end 0.12065 -0.305054)
			(stroke
				(width 0.1)
				(type default)
			)
			(layer "B.Fab")
		)
		(pad "1" smd circle
			(at 0.40005 0 90)
			(size 0 0)
			(layers "B.Cu" "B.Mask" "B.Paste")
			(net "SMB_VPDB_MISC_SDA")
		)
		(pad "2" smd circle
			(at -0.40005 0 90)
			(size 0 0)
			(layers "B.Cu" "B.Mask" "B.Paste")
			(net "SMB_VPDB_IOEXP_SDA")
		)
	)
	(footprint ""
		(layer "B.Cu")
		(at 231.013 -84.836 -90)
		(property "Reference" "R142"
			(at 0 0 90)
			(layer "B.SilkS")
			(hide yes)
			(effects
				(font
					(size 1.27 1.27)
				)
				(justify mirror)
			)
		)
		(property "Value" ""
			(at 0 0 90)
			(layer "B.Fab")
			(effects
				(font
					(size 1.27 1.27)
				)
				(justify mirror)
			)
		)
		(duplicate_pad_numbers_are_jumpers no)
		(fp_line
			(start -0.7874 0.4064)
			(end 0.7874 0.4064)
			(stroke
				(width 0.1524)
				(type default)
			)
			(layer "B.SilkS")
		)
		(fp_line
			(start 0.7874 0.4064)
			(end 0.7874 -0.4064)
			(stroke
				(width 0.1524)
				(type default)
			)
			(layer "B.SilkS")
		)
		(fp_line
			(start -0.7874 -0.4064)
			(end -0.7874 0.4064)
			(stroke
				(width 0.1524)
				(type default)
			)
			(layer "B.SilkS")
		)
		(fp_line
			(start 0.7874 -0.4064)
			(end -0.7874 -0.4064)
			(stroke
				(width 0.1524)
				(type default)
			)
			(layer "B.SilkS")
		)
		(fp_line
			(start -0.67945 0.3048)
			(end -0.120396 0.3048)
			(stroke
				(width 0.1)
				(type default)
			)
			(layer "B.Fab")
		)
		(fp_line
			(start -0.120396 0.3048)
			(end -0.120396 0.2794)
			(stroke
				(width 0.1)
				(type default)
			)
			(layer "B.Fab")
		)
		(fp_line
			(start 0.12065 0.3048)
			(end 0.67945 0.3048)
			(stroke
				(width 0.1)
				(type default)
			)
			(layer "B.Fab")
		)
		(fp_line
			(start 0.67945 0.3048)
			(end 0.67945 -0.305054)
			(stroke
				(width 0.1)
				(type default)
			)
			(layer "B.Fab")
		)
		(fp_line
			(start -0.120396 0.2794)
			(end 0.12065 0.2794)
			(stroke
				(width 0.1)
				(type default)
			)
			(layer "B.Fab")
		)
		(fp_line
			(start 0.12065 0.2794)
			(end 0.12065 0.3048)
			(stroke
				(width 0.1)
				(type default)
			)
			(layer "B.Fab")
		)
		(fp_line
			(start -0.12065 -0.2794)
			(end -0.12065 -0.3048)
			(stroke
				(width 0.1)
				(type default)
			)
			(layer "B.Fab")
		)
		(fp_line
			(start 0.12065 -0.2794)
			(end -0.12065 -0.2794)
			(stroke
				(width 0.1)
				(type default)
			)
			(layer "B.Fab")
		)
		(fp_line
			(start -0.67945 -0.3048)
			(end -0.67945 0.3048)
			(stroke
				(width 0.1)
				(type default)
			)
			(layer "B.Fab")
		)
		(fp_line
			(start -0.12065 -0.3048)
			(end -0.67945 -0.3048)
			(stroke
				(width 0.1)
				(type default)
			)
			(layer "B.Fab")
		)
		(fp_line
			(start 0.12065 -0.305054)
			(end 0.12065 -0.2794)
			(stroke
				(width 0.1)
				(type default)
			)
			(layer "B.Fab")
		)
		(fp_line
			(start 0.67945 -0.305054)
			(end 0.12065 -0.305054)
			(stroke
				(width 0.1)
				(type default)
			)
			(layer "B.Fab")
		)
		(pad "1" smd circle
			(at 0.40005 0 90)
			(size 0 0)
			(layers "B.Cu" "B.Mask" "B.Paste")
			(net "P3V3_AUX")
		)
		(pad "2" smd circle
			(at -0.40005 0 90)
			(size 0 0)
			(layers "B.Cu" "B.Mask" "B.Paste")
			(net "PWRGD_P3V3_AUX_MB_BUF_N")
		)
	)
	(footprint ""
		(layer "B.Cu")
		(at 233.68 -91.313 -90)
		(property "Reference" "R34"
			(at 0 0 90)
			(layer "B.SilkS")
			(hide yes)
			(effects
				(font
					(size 1.27 1.27)
				)
				(justify mirror)
			)
		)
		(property "Value" ""
			(at 0 0 90)
			(layer "B.Fab")
			(effects
				(font
					(size 1.27 1.27)
				)
				(justify mirror)
			)
		)
		(duplicate_pad_numbers_are_jumpers no)
		(fp_line
			(start -0.7874 0.4064)
			(end 0.7874 0.4064)
			(stroke
				(width 0.1524)
				(type default)
			)
			(layer "B.SilkS")
		)
		(fp_line
			(start 0.7874 0.4064)
			(end 0.7874 -0.4064)
			(stroke
				(width 0.1524)
				(type default)
			)
			(layer "B.SilkS")
		)
		(fp_line
			(start -0.7874 -0.4064)
			(end -0.7874 0.4064)
			(stroke
				(width 0.1524)
				(type default)
			)
			(layer "B.SilkS")
		)
		(fp_line
			(start 0.7874 -0.4064)
			(end -0.7874 -0.4064)
			(stroke
				(width 0.1524)
				(type default)
			)
			(layer "B.SilkS")
		)
		(fp_line
			(start -0.67945 0.3048)
			(end -0.120396 0.3048)
			(stroke
				(width 0.1)
				(type default)
			)
			(layer "B.Fab")
		)
		(fp_line
			(start -0.120396 0.3048)
			(end -0.120396 0.2794)
			(stroke
				(width 0.1)
				(type default)
			)
			(layer "B.Fab")
		)
		(fp_line
			(start 0.12065 0.3048)
			(end 0.67945 0.3048)
			(stroke
				(width 0.1)
				(type default)
			)
			(layer "B.Fab")
		)
		(fp_line
			(start 0.67945 0.3048)
			(end 0.67945 -0.305054)
			(stroke
				(width 0.1)
				(type default)
			)
			(layer "B.Fab")
		)
		(fp_line
			(start -0.120396 0.2794)
			(end 0.12065 0.2794)
			(stroke
				(width 0.1)
				(type default)
			)
			(layer "B.Fab")
		)
		(fp_line
			(start 0.12065 0.2794)
			(end 0.12065 0.3048)
			(stroke
				(width 0.1)
				(type default)
			)
			(layer "B.Fab")
		)
		(fp_line
			(start -0.12065 -0.2794)
			(end -0.12065 -0.3048)
			(stroke
				(width 0.1)
				(type default)
			)
			(layer "B.Fab")
		)
		(fp_line
			(start 0.12065 -0.2794)
			(end -0.12065 -0.2794)
			(stroke
				(width 0.1)
				(type default)
			)
			(layer "B.Fab")
		)
		(fp_line
			(start -0.67945 -0.3048)
			(end -0.67945 0.3048)
			(stroke
				(width 0.1)
				(type default)
			)
			(layer "B.Fab")
		)
		(fp_line
			(start -0.12065 -0.3048)
			(end -0.67945 -0.3048)
			(stroke
				(width 0.1)
				(type default)
			)
			(layer "B.Fab")
		)
		(fp_line
			(start 0.12065 -0.305054)
			(end 0.12065 -0.2794)
			(stroke
				(width 0.1)
				(type default)
			)
			(layer "B.Fab")
		)
		(fp_line
			(start 0.67945 -0.305054)
			(end 0.12065 -0.305054)
			(stroke
				(width 0.1)
				(type default)
			)
			(layer "B.Fab")
		)
		(pad "1" smd circle
			(at 0.40005 0 90)
			(size 0 0)
			(layers "B.Cu" "B.Mask" "B.Paste")
			(net "P3V3_AUX")
		)
		(pad "2" smd circle
			(at -0.40005 0 90)
			(size 0 0)
			(layers "B.Cu" "B.Mask" "B.Paste")
			(net "RST_SMB_PDB_BUF_N")
		)
	)
	(footprint ""
		(layer "B.Cu")
		(at 230.886 -70.993 -90)
		(property "Reference" "R70"
			(at 0 0 90)
			(layer "B.SilkS")
			(hide yes)
			(effects
				(font
					(size 1.27 1.27)
				)
				(justify mirror)
			)
		)
		(property "Value" ""
			(at 0 0 90)
			(layer "B.Fab")
			(effects
				(font
					(size 1.27 1.27)
				)
				(justify mirror)
			)
		)
		(duplicate_pad_numbers_are_jumpers no)
		(fp_line
			(start -0.7874 0.4064)
			(end 0.7874 0.4064)
			(stroke
				(width 0.1524)
				(type default)
			)
			(layer "B.SilkS")
		)
		(fp_line
			(start 0.7874 0.4064)
			(end 0.7874 -0.4064)
			(stroke
				(width 0.1524)
				(type default)
			)
			(layer "B.SilkS")
		)
		(fp_line
			(start -0.7874 -0.4064)
			(end -0.7874 0.4064)
			(stroke
				(width 0.1524)
				(type default)
			)
			(layer "B.SilkS")
		)
		(fp_line
			(start 0.7874 -0.4064)
			(end -0.7874 -0.4064)
			(stroke
				(width 0.1524)
				(type default)
			)
			(layer "B.SilkS")
		)
		(fp_line
			(start -0.67945 0.3048)
			(end -0.120396 0.3048)
			(stroke
				(width 0.1)
				(type default)
			)
			(layer "B.Fab")
		)
		(fp_line
			(start -0.120396 0.3048)
			(end -0.120396 0.2794)
			(stroke
				(width 0.1)
				(type default)
			)
			(layer "B.Fab")
		)
		(fp_line
			(start 0.12065 0.3048)
			(end 0.67945 0.3048)
			(stroke
				(width 0.1)
				(type default)
			)
			(layer "B.Fab")
		)
		(fp_line
			(start 0.67945 0.3048)
			(end 0.67945 -0.305054)
			(stroke
				(width 0.1)
				(type default)
			)
			(layer "B.Fab")
		)
		(fp_line
			(start -0.120396 0.2794)
			(end 0.12065 0.2794)
			(stroke
				(width 0.1)
				(type default)
			)
			(layer "B.Fab")
		)
		(fp_line
			(start 0.12065 0.2794)
			(end 0.12065 0.3048)
			(stroke
				(width 0.1)
				(type default)
			)
			(layer "B.Fab")
		)
		(fp_line
			(start -0.12065 -0.2794)
			(end -0.12065 -0.3048)
			(stroke
				(width 0.1)
				(type default)
			)
			(layer "B.Fab")
		)
		(fp_line
			(start 0.12065 -0.2794)
			(end -0.12065 -0.2794)
			(stroke
				(width 0.1)
				(type default)
			)
			(layer "B.Fab")
		)
		(fp_line
			(start -0.67945 -0.3048)
			(end -0.67945 0.3048)
			(stroke
				(width 0.1)
				(type default)
			)
			(layer "B.Fab")
		)
		(fp_line
			(start -0.12065 -0.3048)
			(end -0.67945 -0.3048)
			(stroke
				(width 0.1)
				(type default)
			)
			(layer "B.Fab")
		)
		(fp_line
			(start 0.12065 -0.305054)
			(end 0.12065 -0.2794)
			(stroke
				(width 0.1)
				(type default)
			)
			(layer "B.Fab")
		)
		(fp_line
			(start 0.67945 -0.305054)
			(end 0.12065 -0.305054)
			(stroke
				(width 0.1)
				(type default)
			)
			(layer "B.Fab")
		)
		(pad "1" smd circle
			(at 0.40005 0 90)
			(size 0 0)
			(layers "B.Cu" "B.Mask" "B.Paste")
			(net "FAN_PWR_R_EN")
		)
		(pad "2" smd circle
			(at -0.40005 0 90)
			(size 0 0)
			(layers "B.Cu" "B.Mask" "B.Paste")
			(net "FAN_PWR_EN")
		)
	)
	(footprint ""
		(layer "B.Cu")
		(at 207.137 -82.55 90)
		(property "Reference" "R19"
			(at 0 0 90)
			(layer "B.SilkS")
			(hide yes)
			(effects
				(font
					(size 1.27 1.27)
				)
				(justify mirror)
			)
		)
		(property "Value" ""
			(at 0 0 90)
			(layer "B.Fab")
			(effects
				(font
					(size 1.27 1.27)
				)
				(justify mirror)
			)
		)
		(duplicate_pad_numbers_are_jumpers no)
		(fp_line
			(start 0.7874 -0.4064)
			(end -0.7874 -0.4064)
			(stroke
				(width 0.1524)
				(type default)
			)
			(layer "B.SilkS")
		)
		(fp_line
			(start -0.7874 -0.4064)
			(end -0.7874 0.4064)
			(stroke
				(width 0.1524)
				(type default)
			)
			(layer "B.SilkS")
		)
		(fp_line
			(start 0.7874 0.4064)
			(end 0.7874 -0.4064)
			(stroke
				(width 0.1524)
				(type default)
			)
			(layer "B.SilkS")
		)
		(fp_line
			(start -0.7874 0.4064)
			(end 0.7874 0.4064)
			(stroke
				(width 0.1524)
				(type default)
			)
			(layer "B.SilkS")
		)
		(fp_line
			(start 0.67945 -0.305054)
			(end 0.12065 -0.305054)
			(stroke
				(width 0.1)
				(type default)
			)
			(layer "B.Fab")
		)
		(fp_line
			(start 0.12065 -0.305054)
			(end 0.12065 -0.2794)
			(stroke
				(width 0.1)
				(type default)
			)
			(layer "B.Fab")
		)
		(fp_line
			(start -0.12065 -0.3048)
			(end -0.67945 -0.3048)
			(stroke
				(width 0.1)
				(type default)
			)
			(layer "B.Fab")
		)
		(fp_line
			(start -0.67945 -0.3048)
			(end -0.67945 0.3048)
			(stroke
				(width 0.1)
				(type default)
			)
			(layer "B.Fab")
		)
		(fp_line
			(start 0.12065 -0.2794)
			(end -0.12065 -0.2794)
			(stroke
				(width 0.1)
				(type default)
			)
			(layer "B.Fab")
		)
		(fp_line
			(start -0.12065 -0.2794)
			(end -0.12065 -0.3048)
			(stroke
				(width 0.1)
				(type default)
			)
			(layer "B.Fab")
		)
		(fp_line
			(start 0.12065 0.2794)
			(end 0.12065 0.3048)
			(stroke
				(width 0.1)
				(type default)
			)
			(layer "B.Fab")
		)
		(fp_line
			(start -0.120396 0.2794)
			(end 0.12065 0.2794)
			(stroke
				(width 0.1)
				(type default)
			)
			(layer "B.Fab")
		)
		(fp_line
			(start 0.67945 0.3048)
			(end 0.67945 -0.305054)
			(stroke
				(width 0.1)
				(type default)
			)
			(layer "B.Fab")
		)
		(fp_line
			(start 0.12065 0.3048)
			(end 0.67945 0.3048)
			(stroke
				(width 0.1)
				(type default)
			)
			(layer "B.Fab")
		)
		(fp_line
			(start -0.120396 0.3048)
			(end -0.120396 0.2794)
			(stroke
				(width 0.1)
				(type default)
			)
			(layer "B.Fab")
		)
		(fp_line
			(start -0.67945 0.3048)
			(end -0.120396 0.3048)
			(stroke
				(width 0.1)
				(type default)
			)
			(layer "B.Fab")
		)
		(pad "1" smd circle
			(at 0.40005 0 270)
			(size 0 0)
			(layers "B.Cu" "B.Mask" "B.Paste")
			(net "P3V3_AUX")
		)
		(pad "2" smd circle
			(at -0.40005 0 270)
			(size 0 0)
			(layers "B.Cu" "B.Mask" "B.Paste")
			(net "PCA9555_A1")
		)
	)
	(footprint ""
		(layer "B.Cu")
		(at 217.551 -95.504 90)
		(property "Reference" "C42"
			(at 0 0 90)
			(layer "B.SilkS")
			(hide yes)
			(effects
				(font
					(size 1.27 1.27)
				)
				(justify mirror)
			)
		)
		(property "Value" ""
			(at 0 0 90)
			(layer "B.Fab")
			(effects
				(font
					(size 1.27 1.27)
				)
				(justify mirror)
			)
		)
		(duplicate_pad_numbers_are_jumpers no)
		(fp_line
			(start 2.2098 -0.9398)
			(end -2.2098 -0.9398)
			(stroke
				(width 0.1524)
				(type default)
			)
			(layer "B.SilkS")
		)
		(fp_line
			(start -2.2098 -0.9398)
			(end -2.2098 0.9398)
			(stroke
				(width 0.1524)
				(type default)
			)
			(layer "B.SilkS")
		)
		(fp_line
			(start 2.2098 0.9398)
			(end 2.2098 -0.9398)
			(stroke
				(width 0.1524)
				(type default)
			)
			(layer "B.SilkS")
		)
		(fp_line
			(start -2.2098 0.9398)
			(end 2.2098 0.9398)
			(stroke
				(width 0.1524)
				(type default)
			)
			(layer "B.SilkS")
		)
		(fp_line
			(start 1.700022 -0.899922)
			(end -1.700022 -0.899922)
			(stroke
				(width 0.1)
				(type default)
			)
			(layer "B.Fab")
		)
		(fp_line
			(start -1.700022 -0.899922)
			(end -1.700022 0.899922)
			(stroke
				(width 0.1)
				(type default)
			)
			(layer "B.Fab")
		)
		(fp_line
			(start 1.700022 0.899922)
			(end 1.700022 -0.899922)
			(stroke
				(width 0.1)
				(type default)
			)
			(layer "B.Fab")
		)
		(fp_line
			(start -1.700022 0.899922)
			(end 1.700022 0.899922)
			(stroke
				(width 0.1)
				(type default)
			)
			(layer "B.Fab")
		)
		(pad "1" smd rect
			(at 1.4732 0 90)
			(size 1.1684 1.5748)
			(layers "B.Cu" "B.Mask" "B.Paste")
			(net "P52V_HS")
		)
		(pad "2" smd rect
			(at -1.4732 0 90)
			(size 1.1684 1.5748)
			(layers "B.Cu" "B.Mask" "B.Paste")
			(net "GND")
		)
	)
	(footprint ""
		(layer "B.Cu")
		(at 269.621 -34.036)
		(property "Reference" "PR28"
			(at 0 0 0)
			(layer "B.SilkS")
			(hide yes)
			(effects
				(font
					(size 1.27 1.27)
				)
				(justify mirror)
			)
		)
		(property "Value" ""
			(at 0 0 0)
			(layer "B.Fab")
			(effects
				(font
					(size 1.27 1.27)
				)
				(justify mirror)
			)
		)
		(duplicate_pad_numbers_are_jumpers no)
		(fp_line
			(start -0.7874 -0.4064)
			(end -0.7874 0.4064)
			(stroke
				(width 0.1524)
				(type default)
			)
			(layer "B.SilkS")
		)
		(fp_line
			(start -0.7874 0.4064)
			(end 0.7874 0.4064)
			(stroke
				(width 0.1524)
				(type default)
			)
			(layer "B.SilkS")
		)
		(fp_line
			(start 0.7874 -0.4064)
			(end -0.7874 -0.4064)
			(stroke
				(width 0.1524)
				(type default)
			)
			(layer "B.SilkS")
		)
		(fp_line
			(start 0.7874 0.4064)
			(end 0.7874 -0.4064)
			(stroke
				(width 0.1524)
				(type default)
			)
			(layer "B.SilkS")
		)
		(fp_line
			(start -0.67945 -0.3048)
			(end -0.67945 0.3048)
			(stroke
				(width 0.1)
				(type default)
			)
			(layer "B.Fab")
		)
		(fp_line
			(start -0.67945 0.3048)
			(end -0.120396 0.3048)
			(stroke
				(width 0.1)
				(type default)
			)
			(layer "B.Fab")
		)
		(fp_line
			(start -0.12065 -0.3048)
			(end -0.67945 -0.3048)
			(stroke
				(width 0.1)
				(type default)
			)
			(layer "B.Fab")
		)
		(fp_line
			(start -0.12065 -0.2794)
			(end -0.12065 -0.3048)
			(stroke
				(width 0.1)
				(type default)
			)
			(layer "B.Fab")
		)
		(fp_line
			(start -0.120396 0.2794)
			(end 0.12065 0.2794)
			(stroke
				(width 0.1)
				(type default)
			)
			(layer "B.Fab")
		)
		(fp_line
			(start -0.120396 0.3048)
			(end -0.120396 0.2794)
			(stroke
				(width 0.1)
				(type default)
			)
			(layer "B.Fab")
		)
		(fp_line
			(start 0.12065 -0.305054)
			(end 0.12065 -0.2794)
			(stroke
				(width 0.1)
				(type default)
			)
			(layer "B.Fab")
		)
		(fp_line
			(start 0.12065 -0.2794)
			(end -0.12065 -0.2794)
			(stroke
				(width 0.1)
				(type default)
			)
			(layer "B.Fab")
		)
		(fp_line
			(start 0.12065 0.2794)
			(end 0.12065 0.3048)
			(stroke
				(width 0.1)
				(type default)
			)
			(layer "B.Fab")
		)
		(fp_line
			(start 0.12065 0.3048)
			(end 0.67945 0.3048)
			(stroke
				(width 0.1)
				(type default)
			)
			(layer "B.Fab")
		)
		(fp_line
			(start 0.67945 -0.305054)
			(end 0.12065 -0.305054)
			(stroke
				(width 0.1)
				(type default)
			)
			(layer "B.Fab")
		)
		(fp_line
			(start 0.67945 0.3048)
			(end 0.67945 -0.305054)
			(stroke
				(width 0.1)
				(type default)
			)
			(layer "B.Fab")
		)
		(pad "1" smd circle
			(at 0.40005 0 180)
			(size 0 0)
			(layers "B.Cu" "B.Mask" "B.Paste")
			(net "P52V_HS1_SCK")
		)
		(pad "2" smd circle
			(at -0.40005 0 180)
			(size 0 0)
			(layers "B.Cu" "B.Mask" "B.Paste")
			(net "GND_FIELD_SIGNAL")
		)
	)
	(footprint ""
		(layer "B.Cu")
		(at 277.368 -88.1126 90)
		(property "Reference" "PR6971"
			(at 0 0 90)
			(layer "B.SilkS")
			(hide yes)
			(effects
				(font
					(size 1.27 1.27)
				)
				(justify mirror)
			)
		)
		(property "Value" ""
			(at 0 0 90)
			(layer "B.Fab")
			(effects
				(font
					(size 1.27 1.27)
				)
				(justify mirror)
			)
		)
		(duplicate_pad_numbers_are_jumpers no)
		(fp_line
			(start 1.2954 -0.5842)
			(end -1.2954 -0.5842)
			(stroke
				(width 0.1524)
				(type default)
			)
			(layer "B.SilkS")
		)
		(fp_line
			(start -1.2954 -0.5842)
			(end -1.2954 0.5842)
			(stroke
				(width 0.1524)
				(type default)
			)
			(layer "B.SilkS")
		)
		(fp_line
			(start 1.2954 0.5842)
			(end 1.2954 -0.5842)
			(stroke
				(width 0.1524)
				(type default)
			)
			(layer "B.SilkS")
		)
		(fp_line
			(start -1.2954 0.5842)
			(end 1.2954 0.5842)
			(stroke
				(width 0.1524)
				(type default)
			)
			(layer "B.SilkS")
		)
		(fp_line
			(start 0.8636 -0.4572)
			(end -0.8636 -0.4572)
			(stroke
				(width 0.1)
				(type default)
			)
			(layer "B.Fab")
		)
		(fp_line
			(start -0.8636 -0.4572)
			(end -0.8636 -0.406654)
			(stroke
				(width 0.1)
				(type default)
			)
			(layer "B.Fab")
		)
		(fp_line
			(start 1.1938 -0.406654)
			(end 0.8636 -0.406654)
			(stroke
				(width 0.1)
				(type default)
			)
			(layer "B.Fab")
		)
		(fp_line
			(start 0.8636 -0.406654)
			(end 0.8636 -0.4572)
			(stroke
				(width 0.1)
				(type default)
			)
			(layer "B.Fab")
		)
		(fp_line
			(start -0.8636 -0.406654)
			(end -1.1938 -0.406654)
			(stroke
				(width 0.1)
				(type default)
			)
			(layer "B.Fab")
		)
		(fp_line
			(start -1.1938 -0.406654)
			(end -1.1938 0.4064)
			(stroke
				(width 0.1)
				(type default)
			)
			(layer "B.Fab")
		)
		(fp_line
			(start 1.1938 0.4064)
			(end 1.1938 -0.406654)
			(stroke
				(width 0.1)
				(type default)
			)
			(layer "B.Fab")
		)
		(fp_line
			(start 0.8636 0.4064)
			(end 1.1938 0.4064)
			(stroke
				(width 0.1)
				(type default)
			)
			(layer "B.Fab")
		)
		(fp_line
			(start -0.8636 0.4064)
			(end -0.8636 0.4572)
			(stroke
				(width 0.1)
				(type default)
			)
			(layer "B.Fab")
		)
		(fp_line
			(start -1.1938 0.4064)
			(end -0.8636 0.4064)
			(stroke
				(width 0.1)
				(type default)
			)
			(layer "B.Fab")
		)
		(fp_line
			(start 0.8636 0.4318)
			(end 0.8636 0.4064)
			(stroke
				(width 0.1)
				(type default)
			)
			(layer "B.Fab")
		)
		(fp_line
			(start 0.8636 0.4572)
			(end 0.8636 0.4318)
			(stroke
				(width 0.1)
				(type default)
			)
			(layer "B.Fab")
		)
		(fp_line
			(start -0.8636 0.4572)
			(end 0.8636 0.4572)
			(stroke
				(width 0.1)
				(type default)
			)
			(layer "B.Fab")
		)
		(pad "1" smd rect
			(at 0.7366 0)
			(size 0.7112 0.8128)
			(layers "B.Cu" "B.Mask" "B.Paste")
			(net "P52V_HS1_4287_GATE2_R")
		)
		(pad "2" smd rect
			(at -0.7366 0)
			(size 0.7112 0.8128)
			(layers "B.Cu" "B.Mask" "B.Paste")
			(net "P52V_HS1_4287_GATE2_RC")
		)
	)
	(footprint ""
		(layer "B.Cu")
		(at 232.537 -70.993 -90)
		(property "Reference" "C15"
			(at 0 0 90)
			(layer "B.SilkS")
			(hide yes)
			(effects
				(font
					(size 1.27 1.27)
				)
				(justify mirror)
			)
		)
		(property "Value" ""
			(at 0 0 90)
			(layer "B.Fab")
			(effects
				(font
					(size 1.27 1.27)
				)
				(justify mirror)
			)
		)
		(duplicate_pad_numbers_are_jumpers no)
		(fp_line
			(start -0.7874 0.4064)
			(end 0.7874 0.4064)
			(stroke
				(width 0.1524)
				(type default)
			)
			(layer "B.SilkS")
		)
		(fp_line
			(start 0.7874 0.4064)
			(end 0.7874 -0.4064)
			(stroke
				(width 0.1524)
				(type default)
			)
			(layer "B.SilkS")
		)
		(fp_line
			(start -0.7874 -0.4064)
			(end -0.7874 0.4064)
			(stroke
				(width 0.1524)
				(type default)
			)
			(layer "B.SilkS")
		)
		(fp_line
			(start 0.7874 -0.4064)
			(end -0.7874 -0.4064)
			(stroke
				(width 0.1524)
				(type default)
			)
			(layer "B.SilkS")
		)
		(fp_line
			(start -0.67945 0.3048)
			(end -0.120396 0.3048)
			(stroke
				(width 0.1)
				(type default)
			)
			(layer "B.Fab")
		)
		(fp_line
			(start -0.120396 0.3048)
			(end -0.120396 0.2794)
			(stroke
				(width 0.1)
				(type default)
			)
			(layer "B.Fab")
		)
		(fp_line
			(start 0.12065 0.3048)
			(end 0.67945 0.3048)
			(stroke
				(width 0.1)
				(type default)
			)
			(layer "B.Fab")
		)
		(fp_line
			(start 0.67945 0.3048)
			(end 0.67945 -0.305054)
			(stroke
				(width 0.1)
				(type default)
			)
			(layer "B.Fab")
		)
		(fp_line
			(start -0.120396 0.2794)
			(end 0.12065 0.2794)
			(stroke
				(width 0.1)
				(type default)
			)
			(layer "B.Fab")
		)
		(fp_line
			(start 0.12065 0.2794)
			(end 0.12065 0.3048)
			(stroke
				(width 0.1)
				(type default)
			)
			(layer "B.Fab")
		)
		(fp_line
			(start -0.12065 -0.2794)
			(end -0.12065 -0.3048)
			(stroke
				(width 0.1)
				(type default)
			)
			(layer "B.Fab")
		)
		(fp_line
			(start 0.12065 -0.2794)
			(end -0.12065 -0.2794)
			(stroke
				(width 0.1)
				(type default)
			)
			(layer "B.Fab")
		)
		(fp_line
			(start -0.67945 -0.3048)
			(end -0.67945 0.3048)
			(stroke
				(width 0.1)
				(type default)
			)
			(layer "B.Fab")
		)
		(fp_line
			(start -0.12065 -0.3048)
			(end -0.67945 -0.3048)
			(stroke
				(width 0.1)
				(type default)
			)
			(layer "B.Fab")
		)
		(fp_line
			(start 0.12065 -0.305054)
			(end 0.12065 -0.2794)
			(stroke
				(width 0.1)
				(type default)
			)
			(layer "B.Fab")
		)
		(fp_line
			(start 0.67945 -0.305054)
			(end 0.12065 -0.305054)
			(stroke
				(width 0.1)
				(type default)
			)
			(layer "B.Fab")
		)
		(pad "1" smd circle
			(at 0.40005 0 90)
			(size 0 0)
			(layers "B.Cu" "B.Mask" "B.Paste")
			(net "PWRGD_P3V3_AUX_MB_R")
		)
		(pad "2" smd circle
			(at -0.40005 0 90)
			(size 0 0)
			(layers "B.Cu" "B.Mask" "B.Paste")
			(net "GND")
		)
	)
	(footprint ""
		(layer "B.Cu")
		(at 267.589 -28.321)
		(property "Reference" "R5918"
			(at 0 0 0)
			(layer "B.SilkS")
			(hide yes)
			(effects
				(font
					(size 1.27 1.27)
				)
				(justify mirror)
			)
		)
		(property "Value" ""
			(at 0 0 0)
			(layer "B.Fab")
			(effects
				(font
					(size 1.27 1.27)
				)
				(justify mirror)
			)
		)
		(duplicate_pad_numbers_are_jumpers no)
		(fp_line
			(start -1.651 -0.8382)
			(end -1.651 0.8382)
			(stroke
				(width 0.1524)
				(type default)
			)
			(layer "B.SilkS")
		)
		(fp_line
			(start -1.651 0.8382)
			(end 1.651 0.8382)
			(stroke
				(width 0.1524)
				(type default)
			)
			(layer "B.SilkS")
		)
		(fp_line
			(start 1.651 -0.8382)
			(end -1.651 -0.8382)
			(stroke
				(width 0.1524)
				(type default)
			)
			(layer "B.SilkS")
		)
		(fp_line
			(start 1.651 0.8382)
			(end 1.651 -0.8382)
			(stroke
				(width 0.1524)
				(type default)
			)
			(layer "B.SilkS")
		)
		(fp_line
			(start -1.560576 -0.7366)
			(end -1.524 -0.7366)
			(stroke
				(width 0.1)
				(type default)
			)
			(layer "B.Fab")
		)
		(fp_line
			(start -1.560576 0.7366)
			(end -1.560576 -0.7366)
			(stroke
				(width 0.1)
				(type default)
			)
			(layer "B.Fab")
		)
		(fp_line
			(start -1.524 -0.7366)
			(end 1.524 -0.7366)
			(stroke
				(width 0.1)
				(type default)
			)
			(layer "B.Fab")
		)
		(fp_line
			(start -1.524 0.7366)
			(end -1.560576 0.7366)
			(stroke
				(width 0.1)
				(type default)
			)
			(layer "B.Fab")
		)
		(fp_line
			(start 1.524 -0.7366)
			(end 1.559814 -0.7366)
			(stroke
				(width 0.1)
				(type default)
			)
			(layer "B.Fab")
		)
		(fp_line
			(start 1.524 0.7366)
			(end -1.524 0.7366)
			(stroke
				(width 0.1)
				(type default)
			)
			(layer "B.Fab")
		)
		(fp_line
			(start 1.559814 -0.7366)
			(end 1.559814 0.7366)
			(stroke
				(width 0.1)
				(type default)
			)
			(layer "B.Fab")
		)
		(fp_line
			(start 1.559814 0.7366)
			(end 1.524 0.7366)
			(stroke
				(width 0.1)
				(type default)
			)
			(layer "B.Fab")
		)
		(pad "1" smd rect
			(at 0.94996 0)
			(size 1.1176 1.3716)
			(layers "B.Cu" "B.Mask" "B.Paste")
			(net "P52V_HS1_EN")
		)
		(pad "2" smd rect
			(at -0.94996 0)
			(size 1.1176 1.3716)
			(layers "B.Cu" "B.Mask" "B.Paste")
			(net "P52V_HS1_EN_DELAY")
		)
	)
	(footprint ""
		(layer "B.Cu")
		(at 209.677 -84.836)
		(property "Reference" "R185"
			(at 0 0 0)
			(layer "B.SilkS")
			(hide yes)
			(effects
				(font
					(size 1.27 1.27)
				)
				(justify mirror)
			)
		)
		(property "Value" ""
			(at 0 0 0)
			(layer "B.Fab")
			(effects
				(font
					(size 1.27 1.27)
				)
				(justify mirror)
			)
		)
		(duplicate_pad_numbers_are_jumpers no)
		(fp_line
			(start -0.7874 -0.4064)
			(end -0.7874 0.4064)
			(stroke
				(width 0.1524)
				(type default)
			)
			(layer "B.SilkS")
		)
		(fp_line
			(start -0.7874 0.4064)
			(end 0.7874 0.4064)
			(stroke
				(width 0.1524)
				(type default)
			)
			(layer "B.SilkS")
		)
		(fp_line
			(start 0.7874 -0.4064)
			(end -0.7874 -0.4064)
			(stroke
				(width 0.1524)
				(type default)
			)
			(layer "B.SilkS")
		)
		(fp_line
			(start 0.7874 0.4064)
			(end 0.7874 -0.4064)
			(stroke
				(width 0.1524)
				(type default)
			)
			(layer "B.SilkS")
		)
		(fp_line
			(start -0.67945 -0.3048)
			(end -0.67945 0.3048)
			(stroke
				(width 0.1)
				(type default)
			)
			(layer "B.Fab")
		)
		(fp_line
			(start -0.67945 0.3048)
			(end -0.120396 0.3048)
			(stroke
				(width 0.1)
				(type default)
			)
			(layer "B.Fab")
		)
		(fp_line
			(start -0.12065 -0.3048)
			(end -0.67945 -0.3048)
			(stroke
				(width 0.1)
				(type default)
			)
			(layer "B.Fab")
		)
		(fp_line
			(start -0.12065 -0.2794)
			(end -0.12065 -0.3048)
			(stroke
				(width 0.1)
				(type default)
			)
			(layer "B.Fab")
		)
		(fp_line
			(start -0.120396 0.2794)
			(end 0.12065 0.2794)
			(stroke
				(width 0.1)
				(type default)
			)
			(layer "B.Fab")
		)
		(fp_line
			(start -0.120396 0.3048)
			(end -0.120396 0.2794)
			(stroke
				(width 0.1)
				(type default)
			)
			(layer "B.Fab")
		)
		(fp_line
			(start 0.12065 -0.305054)
			(end 0.12065 -0.2794)
			(stroke
				(width 0.1)
				(type default)
			)
			(layer "B.Fab")
		)
		(fp_line
			(start 0.12065 -0.2794)
			(end -0.12065 -0.2794)
			(stroke
				(width 0.1)
				(type default)
			)
			(layer "B.Fab")
		)
		(fp_line
			(start 0.12065 0.2794)
			(end 0.12065 0.3048)
			(stroke
				(width 0.1)
				(type default)
			)
			(layer "B.Fab")
		)
		(fp_line
			(start 0.12065 0.3048)
			(end 0.67945 0.3048)
			(stroke
				(width 0.1)
				(type default)
			)
			(layer "B.Fab")
		)
		(fp_line
			(start 0.67945 -0.305054)
			(end 0.12065 -0.305054)
			(stroke
				(width 0.1)
				(type default)
			)
			(layer "B.Fab")
		)
		(fp_line
			(start 0.67945 0.3048)
			(end 0.67945 -0.305054)
			(stroke
				(width 0.1)
				(type default)
			)
			(layer "B.Fab")
		)
		(pad "1" smd circle
			(at 0.40005 0 180)
			(size 0 0)
			(layers "B.Cu" "B.Mask" "B.Paste")
			(net "PWRGD_GPU_HSC")
		)
		(pad "2" smd circle
			(at -0.40005 0 180)
			(size 0 0)
			(layers "B.Cu" "B.Mask" "B.Paste")
			(net "PWRGD_GPU_HSC_R")
		)
	)
	(footprint ""
		(layer "B.Cu")
		(at 214.884 -69.723 -90)
		(property "Reference" "R133"
			(at 0 0 90)
			(layer "B.SilkS")
			(hide yes)
			(effects
				(font
					(size 1.27 1.27)
				)
				(justify mirror)
			)
		)
		(property "Value" ""
			(at 0 0 90)
			(layer "B.Fab")
			(effects
				(font
					(size 1.27 1.27)
				)
				(justify mirror)
			)
		)
		(duplicate_pad_numbers_are_jumpers no)
		(fp_line
			(start -0.7874 0.4064)
			(end 0.7874 0.4064)
			(stroke
				(width 0.1524)
				(type default)
			)
			(layer "B.SilkS")
		)
		(fp_line
			(start 0.7874 0.4064)
			(end 0.7874 -0.4064)
			(stroke
				(width 0.1524)
				(type default)
			)
			(layer "B.SilkS")
		)
		(fp_line
			(start -0.7874 -0.4064)
			(end -0.7874 0.4064)
			(stroke
				(width 0.1524)
				(type default)
			)
			(layer "B.SilkS")
		)
		(fp_line
			(start 0.7874 -0.4064)
			(end -0.7874 -0.4064)
			(stroke
				(width 0.1524)
				(type default)
			)
			(layer "B.SilkS")
		)
		(fp_line
			(start -0.67945 0.3048)
			(end -0.120396 0.3048)
			(stroke
				(width 0.1)
				(type default)
			)
			(layer "B.Fab")
		)
		(fp_line
			(start -0.120396 0.3048)
			(end -0.120396 0.2794)
			(stroke
				(width 0.1)
				(type default)
			)
			(layer "B.Fab")
		)
		(fp_line
			(start 0.12065 0.3048)
			(end 0.67945 0.3048)
			(stroke
				(width 0.1)
				(type default)
			)
			(layer "B.Fab")
		)
		(fp_line
			(start 0.67945 0.3048)
			(end 0.67945 -0.305054)
			(stroke
				(width 0.1)
				(type default)
			)
			(layer "B.Fab")
		)
		(fp_line
			(start -0.120396 0.2794)
			(end 0.12065 0.2794)
			(stroke
				(width 0.1)
				(type default)
			)
			(layer "B.Fab")
		)
		(fp_line
			(start 0.12065 0.2794)
			(end 0.12065 0.3048)
			(stroke
				(width 0.1)
				(type default)
			)
			(layer "B.Fab")
		)
		(fp_line
			(start -0.12065 -0.2794)
			(end -0.12065 -0.3048)
			(stroke
				(width 0.1)
				(type default)
			)
			(layer "B.Fab")
		)
		(fp_line
			(start 0.12065 -0.2794)
			(end -0.12065 -0.2794)
			(stroke
				(width 0.1)
				(type default)
			)
			(layer "B.Fab")
		)
		(fp_line
			(start -0.67945 -0.3048)
			(end -0.67945 0.3048)
			(stroke
				(width 0.1)
				(type default)
			)
			(layer "B.Fab")
		)
		(fp_line
			(start -0.12065 -0.3048)
			(end -0.67945 -0.3048)
			(stroke
				(width 0.1)
				(type default)
			)
			(layer "B.Fab")
		)
		(fp_line
			(start 0.12065 -0.305054)
			(end 0.12065 -0.2794)
			(stroke
				(width 0.1)
				(type default)
			)
			(layer "B.Fab")
		)
		(fp_line
			(start 0.67945 -0.305054)
			(end 0.12065 -0.305054)
			(stroke
				(width 0.1)
				(type default)
			)
			(layer "B.Fab")
		)
		(pad "1" smd circle
			(at 0.40005 0 90)
			(size 0 0)
			(layers "B.Cu" "B.Mask" "B.Paste")
			(net "P3V3_AUX")
		)
		(pad "2" smd circle
			(at -0.40005 0 90)
			(size 0 0)
			(layers "B.Cu" "B.Mask" "B.Paste")
			(net "BOARD_ID_2")
		)
	)
	(footprint ""
		(layer "B.Cu")
		(at 149.733 -114.427 -90)
		(property "Reference" "C55"
			(at 0 0 90)
			(layer "B.SilkS")
			(hide yes)
			(effects
				(font
					(size 1.27 1.27)
				)
				(justify mirror)
			)
		)
		(property "Value" ""
			(at 0 0 90)
			(layer "B.Fab")
			(effects
				(font
					(size 1.27 1.27)
				)
				(justify mirror)
			)
		)
		(duplicate_pad_numbers_are_jumpers no)
		(fp_line
			(start -0.7874 0.4064)
			(end 0.7874 0.4064)
			(stroke
				(width 0.1524)
				(type default)
			)
			(layer "B.SilkS")
		)
		(fp_line
			(start 0.7874 0.4064)
			(end 0.7874 -0.4064)
			(stroke
				(width 0.1524)
				(type default)
			)
			(layer "B.SilkS")
		)
		(fp_line
			(start -0.7874 -0.4064)
			(end -0.7874 0.4064)
			(stroke
				(width 0.1524)
				(type default)
			)
			(layer "B.SilkS")
		)
		(fp_line
			(start 0.7874 -0.4064)
			(end -0.7874 -0.4064)
			(stroke
				(width 0.1524)
				(type default)
			)
			(layer "B.SilkS")
		)
		(fp_line
			(start -0.67945 0.3048)
			(end -0.120396 0.3048)
			(stroke
				(width 0.1)
				(type default)
			)
			(layer "B.Fab")
		)
		(fp_line
			(start -0.120396 0.3048)
			(end -0.120396 0.2794)
			(stroke
				(width 0.1)
				(type default)
			)
			(layer "B.Fab")
		)
		(fp_line
			(start 0.12065 0.3048)
			(end 0.67945 0.3048)
			(stroke
				(width 0.1)
				(type default)
			)
			(layer "B.Fab")
		)
		(fp_line
			(start 0.67945 0.3048)
			(end 0.67945 -0.305054)
			(stroke
				(width 0.1)
				(type default)
			)
			(layer "B.Fab")
		)
		(fp_line
			(start -0.120396 0.2794)
			(end 0.12065 0.2794)
			(stroke
				(width 0.1)
				(type default)
			)
			(layer "B.Fab")
		)
		(fp_line
			(start 0.12065 0.2794)
			(end 0.12065 0.3048)
			(stroke
				(width 0.1)
				(type default)
			)
			(layer "B.Fab")
		)
		(fp_line
			(start -0.12065 -0.2794)
			(end -0.12065 -0.3048)
			(stroke
				(width 0.1)
				(type default)
			)
			(layer "B.Fab")
		)
		(fp_line
			(start 0.12065 -0.2794)
			(end -0.12065 -0.2794)
			(stroke
				(width 0.1)
				(type default)
			)
			(layer "B.Fab")
		)
		(fp_line
			(start -0.67945 -0.3048)
			(end -0.67945 0.3048)
			(stroke
				(width 0.1)
				(type default)
			)
			(layer "B.Fab")
		)
		(fp_line
			(start -0.12065 -0.3048)
			(end -0.67945 -0.3048)
			(stroke
				(width 0.1)
				(type default)
			)
			(layer "B.Fab")
		)
		(fp_line
			(start 0.12065 -0.305054)
			(end 0.12065 -0.2794)
			(stroke
				(width 0.1)
				(type default)
			)
			(layer "B.Fab")
		)
		(fp_line
			(start 0.67945 -0.305054)
			(end 0.12065 -0.305054)
			(stroke
				(width 0.1)
				(type default)
			)
			(layer "B.Fab")
		)
		(pad "1" smd circle
			(at 0.40005 0 90)
			(size 0 0)
			(layers "B.Cu" "B.Mask" "B.Paste")
			(net "GND")
		)
		(pad "2" smd circle
			(at -0.40005 0 90)
			(size 0 0)
			(layers "B.Cu" "B.Mask" "B.Paste")
			(net "PWRGD_P52V_HS1_PG")
		)
	)
	(footprint ""
		(layer "B.Cu")
		(at 45.695616 -57.841642 180)
		(property "Reference" "R5902"
			(at 0 0 0)
			(layer "B.SilkS")
			(hide yes)
			(effects
				(font
					(size 1.27 1.27)
				)
				(justify mirror)
			)
		)
		(property "Value" ""
			(at 0 0 0)
			(layer "B.Fab")
			(effects
				(font
					(size 1.27 1.27)
				)
				(justify mirror)
			)
		)
		(duplicate_pad_numbers_are_jumpers no)
		(fp_line
			(start 0.7874 0.4064)
			(end 0.7874 -0.4064)
			(stroke
				(width 0.1524)
				(type default)
			)
			(layer "B.SilkS")
		)
		(fp_line
			(start 0.7874 -0.4064)
			(end -0.7874 -0.4064)
			(stroke
				(width 0.1524)
				(type default)
			)
			(layer "B.SilkS")
		)
		(fp_line
			(start -0.7874 0.4064)
			(end 0.7874 0.4064)
			(stroke
				(width 0.1524)
				(type default)
			)
			(layer "B.SilkS")
		)
		(fp_line
			(start -0.7874 -0.4064)
			(end -0.7874 0.4064)
			(stroke
				(width 0.1524)
				(type default)
			)
			(layer "B.SilkS")
		)
		(fp_line
			(start 0.67945 0.3048)
			(end 0.67945 -0.305054)
			(stroke
				(width 0.1)
				(type default)
			)
			(layer "B.Fab")
		)
		(fp_line
			(start 0.67945 -0.305054)
			(end 0.12065 -0.305054)
			(stroke
				(width 0.1)
				(type default)
			)
			(layer "B.Fab")
		)
		(fp_line
			(start 0.12065 0.3048)
			(end 0.67945 0.3048)
			(stroke
				(width 0.1)
				(type default)
			)
			(layer "B.Fab")
		)
		(fp_line
			(start 0.12065 0.2794)
			(end 0.12065 0.3048)
			(stroke
				(width 0.1)
				(type default)
			)
			(layer "B.Fab")
		)
		(fp_line
			(start 0.12065 -0.2794)
			(end -0.12065 -0.2794)
			(stroke
				(width 0.1)
				(type default)
			)
			(layer "B.Fab")
		)
		(fp_line
			(start 0.12065 -0.305054)
			(end 0.12065 -0.2794)
			(stroke
				(width 0.1)
				(type default)
			)
			(layer "B.Fab")
		)
		(fp_line
			(start -0.120396 0.3048)
			(end -0.120396 0.2794)
			(stroke
				(width 0.1)
				(type default)
			)
			(layer "B.Fab")
		)
		(fp_line
			(start -0.120396 0.2794)
			(end 0.12065 0.2794)
			(stroke
				(width 0.1)
				(type default)
			)
			(layer "B.Fab")
		)
		(fp_line
			(start -0.12065 -0.2794)
			(end -0.12065 -0.3048)
			(stroke
				(width 0.1)
				(type default)
			)
			(layer "B.Fab")
		)
		(fp_line
			(start -0.12065 -0.3048)
			(end -0.67945 -0.3048)
			(stroke
				(width 0.1)
				(type default)
			)
			(layer "B.Fab")
		)
		(fp_line
			(start -0.67945 0.3048)
			(end -0.120396 0.3048)
			(stroke
				(width 0.1)
				(type default)
			)
			(layer "B.Fab")
		)
		(fp_line
			(start -0.67945 -0.3048)
			(end -0.67945 0.3048)
			(stroke
				(width 0.1)
				(type default)
			)
			(layer "B.Fab")
		)
		(pad "1" smd circle
			(at 0.40005 0)
			(size 0 0)
			(layers "B.Cu" "B.Mask" "B.Paste")
			(net "P12V_HPDB_0_ISET")
		)
		(pad "2" smd circle
			(at -0.40005 0)
			(size 0 0)
			(layers "B.Cu" "B.Mask" "B.Paste")
			(net "P12V_HPDB_0_ISET_R")
		)
	)
	(footprint ""
		(layer "B.Cu")
		(at 202.946 -88.011 180)
		(property "Reference" "R125"
			(at 0 0 0)
			(layer "B.SilkS")
			(hide yes)
			(effects
				(font
					(size 1.27 1.27)
				)
				(justify mirror)
			)
		)
		(property "Value" ""
			(at 0 0 0)
			(layer "B.Fab")
			(effects
				(font
					(size 1.27 1.27)
				)
				(justify mirror)
			)
		)
		(duplicate_pad_numbers_are_jumpers no)
		(fp_line
			(start 0.7874 0.4064)
			(end 0.7874 -0.4064)
			(stroke
				(width 0.1524)
				(type default)
			)
			(layer "B.SilkS")
		)
		(fp_line
			(start 0.7874 -0.4064)
			(end -0.7874 -0.4064)
			(stroke
				(width 0.1524)
				(type default)
			)
			(layer "B.SilkS")
		)
		(fp_line
			(start -0.7874 0.4064)
			(end 0.7874 0.4064)
			(stroke
				(width 0.1524)
				(type default)
			)
			(layer "B.SilkS")
		)
		(fp_line
			(start -0.7874 -0.4064)
			(end -0.7874 0.4064)
			(stroke
				(width 0.1524)
				(type default)
			)
			(layer "B.SilkS")
		)
		(fp_line
			(start 0.67945 0.3048)
			(end 0.67945 -0.305054)
			(stroke
				(width 0.1)
				(type default)
			)
			(layer "B.Fab")
		)
		(fp_line
			(start 0.67945 -0.305054)
			(end 0.12065 -0.305054)
			(stroke
				(width 0.1)
				(type default)
			)
			(layer "B.Fab")
		)
		(fp_line
			(start 0.12065 0.3048)
			(end 0.67945 0.3048)
			(stroke
				(width 0.1)
				(type default)
			)
			(layer "B.Fab")
		)
		(fp_line
			(start 0.12065 0.2794)
			(end 0.12065 0.3048)
			(stroke
				(width 0.1)
				(type default)
			)
			(layer "B.Fab")
		)
		(fp_line
			(start 0.12065 -0.2794)
			(end -0.12065 -0.2794)
			(stroke
				(width 0.1)
				(type default)
			)
			(layer "B.Fab")
		)
		(fp_line
			(start 0.12065 -0.305054)
			(end 0.12065 -0.2794)
			(stroke
				(width 0.1)
				(type default)
			)
			(layer "B.Fab")
		)
		(fp_line
			(start -0.120396 0.3048)
			(end -0.120396 0.2794)
			(stroke
				(width 0.1)
				(type default)
			)
			(layer "B.Fab")
		)
		(fp_line
			(start -0.120396 0.2794)
			(end 0.12065 0.2794)
			(stroke
				(width 0.1)
				(type default)
			)
			(layer "B.Fab")
		)
		(fp_line
			(start -0.12065 -0.2794)
			(end -0.12065 -0.3048)
			(stroke
				(width 0.1)
				(type default)
			)
			(layer "B.Fab")
		)
		(fp_line
			(start -0.12065 -0.3048)
			(end -0.67945 -0.3048)
			(stroke
				(width 0.1)
				(type default)
			)
			(layer "B.Fab")
		)
		(fp_line
			(start -0.67945 0.3048)
			(end -0.120396 0.3048)
			(stroke
				(width 0.1)
				(type default)
			)
			(layer "B.Fab")
		)
		(fp_line
			(start -0.67945 -0.3048)
			(end -0.67945 0.3048)
			(stroke
				(width 0.1)
				(type default)
			)
			(layer "B.Fab")
		)
		(pad "1" smd circle
			(at 0.40005 0)
			(size 0 0)
			(layers "B.Cu" "B.Mask" "B.Paste")
			(net "SMB_VPDB_MISC_SDA")
		)
		(pad "2" smd circle
			(at -0.40005 0)
			(size 0 0)
			(layers "B.Cu" "B.Mask" "B.Paste")
			(net "P3V3_AUX")
		)
	)
	(footprint ""
		(layer "B.Cu")
		(at 234.823 -91.313 90)
		(property "Reference" "C9"
			(at 0 0 90)
			(layer "B.SilkS")
			(hide yes)
			(effects
				(font
					(size 1.27 1.27)
				)
				(justify mirror)
			)
		)
		(property "Value" ""
			(at 0 0 90)
			(layer "B.Fab")
			(effects
				(font
					(size 1.27 1.27)
				)
				(justify mirror)
			)
		)
		(duplicate_pad_numbers_are_jumpers no)
		(fp_line
			(start 0.7874 -0.4064)
			(end -0.7874 -0.4064)
			(stroke
				(width 0.1524)
				(type default)
			)
			(layer "B.SilkS")
		)
		(fp_line
			(start -0.7874 -0.4064)
			(end -0.7874 0.4064)
			(stroke
				(width 0.1524)
				(type default)
			)
			(layer "B.SilkS")
		)
		(fp_line
			(start 0.7874 0.4064)
			(end 0.7874 -0.4064)
			(stroke
				(width 0.1524)
				(type default)
			)
			(layer "B.SilkS")
		)
		(fp_line
			(start -0.7874 0.4064)
			(end 0.7874 0.4064)
			(stroke
				(width 0.1524)
				(type default)
			)
			(layer "B.SilkS")
		)
		(fp_line
			(start 0.67945 -0.305054)
			(end 0.12065 -0.305054)
			(stroke
				(width 0.1)
				(type default)
			)
			(layer "B.Fab")
		)
		(fp_line
			(start 0.12065 -0.305054)
			(end 0.12065 -0.2794)
			(stroke
				(width 0.1)
				(type default)
			)
			(layer "B.Fab")
		)
		(fp_line
			(start -0.12065 -0.3048)
			(end -0.67945 -0.3048)
			(stroke
				(width 0.1)
				(type default)
			)
			(layer "B.Fab")
		)
		(fp_line
			(start -0.67945 -0.3048)
			(end -0.67945 0.3048)
			(stroke
				(width 0.1)
				(type default)
			)
			(layer "B.Fab")
		)
		(fp_line
			(start 0.12065 -0.2794)
			(end -0.12065 -0.2794)
			(stroke
				(width 0.1)
				(type default)
			)
			(layer "B.Fab")
		)
		(fp_line
			(start -0.12065 -0.2794)
			(end -0.12065 -0.3048)
			(stroke
				(width 0.1)
				(type default)
			)
			(layer "B.Fab")
		)
		(fp_line
			(start 0.12065 0.2794)
			(end 0.12065 0.3048)
			(stroke
				(width 0.1)
				(type default)
			)
			(layer "B.Fab")
		)
		(fp_line
			(start -0.120396 0.2794)
			(end 0.12065 0.2794)
			(stroke
				(width 0.1)
				(type default)
			)
			(layer "B.Fab")
		)
		(fp_line
			(start 0.67945 0.3048)
			(end 0.67945 -0.305054)
			(stroke
				(width 0.1)
				(type default)
			)
			(layer "B.Fab")
		)
		(fp_line
			(start 0.12065 0.3048)
			(end 0.67945 0.3048)
			(stroke
				(width 0.1)
				(type default)
			)
			(layer "B.Fab")
		)
		(fp_line
			(start -0.120396 0.3048)
			(end -0.120396 0.2794)
			(stroke
				(width 0.1)
				(type default)
			)
			(layer "B.Fab")
		)
		(fp_line
			(start -0.67945 0.3048)
			(end -0.120396 0.3048)
			(stroke
				(width 0.1)
				(type default)
			)
			(layer "B.Fab")
		)
		(pad "1" smd circle
			(at 0.40005 0 270)
			(size 0 0)
			(layers "B.Cu" "B.Mask" "B.Paste")
			(net "GND")
		)
		(pad "2" smd circle
			(at -0.40005 0 270)
			(size 0 0)
			(layers "B.Cu" "B.Mask" "B.Paste")
			(net "P3V3_AUX")
		)
	)
	(footprint ""
		(layer "B.Cu")
		(at 214.122 -91.059 -90)
		(property "Reference" "R32"
			(at 0 0 90)
			(layer "B.SilkS")
			(hide yes)
			(effects
				(font
					(size 1.27 1.27)
				)
				(justify mirror)
			)
		)
		(property "Value" ""
			(at 0 0 90)
			(layer "B.Fab")
			(effects
				(font
					(size 1.27 1.27)
				)
				(justify mirror)
			)
		)
		(duplicate_pad_numbers_are_jumpers no)
		(fp_line
			(start -0.7874 0.4064)
			(end 0.7874 0.4064)
			(stroke
				(width 0.1524)
				(type default)
			)
			(layer "B.SilkS")
		)
		(fp_line
			(start 0.7874 0.4064)
			(end 0.7874 -0.4064)
			(stroke
				(width 0.1524)
				(type default)
			)
			(layer "B.SilkS")
		)
		(fp_line
			(start -0.7874 -0.4064)
			(end -0.7874 0.4064)
			(stroke
				(width 0.1524)
				(type default)
			)
			(layer "B.SilkS")
		)
		(fp_line
			(start 0.7874 -0.4064)
			(end -0.7874 -0.4064)
			(stroke
				(width 0.1524)
				(type default)
			)
			(layer "B.SilkS")
		)
		(fp_line
			(start -0.67945 0.3048)
			(end -0.120396 0.3048)
			(stroke
				(width 0.1)
				(type default)
			)
			(layer "B.Fab")
		)
		(fp_line
			(start -0.120396 0.3048)
			(end -0.120396 0.2794)
			(stroke
				(width 0.1)
				(type default)
			)
			(layer "B.Fab")
		)
		(fp_line
			(start 0.12065 0.3048)
			(end 0.67945 0.3048)
			(stroke
				(width 0.1)
				(type default)
			)
			(layer "B.Fab")
		)
		(fp_line
			(start 0.67945 0.3048)
			(end 0.67945 -0.305054)
			(stroke
				(width 0.1)
				(type default)
			)
			(layer "B.Fab")
		)
		(fp_line
			(start -0.120396 0.2794)
			(end 0.12065 0.2794)
			(stroke
				(width 0.1)
				(type default)
			)
			(layer "B.Fab")
		)
		(fp_line
			(start 0.12065 0.2794)
			(end 0.12065 0.3048)
			(stroke
				(width 0.1)
				(type default)
			)
			(layer "B.Fab")
		)
		(fp_line
			(start -0.12065 -0.2794)
			(end -0.12065 -0.3048)
			(stroke
				(width 0.1)
				(type default)
			)
			(layer "B.Fab")
		)
		(fp_line
			(start 0.12065 -0.2794)
			(end -0.12065 -0.2794)
			(stroke
				(width 0.1)
				(type default)
			)
			(layer "B.Fab")
		)
		(fp_line
			(start -0.67945 -0.3048)
			(end -0.67945 0.3048)
			(stroke
				(width 0.1)
				(type default)
			)
			(layer "B.Fab")
		)
		(fp_line
			(start -0.12065 -0.3048)
			(end -0.67945 -0.3048)
			(stroke
				(width 0.1)
				(type default)
			)
			(layer "B.Fab")
		)
		(fp_line
			(start 0.12065 -0.305054)
			(end 0.12065 -0.2794)
			(stroke
				(width 0.1)
				(type default)
			)
			(layer "B.Fab")
		)
		(fp_line
			(start 0.67945 -0.305054)
			(end 0.12065 -0.305054)
			(stroke
				(width 0.1)
				(type default)
			)
			(layer "B.Fab")
		)
		(pad "1" smd circle
			(at 0.40005 0 90)
			(size 0 0)
			(layers "B.Cu" "B.Mask" "B.Paste")
			(net "FAN_PWR_EN_BUF_R")
		)
		(pad "2" smd circle
			(at -0.40005 0 90)
			(size 0 0)
			(layers "B.Cu" "B.Mask" "B.Paste")
			(net "FAN_PWR_EN_BUF")
		)
	)
	(footprint ""
		(layer "B.Cu")
		(at 238.555784 -80.10779)
		(property "Reference" "R7"
			(at 0 0 0)
			(layer "B.SilkS")
			(hide yes)
			(effects
				(font
					(size 1.27 1.27)
				)
				(justify mirror)
			)
		)
		(property "Value" ""
			(at 0 0 0)
			(layer "B.Fab")
			(effects
				(font
					(size 1.27 1.27)
				)
				(justify mirror)
			)
		)
		(duplicate_pad_numbers_are_jumpers no)
		(fp_line
			(start -0.7874 -0.4064)
			(end -0.7874 0.4064)
			(stroke
				(width 0.1524)
				(type default)
			)
			(layer "B.SilkS")
		)
		(fp_line
			(start -0.7874 0.4064)
			(end 0.7874 0.4064)
			(stroke
				(width 0.1524)
				(type default)
			)
			(layer "B.SilkS")
		)
		(fp_line
			(start 0.7874 -0.4064)
			(end -0.7874 -0.4064)
			(stroke
				(width 0.1524)
				(type default)
			)
			(layer "B.SilkS")
		)
		(fp_line
			(start 0.7874 0.4064)
			(end 0.7874 -0.4064)
			(stroke
				(width 0.1524)
				(type default)
			)
			(layer "B.SilkS")
		)
		(fp_line
			(start -0.67945 -0.3048)
			(end -0.67945 0.3048)
			(stroke
				(width 0.1)
				(type default)
			)
			(layer "B.Fab")
		)
		(fp_line
			(start -0.67945 0.3048)
			(end -0.120396 0.3048)
			(stroke
				(width 0.1)
				(type default)
			)
			(layer "B.Fab")
		)
		(fp_line
			(start -0.12065 -0.3048)
			(end -0.67945 -0.3048)
			(stroke
				(width 0.1)
				(type default)
			)
			(layer "B.Fab")
		)
		(fp_line
			(start -0.12065 -0.2794)
			(end -0.12065 -0.3048)
			(stroke
				(width 0.1)
				(type default)
			)
			(layer "B.Fab")
		)
		(fp_line
			(start -0.120396 0.2794)
			(end 0.12065 0.2794)
			(stroke
				(width 0.1)
				(type default)
			)
			(layer "B.Fab")
		)
		(fp_line
			(start -0.120396 0.3048)
			(end -0.120396 0.2794)
			(stroke
				(width 0.1)
				(type default)
			)
			(layer "B.Fab")
		)
		(fp_line
			(start 0.12065 -0.305054)
			(end 0.12065 -0.2794)
			(stroke
				(width 0.1)
				(type default)
			)
			(layer "B.Fab")
		)
		(fp_line
			(start 0.12065 -0.2794)
			(end -0.12065 -0.2794)
			(stroke
				(width 0.1)
				(type default)
			)
			(layer "B.Fab")
		)
		(fp_line
			(start 0.12065 0.2794)
			(end 0.12065 0.3048)
			(stroke
				(width 0.1)
				(type default)
			)
			(layer "B.Fab")
		)
		(fp_line
			(start 0.12065 0.3048)
			(end 0.67945 0.3048)
			(stroke
				(width 0.1)
				(type default)
			)
			(layer "B.Fab")
		)
		(fp_line
			(start 0.67945 -0.305054)
			(end 0.12065 -0.305054)
			(stroke
				(width 0.1)
				(type default)
			)
			(layer "B.Fab")
		)
		(fp_line
			(start 0.67945 0.3048)
			(end 0.67945 -0.305054)
			(stroke
				(width 0.1)
				(type default)
			)
			(layer "B.Fab")
		)
		(pad "1" smd circle
			(at 0.40005 0 180)
			(size 0 0)
			(layers "B.Cu" "B.Mask" "B.Paste")
			(net "SMB_MB_PDB_SDA")
		)
		(pad "2" smd circle
			(at -0.40005 0 180)
			(size 0 0)
			(layers "B.Cu" "B.Mask" "B.Paste")
			(net "SMB_PDB_MISC_SDA_R")
		)
	)
	(footprint ""
		(layer "B.Cu")
		(at 280.543 -35.941 90)
		(property "Reference" "R5931"
			(at 0 0 90)
			(layer "B.SilkS")
			(hide yes)
			(effects
				(font
					(size 1.27 1.27)
				)
				(justify mirror)
			)
		)
		(property "Value" ""
			(at 0 0 90)
			(layer "B.Fab")
			(effects
				(font
					(size 1.27 1.27)
				)
				(justify mirror)
			)
		)
		(duplicate_pad_numbers_are_jumpers no)
		(fp_line
			(start 0.7874 -0.4064)
			(end -0.7874 -0.4064)
			(stroke
				(width 0.1524)
				(type default)
			)
			(layer "B.SilkS")
		)
		(fp_line
			(start -0.7874 -0.4064)
			(end -0.7874 0.4064)
			(stroke
				(width 0.1524)
				(type default)
			)
			(layer "B.SilkS")
		)
		(fp_line
			(start 0.7874 0.4064)
			(end 0.7874 -0.4064)
			(stroke
				(width 0.1524)
				(type default)
			)
			(layer "B.SilkS")
		)
		(fp_line
			(start -0.7874 0.4064)
			(end 0.7874 0.4064)
			(stroke
				(width 0.1524)
				(type default)
			)
			(layer "B.SilkS")
		)
		(fp_line
			(start 0.67945 -0.305054)
			(end 0.12065 -0.305054)
			(stroke
				(width 0.1)
				(type default)
			)
			(layer "B.Fab")
		)
		(fp_line
			(start 0.12065 -0.305054)
			(end 0.12065 -0.2794)
			(stroke
				(width 0.1)
				(type default)
			)
			(layer "B.Fab")
		)
		(fp_line
			(start -0.12065 -0.3048)
			(end -0.67945 -0.3048)
			(stroke
				(width 0.1)
				(type default)
			)
			(layer "B.Fab")
		)
		(fp_line
			(start -0.67945 -0.3048)
			(end -0.67945 0.3048)
			(stroke
				(width 0.1)
				(type default)
			)
			(layer "B.Fab")
		)
		(fp_line
			(start 0.12065 -0.2794)
			(end -0.12065 -0.2794)
			(stroke
				(width 0.1)
				(type default)
			)
			(layer "B.Fab")
		)
		(fp_line
			(start -0.12065 -0.2794)
			(end -0.12065 -0.3048)
			(stroke
				(width 0.1)
				(type default)
			)
			(layer "B.Fab")
		)
		(fp_line
			(start 0.12065 0.2794)
			(end 0.12065 0.3048)
			(stroke
				(width 0.1)
				(type default)
			)
			(layer "B.Fab")
		)
		(fp_line
			(start -0.120396 0.2794)
			(end 0.12065 0.2794)
			(stroke
				(width 0.1)
				(type default)
			)
			(layer "B.Fab")
		)
		(fp_line
			(start 0.67945 0.3048)
			(end 0.67945 -0.305054)
			(stroke
				(width 0.1)
				(type default)
			)
			(layer "B.Fab")
		)
		(fp_line
			(start 0.12065 0.3048)
			(end 0.67945 0.3048)
			(stroke
				(width 0.1)
				(type default)
			)
			(layer "B.Fab")
		)
		(fp_line
			(start -0.120396 0.3048)
			(end -0.120396 0.2794)
			(stroke
				(width 0.1)
				(type default)
			)
			(layer "B.Fab")
		)
		(fp_line
			(start -0.67945 0.3048)
			(end -0.120396 0.3048)
			(stroke
				(width 0.1)
				(type default)
			)
			(layer "B.Fab")
		)
		(pad "1" smd circle
			(at 0.40005 0 270)
			(size 0 0)
			(layers "B.Cu" "B.Mask" "B.Paste")
			(net "P52V_HS1_EN_DELAY_N")
		)
		(pad "2" smd circle
			(at -0.40005 0 270)
			(size 0 0)
			(layers "B.Cu" "B.Mask" "B.Paste")
			(net "GND")
		)
	)
	(footprint ""
		(layer "B.Cu")
		(at 98.806 -78.613)
		(property "Reference" "R174"
			(at 0 0 0)
			(layer "B.SilkS")
			(hide yes)
			(effects
				(font
					(size 1.27 1.27)
				)
				(justify mirror)
			)
		)
		(property "Value" ""
			(at 0 0 0)
			(layer "B.Fab")
			(effects
				(font
					(size 1.27 1.27)
				)
				(justify mirror)
			)
		)
		(duplicate_pad_numbers_are_jumpers no)
		(fp_line
			(start -0.7874 -0.4064)
			(end -0.7874 0.4064)
			(stroke
				(width 0.1524)
				(type default)
			)
			(layer "B.SilkS")
		)
		(fp_line
			(start -0.7874 0.4064)
			(end 0.7874 0.4064)
			(stroke
				(width 0.1524)
				(type default)
			)
			(layer "B.SilkS")
		)
		(fp_line
			(start 0.7874 -0.4064)
			(end -0.7874 -0.4064)
			(stroke
				(width 0.1524)
				(type default)
			)
			(layer "B.SilkS")
		)
		(fp_line
			(start 0.7874 0.4064)
			(end 0.7874 -0.4064)
			(stroke
				(width 0.1524)
				(type default)
			)
			(layer "B.SilkS")
		)
		(fp_line
			(start -0.67945 -0.3048)
			(end -0.67945 0.3048)
			(stroke
				(width 0.1)
				(type default)
			)
			(layer "B.Fab")
		)
		(fp_line
			(start -0.67945 0.3048)
			(end -0.120396 0.3048)
			(stroke
				(width 0.1)
				(type default)
			)
			(layer "B.Fab")
		)
		(fp_line
			(start -0.12065 -0.3048)
			(end -0.67945 -0.3048)
			(stroke
				(width 0.1)
				(type default)
			)
			(layer "B.Fab")
		)
		(fp_line
			(start -0.12065 -0.2794)
			(end -0.12065 -0.3048)
			(stroke
				(width 0.1)
				(type default)
			)
			(layer "B.Fab")
		)
		(fp_line
			(start -0.120396 0.2794)
			(end 0.12065 0.2794)
			(stroke
				(width 0.1)
				(type default)
			)
			(layer "B.Fab")
		)
		(fp_line
			(start -0.120396 0.3048)
			(end -0.120396 0.2794)
			(stroke
				(width 0.1)
				(type default)
			)
			(layer "B.Fab")
		)
		(fp_line
			(start 0.12065 -0.305054)
			(end 0.12065 -0.2794)
			(stroke
				(width 0.1)
				(type default)
			)
			(layer "B.Fab")
		)
		(fp_line
			(start 0.12065 -0.2794)
			(end -0.12065 -0.2794)
			(stroke
				(width 0.1)
				(type default)
			)
			(layer "B.Fab")
		)
		(fp_line
			(start 0.12065 0.2794)
			(end 0.12065 0.3048)
			(stroke
				(width 0.1)
				(type default)
			)
			(layer "B.Fab")
		)
		(fp_line
			(start 0.12065 0.3048)
			(end 0.67945 0.3048)
			(stroke
				(width 0.1)
				(type default)
			)
			(layer "B.Fab")
		)
		(fp_line
			(start 0.67945 -0.305054)
			(end 0.12065 -0.305054)
			(stroke
				(width 0.1)
				(type default)
			)
			(layer "B.Fab")
		)
		(fp_line
			(start 0.67945 0.3048)
			(end 0.67945 -0.305054)
			(stroke
				(width 0.1)
				(type default)
			)
			(layer "B.Fab")
		)
		(pad "1" smd circle
			(at 0.40005 0 180)
			(size 0 0)
			(layers "B.Cu" "B.Mask" "B.Paste")
			(net "P3V3_AUX")
		)
		(pad "2" smd circle
			(at -0.40005 0 180)
			(size 0 0)
			(layers "B.Cu" "B.Mask" "B.Paste")
			(net "SMB_P52V_VPDB_SDA")
		)
	)
	(footprint ""
		(layer "B.Cu")
		(at 229.743 -75.184 90)
		(property "Reference" "R24"
			(at 0 0 90)
			(layer "B.SilkS")
			(hide yes)
			(effects
				(font
					(size 1.27 1.27)
				)
				(justify mirror)
			)
		)
		(property "Value" ""
			(at 0 0 90)
			(layer "B.Fab")
			(effects
				(font
					(size 1.27 1.27)
				)
				(justify mirror)
			)
		)
		(duplicate_pad_numbers_are_jumpers no)
		(fp_line
			(start 0.7874 -0.4064)
			(end -0.7874 -0.4064)
			(stroke
				(width 0.1524)
				(type default)
			)
			(layer "B.SilkS")
		)
		(fp_line
			(start -0.7874 -0.4064)
			(end -0.7874 0.4064)
			(stroke
				(width 0.1524)
				(type default)
			)
			(layer "B.SilkS")
		)
		(fp_line
			(start 0.7874 0.4064)
			(end 0.7874 -0.4064)
			(stroke
				(width 0.1524)
				(type default)
			)
			(layer "B.SilkS")
		)
		(fp_line
			(start -0.7874 0.4064)
			(end 0.7874 0.4064)
			(stroke
				(width 0.1524)
				(type default)
			)
			(layer "B.SilkS")
		)
		(fp_line
			(start 0.67945 -0.305054)
			(end 0.12065 -0.305054)
			(stroke
				(width 0.1)
				(type default)
			)
			(layer "B.Fab")
		)
		(fp_line
			(start 0.12065 -0.305054)
			(end 0.12065 -0.2794)
			(stroke
				(width 0.1)
				(type default)
			)
			(layer "B.Fab")
		)
		(fp_line
			(start -0.12065 -0.3048)
			(end -0.67945 -0.3048)
			(stroke
				(width 0.1)
				(type default)
			)
			(layer "B.Fab")
		)
		(fp_line
			(start -0.67945 -0.3048)
			(end -0.67945 0.3048)
			(stroke
				(width 0.1)
				(type default)
			)
			(layer "B.Fab")
		)
		(fp_line
			(start 0.12065 -0.2794)
			(end -0.12065 -0.2794)
			(stroke
				(width 0.1)
				(type default)
			)
			(layer "B.Fab")
		)
		(fp_line
			(start -0.12065 -0.2794)
			(end -0.12065 -0.3048)
			(stroke
				(width 0.1)
				(type default)
			)
			(layer "B.Fab")
		)
		(fp_line
			(start 0.12065 0.2794)
			(end 0.12065 0.3048)
			(stroke
				(width 0.1)
				(type default)
			)
			(layer "B.Fab")
		)
		(fp_line
			(start -0.120396 0.2794)
			(end 0.12065 0.2794)
			(stroke
				(width 0.1)
				(type default)
			)
			(layer "B.Fab")
		)
		(fp_line
			(start 0.67945 0.3048)
			(end 0.67945 -0.305054)
			(stroke
				(width 0.1)
				(type default)
			)
			(layer "B.Fab")
		)
		(fp_line
			(start 0.12065 0.3048)
			(end 0.67945 0.3048)
			(stroke
				(width 0.1)
				(type default)
			)
			(layer "B.Fab")
		)
		(fp_line
			(start -0.120396 0.3048)
			(end -0.120396 0.2794)
			(stroke
				(width 0.1)
				(type default)
			)
			(layer "B.Fab")
		)
		(fp_line
			(start -0.67945 0.3048)
			(end -0.120396 0.3048)
			(stroke
				(width 0.1)
				(type default)
			)
			(layer "B.Fab")
		)
		(pad "1" smd circle
			(at 0.40005 0 270)
			(size 0 0)
			(layers "B.Cu" "B.Mask" "B.Paste")
			(net "FM_U5_VCC")
		)
		(pad "2" smd circle
			(at -0.40005 0 270)
			(size 0 0)
			(layers "B.Cu" "B.Mask" "B.Paste")
			(net "P3V3_AUX")
		)
	)
	(footprint ""
		(layer "B.Cu")
		(at 266.192 -34.925 180)
		(property "Reference" "R5905"
			(at 0 0 0)
			(layer "B.SilkS")
			(hide yes)
			(effects
				(font
					(size 1.27 1.27)
				)
				(justify mirror)
			)
		)
		(property "Value" ""
			(at 0 0 0)
			(layer "B.Fab")
			(effects
				(font
					(size 1.27 1.27)
				)
				(justify mirror)
			)
		)
		(duplicate_pad_numbers_are_jumpers no)
		(fp_line
			(start 0.7874 0.4064)
			(end 0.7874 -0.4064)
			(stroke
				(width 0.1524)
				(type default)
			)
			(layer "B.SilkS")
		)
		(fp_line
			(start 0.7874 -0.4064)
			(end -0.7874 -0.4064)
			(stroke
				(width 0.1524)
				(type default)
			)
			(layer "B.SilkS")
		)
		(fp_line
			(start -0.7874 0.4064)
			(end 0.7874 0.4064)
			(stroke
				(width 0.1524)
				(type default)
			)
			(layer "B.SilkS")
		)
		(fp_line
			(start -0.7874 -0.4064)
			(end -0.7874 0.4064)
			(stroke
				(width 0.1524)
				(type default)
			)
			(layer "B.SilkS")
		)
		(fp_line
			(start 0.67945 0.3048)
			(end 0.67945 -0.305054)
			(stroke
				(width 0.1)
				(type default)
			)
			(layer "B.Fab")
		)
		(fp_line
			(start 0.67945 -0.305054)
			(end 0.12065 -0.305054)
			(stroke
				(width 0.1)
				(type default)
			)
			(layer "B.Fab")
		)
		(fp_line
			(start 0.12065 0.3048)
			(end 0.67945 0.3048)
			(stroke
				(width 0.1)
				(type default)
			)
			(layer "B.Fab")
		)
		(fp_line
			(start 0.12065 0.2794)
			(end 0.12065 0.3048)
			(stroke
				(width 0.1)
				(type default)
			)
			(layer "B.Fab")
		)
		(fp_line
			(start 0.12065 -0.2794)
			(end -0.12065 -0.2794)
			(stroke
				(width 0.1)
				(type default)
			)
			(layer "B.Fab")
		)
		(fp_line
			(start 0.12065 -0.305054)
			(end 0.12065 -0.2794)
			(stroke
				(width 0.1)
				(type default)
			)
			(layer "B.Fab")
		)
		(fp_line
			(start -0.120396 0.3048)
			(end -0.120396 0.2794)
			(stroke
				(width 0.1)
				(type default)
			)
			(layer "B.Fab")
		)
		(fp_line
			(start -0.120396 0.2794)
			(end 0.12065 0.2794)
			(stroke
				(width 0.1)
				(type default)
			)
			(layer "B.Fab")
		)
		(fp_line
			(start -0.12065 -0.2794)
			(end -0.12065 -0.3048)
			(stroke
				(width 0.1)
				(type default)
			)
			(layer "B.Fab")
		)
		(fp_line
			(start -0.12065 -0.3048)
			(end -0.67945 -0.3048)
			(stroke
				(width 0.1)
				(type default)
			)
			(layer "B.Fab")
		)
		(fp_line
			(start -0.67945 0.3048)
			(end -0.120396 0.3048)
			(stroke
				(width 0.1)
				(type default)
			)
			(layer "B.Fab")
		)
		(fp_line
			(start -0.67945 -0.3048)
			(end -0.67945 0.3048)
			(stroke
				(width 0.1)
				(type default)
			)
			(layer "B.Fab")
		)
		(pad "1" smd circle
			(at 0.40005 0)
			(size 0 0)
			(layers "B.Cu" "B.Mask" "B.Paste")
			(net "P52V_HS1_INTVCC")
		)
		(pad "2" smd circle
			(at -0.40005 0)
			(size 0 0)
			(layers "B.Cu" "B.Mask" "B.Paste")
			(net "P52V_HS1_ADR0")
		)
	)
	(footprint ""
		(layer "B.Cu")
		(at 240.538 -73.533 -90)
		(property "Reference" "C66"
			(at 0 0 90)
			(layer "B.SilkS")
			(hide yes)
			(effects
				(font
					(size 1.27 1.27)
				)
				(justify mirror)
			)
		)
		(property "Value" ""
			(at 0 0 90)
			(layer "B.Fab")
			(effects
				(font
					(size 1.27 1.27)
				)
				(justify mirror)
			)
		)
		(duplicate_pad_numbers_are_jumpers no)
		(fp_line
			(start -0.7874 0.4064)
			(end 0.7874 0.4064)
			(stroke
				(width 0.1524)
				(type default)
			)
			(layer "B.SilkS")
		)
		(fp_line
			(start 0.7874 0.4064)
			(end 0.7874 -0.4064)
			(stroke
				(width 0.1524)
				(type default)
			)
			(layer "B.SilkS")
		)
		(fp_line
			(start -0.7874 -0.4064)
			(end -0.7874 0.4064)
			(stroke
				(width 0.1524)
				(type default)
			)
			(layer "B.SilkS")
		)
		(fp_line
			(start 0.7874 -0.4064)
			(end -0.7874 -0.4064)
			(stroke
				(width 0.1524)
				(type default)
			)
			(layer "B.SilkS")
		)
		(fp_line
			(start -0.67945 0.3048)
			(end -0.120396 0.3048)
			(stroke
				(width 0.1)
				(type default)
			)
			(layer "B.Fab")
		)
		(fp_line
			(start -0.120396 0.3048)
			(end -0.120396 0.2794)
			(stroke
				(width 0.1)
				(type default)
			)
			(layer "B.Fab")
		)
		(fp_line
			(start 0.12065 0.3048)
			(end 0.67945 0.3048)
			(stroke
				(width 0.1)
				(type default)
			)
			(layer "B.Fab")
		)
		(fp_line
			(start 0.67945 0.3048)
			(end 0.67945 -0.305054)
			(stroke
				(width 0.1)
				(type default)
			)
			(layer "B.Fab")
		)
		(fp_line
			(start -0.120396 0.2794)
			(end 0.12065 0.2794)
			(stroke
				(width 0.1)
				(type default)
			)
			(layer "B.Fab")
		)
		(fp_line
			(start 0.12065 0.2794)
			(end 0.12065 0.3048)
			(stroke
				(width 0.1)
				(type default)
			)
			(layer "B.Fab")
		)
		(fp_line
			(start -0.12065 -0.2794)
			(end -0.12065 -0.3048)
			(stroke
				(width 0.1)
				(type default)
			)
			(layer "B.Fab")
		)
		(fp_line
			(start 0.12065 -0.2794)
			(end -0.12065 -0.2794)
			(stroke
				(width 0.1)
				(type default)
			)
			(layer "B.Fab")
		)
		(fp_line
			(start -0.67945 -0.3048)
			(end -0.67945 0.3048)
			(stroke
				(width 0.1)
				(type default)
			)
			(layer "B.Fab")
		)
		(fp_line
			(start -0.12065 -0.3048)
			(end -0.67945 -0.3048)
			(stroke
				(width 0.1)
				(type default)
			)
			(layer "B.Fab")
		)
		(fp_line
			(start 0.12065 -0.305054)
			(end 0.12065 -0.2794)
			(stroke
				(width 0.1)
				(type default)
			)
			(layer "B.Fab")
		)
		(fp_line
			(start 0.67945 -0.305054)
			(end 0.12065 -0.305054)
			(stroke
				(width 0.1)
				(type default)
			)
			(layer "B.Fab")
		)
		(pad "1" smd circle
			(at 0.40005 0 90)
			(size 0 0)
			(layers "B.Cu" "B.Mask" "B.Paste")
			(net "SMB_MB_PDB_R_SCL")
		)
		(pad "2" smd circle
			(at -0.40005 0 90)
			(size 0 0)
			(layers "B.Cu" "B.Mask" "B.Paste")
			(net "GND")
		)
	)
	(footprint ""
		(layer "B.Cu")
		(at 279.908 -41.91)
		(property "Reference" "PR31"
			(at 0 0 0)
			(layer "B.SilkS")
			(hide yes)
			(effects
				(font
					(size 1.27 1.27)
				)
				(justify mirror)
			)
		)
		(property "Value" ""
			(at 0 0 0)
			(layer "B.Fab")
			(effects
				(font
					(size 1.27 1.27)
				)
				(justify mirror)
			)
		)
		(duplicate_pad_numbers_are_jumpers no)
		(fp_line
			(start -0.7874 -0.4064)
			(end -0.7874 0.4064)
			(stroke
				(width 0.1524)
				(type default)
			)
			(layer "B.SilkS")
		)
		(fp_line
			(start -0.7874 0.4064)
			(end 0.7874 0.4064)
			(stroke
				(width 0.1524)
				(type default)
			)
			(layer "B.SilkS")
		)
		(fp_line
			(start 0.7874 -0.4064)
			(end -0.7874 -0.4064)
			(stroke
				(width 0.1524)
				(type default)
			)
			(layer "B.SilkS")
		)
		(fp_line
			(start 0.7874 0.4064)
			(end 0.7874 -0.4064)
			(stroke
				(width 0.1524)
				(type default)
			)
			(layer "B.SilkS")
		)
		(fp_line
			(start -0.67945 -0.3048)
			(end -0.67945 0.3048)
			(stroke
				(width 0.1)
				(type default)
			)
			(layer "B.Fab")
		)
		(fp_line
			(start -0.67945 0.3048)
			(end -0.120396 0.3048)
			(stroke
				(width 0.1)
				(type default)
			)
			(layer "B.Fab")
		)
		(fp_line
			(start -0.12065 -0.3048)
			(end -0.67945 -0.3048)
			(stroke
				(width 0.1)
				(type default)
			)
			(layer "B.Fab")
		)
		(fp_line
			(start -0.12065 -0.2794)
			(end -0.12065 -0.3048)
			(stroke
				(width 0.1)
				(type default)
			)
			(layer "B.Fab")
		)
		(fp_line
			(start -0.120396 0.2794)
			(end 0.12065 0.2794)
			(stroke
				(width 0.1)
				(type default)
			)
			(layer "B.Fab")
		)
		(fp_line
			(start -0.120396 0.3048)
			(end -0.120396 0.2794)
			(stroke
				(width 0.1)
				(type default)
			)
			(layer "B.Fab")
		)
		(fp_line
			(start 0.12065 -0.305054)
			(end 0.12065 -0.2794)
			(stroke
				(width 0.1)
				(type default)
			)
			(layer "B.Fab")
		)
		(fp_line
			(start 0.12065 -0.2794)
			(end -0.12065 -0.2794)
			(stroke
				(width 0.1)
				(type default)
			)
			(layer "B.Fab")
		)
		(fp_line
			(start 0.12065 0.2794)
			(end 0.12065 0.3048)
			(stroke
				(width 0.1)
				(type default)
			)
			(layer "B.Fab")
		)
		(fp_line
			(start 0.12065 0.3048)
			(end 0.67945 0.3048)
			(stroke
				(width 0.1)
				(type default)
			)
			(layer "B.Fab")
		)
		(fp_line
			(start 0.67945 -0.305054)
			(end 0.12065 -0.305054)
			(stroke
				(width 0.1)
				(type default)
			)
			(layer "B.Fab")
		)
		(fp_line
			(start 0.67945 0.3048)
			(end 0.67945 -0.305054)
			(stroke
				(width 0.1)
				(type default)
			)
			(layer "B.Fab")
		)
		(pad "1" smd circle
			(at 0.40005 0 180)
			(size 0 0)
			(layers "B.Cu" "B.Mask" "B.Paste")
			(net "P52V_HS1_EFAULT_R")
		)
		(pad "2" smd circle
			(at -0.40005 0 180)
			(size 0 0)
			(layers "B.Cu" "B.Mask" "B.Paste")
			(net "P52V_HS1_EFAULT")
		)
	)
	(footprint ""
		(layer "B.Cu")
		(at 222.885 -70.993 -90)
		(property "Reference" "C16"
			(at 0 0 90)
			(layer "B.SilkS")
			(hide yes)
			(effects
				(font
					(size 1.27 1.27)
				)
				(justify mirror)
			)
		)
		(property "Value" ""
			(at 0 0 90)
			(layer "B.Fab")
			(effects
				(font
					(size 1.27 1.27)
				)
				(justify mirror)
			)
		)
		(duplicate_pad_numbers_are_jumpers no)
		(fp_line
			(start -0.7874 0.4064)
			(end 0.7874 0.4064)
			(stroke
				(width 0.1524)
				(type default)
			)
			(layer "B.SilkS")
		)
		(fp_line
			(start 0.7874 0.4064)
			(end 0.7874 -0.4064)
			(stroke
				(width 0.1524)
				(type default)
			)
			(layer "B.SilkS")
		)
		(fp_line
			(start -0.7874 -0.4064)
			(end -0.7874 0.4064)
			(stroke
				(width 0.1524)
				(type default)
			)
			(layer "B.SilkS")
		)
		(fp_line
			(start 0.7874 -0.4064)
			(end -0.7874 -0.4064)
			(stroke
				(width 0.1524)
				(type default)
			)
			(layer "B.SilkS")
		)
		(fp_line
			(start -0.67945 0.3048)
			(end -0.120396 0.3048)
			(stroke
				(width 0.1)
				(type default)
			)
			(layer "B.Fab")
		)
		(fp_line
			(start -0.120396 0.3048)
			(end -0.120396 0.2794)
			(stroke
				(width 0.1)
				(type default)
			)
			(layer "B.Fab")
		)
		(fp_line
			(start 0.12065 0.3048)
			(end 0.67945 0.3048)
			(stroke
				(width 0.1)
				(type default)
			)
			(layer "B.Fab")
		)
		(fp_line
			(start 0.67945 0.3048)
			(end 0.67945 -0.305054)
			(stroke
				(width 0.1)
				(type default)
			)
			(layer "B.Fab")
		)
		(fp_line
			(start -0.120396 0.2794)
			(end 0.12065 0.2794)
			(stroke
				(width 0.1)
				(type default)
			)
			(layer "B.Fab")
		)
		(fp_line
			(start 0.12065 0.2794)
			(end 0.12065 0.3048)
			(stroke
				(width 0.1)
				(type default)
			)
			(layer "B.Fab")
		)
		(fp_line
			(start -0.12065 -0.2794)
			(end -0.12065 -0.3048)
			(stroke
				(width 0.1)
				(type default)
			)
			(layer "B.Fab")
		)
		(fp_line
			(start 0.12065 -0.2794)
			(end -0.12065 -0.2794)
			(stroke
				(width 0.1)
				(type default)
			)
			(layer "B.Fab")
		)
		(fp_line
			(start -0.67945 -0.3048)
			(end -0.67945 0.3048)
			(stroke
				(width 0.1)
				(type default)
			)
			(layer "B.Fab")
		)
		(fp_line
			(start -0.12065 -0.3048)
			(end -0.67945 -0.3048)
			(stroke
				(width 0.1)
				(type default)
			)
			(layer "B.Fab")
		)
		(fp_line
			(start 0.12065 -0.305054)
			(end 0.12065 -0.2794)
			(stroke
				(width 0.1)
				(type default)
			)
			(layer "B.Fab")
		)
		(fp_line
			(start 0.67945 -0.305054)
			(end 0.12065 -0.305054)
			(stroke
				(width 0.1)
				(type default)
			)
			(layer "B.Fab")
		)
		(pad "1" smd circle
			(at 0.40005 0 90)
			(size 0 0)
			(layers "B.Cu" "B.Mask" "B.Paste")
			(net "PWRGD_GPU_HSC_BUF_R")
		)
		(pad "2" smd circle
			(at -0.40005 0 90)
			(size 0 0)
			(layers "B.Cu" "B.Mask" "B.Paste")
			(net "GND")
		)
	)
	(footprint ""
		(layer "B.Cu")
		(at 186.309 -83.439)
		(property "Reference" "R5879"
			(at 0 0 0)
			(layer "B.SilkS")
			(hide yes)
			(effects
				(font
					(size 1.27 1.27)
				)
				(justify mirror)
			)
		)
		(property "Value" ""
			(at 0 0 0)
			(layer "B.Fab")
			(effects
				(font
					(size 1.27 1.27)
				)
				(justify mirror)
			)
		)
		(duplicate_pad_numbers_are_jumpers no)
		(fp_line
			(start -0.7874 -0.4064)
			(end -0.7874 0.4064)
			(stroke
				(width 0.1524)
				(type default)
			)
			(layer "B.SilkS")
		)
		(fp_line
			(start -0.7874 0.4064)
			(end 0.7874 0.4064)
			(stroke
				(width 0.1524)
				(type default)
			)
			(layer "B.SilkS")
		)
		(fp_line
			(start 0.7874 -0.4064)
			(end -0.7874 -0.4064)
			(stroke
				(width 0.1524)
				(type default)
			)
			(layer "B.SilkS")
		)
		(fp_line
			(start 0.7874 0.4064)
			(end 0.7874 -0.4064)
			(stroke
				(width 0.1524)
				(type default)
			)
			(layer "B.SilkS")
		)
		(fp_line
			(start -0.67945 -0.3048)
			(end -0.67945 0.3048)
			(stroke
				(width 0.1)
				(type default)
			)
			(layer "B.Fab")
		)
		(fp_line
			(start -0.67945 0.3048)
			(end -0.120396 0.3048)
			(stroke
				(width 0.1)
				(type default)
			)
			(layer "B.Fab")
		)
		(fp_line
			(start -0.12065 -0.3048)
			(end -0.67945 -0.3048)
			(stroke
				(width 0.1)
				(type default)
			)
			(layer "B.Fab")
		)
		(fp_line
			(start -0.12065 -0.2794)
			(end -0.12065 -0.3048)
			(stroke
				(width 0.1)
				(type default)
			)
			(layer "B.Fab")
		)
		(fp_line
			(start -0.120396 0.2794)
			(end 0.12065 0.2794)
			(stroke
				(width 0.1)
				(type default)
			)
			(layer "B.Fab")
		)
		(fp_line
			(start -0.120396 0.3048)
			(end -0.120396 0.2794)
			(stroke
				(width 0.1)
				(type default)
			)
			(layer "B.Fab")
		)
		(fp_line
			(start 0.12065 -0.305054)
			(end 0.12065 -0.2794)
			(stroke
				(width 0.1)
				(type default)
			)
			(layer "B.Fab")
		)
		(fp_line
			(start 0.12065 -0.2794)
			(end -0.12065 -0.2794)
			(stroke
				(width 0.1)
				(type default)
			)
			(layer "B.Fab")
		)
		(fp_line
			(start 0.12065 0.2794)
			(end 0.12065 0.3048)
			(stroke
				(width 0.1)
				(type default)
			)
			(layer "B.Fab")
		)
		(fp_line
			(start 0.12065 0.3048)
			(end 0.67945 0.3048)
			(stroke
				(width 0.1)
				(type default)
			)
			(layer "B.Fab")
		)
		(fp_line
			(start 0.67945 -0.305054)
			(end 0.12065 -0.305054)
			(stroke
				(width 0.1)
				(type default)
			)
			(layer "B.Fab")
		)
		(fp_line
			(start 0.67945 0.3048)
			(end 0.67945 -0.305054)
			(stroke
				(width 0.1)
				(type default)
			)
			(layer "B.Fab")
		)
		(pad "1" smd circle
			(at 0.40005 0 180)
			(size 0 0)
			(layers "B.Cu" "B.Mask" "B.Paste")
			(net "SMB_P52V_VPDB_SDA")
		)
		(pad "2" smd circle
			(at -0.40005 0 180)
			(size 0 0)
			(layers "B.Cu" "B.Mask" "B.Paste")
			(net "SMB_P52V_HSC_SDA")
		)
	)
	(footprint ""
		(layer "B.Cu")
		(at 202.946 -91.948)
		(property "Reference" "R98"
			(at 0 0 0)
			(layer "B.SilkS")
			(hide yes)
			(effects
				(font
					(size 1.27 1.27)
				)
				(justify mirror)
			)
		)
		(property "Value" ""
			(at 0 0 0)
			(layer "B.Fab")
			(effects
				(font
					(size 1.27 1.27)
				)
				(justify mirror)
			)
		)
		(duplicate_pad_numbers_are_jumpers no)
		(fp_line
			(start -0.7874 -0.4064)
			(end -0.7874 0.4064)
			(stroke
				(width 0.1524)
				(type default)
			)
			(layer "B.SilkS")
		)
		(fp_line
			(start -0.7874 0.4064)
			(end 0.7874 0.4064)
			(stroke
				(width 0.1524)
				(type default)
			)
			(layer "B.SilkS")
		)
		(fp_line
			(start 0.7874 -0.4064)
			(end -0.7874 -0.4064)
			(stroke
				(width 0.1524)
				(type default)
			)
			(layer "B.SilkS")
		)
		(fp_line
			(start 0.7874 0.4064)
			(end 0.7874 -0.4064)
			(stroke
				(width 0.1524)
				(type default)
			)
			(layer "B.SilkS")
		)
		(fp_line
			(start -0.67945 -0.3048)
			(end -0.67945 0.3048)
			(stroke
				(width 0.1)
				(type default)
			)
			(layer "B.Fab")
		)
		(fp_line
			(start -0.67945 0.3048)
			(end -0.120396 0.3048)
			(stroke
				(width 0.1)
				(type default)
			)
			(layer "B.Fab")
		)
		(fp_line
			(start -0.12065 -0.3048)
			(end -0.67945 -0.3048)
			(stroke
				(width 0.1)
				(type default)
			)
			(layer "B.Fab")
		)
		(fp_line
			(start -0.12065 -0.2794)
			(end -0.12065 -0.3048)
			(stroke
				(width 0.1)
				(type default)
			)
			(layer "B.Fab")
		)
		(fp_line
			(start -0.120396 0.2794)
			(end 0.12065 0.2794)
			(stroke
				(width 0.1)
				(type default)
			)
			(layer "B.Fab")
		)
		(fp_line
			(start -0.120396 0.3048)
			(end -0.120396 0.2794)
			(stroke
				(width 0.1)
				(type default)
			)
			(layer "B.Fab")
		)
		(fp_line
			(start 0.12065 -0.305054)
			(end 0.12065 -0.2794)
			(stroke
				(width 0.1)
				(type default)
			)
			(layer "B.Fab")
		)
		(fp_line
			(start 0.12065 -0.2794)
			(end -0.12065 -0.2794)
			(stroke
				(width 0.1)
				(type default)
			)
			(layer "B.Fab")
		)
		(fp_line
			(start 0.12065 0.2794)
			(end 0.12065 0.3048)
			(stroke
				(width 0.1)
				(type default)
			)
			(layer "B.Fab")
		)
		(fp_line
			(start 0.12065 0.3048)
			(end 0.67945 0.3048)
			(stroke
				(width 0.1)
				(type default)
			)
			(layer "B.Fab")
		)
		(fp_line
			(start 0.67945 -0.305054)
			(end 0.12065 -0.305054)
			(stroke
				(width 0.1)
				(type default)
			)
			(layer "B.Fab")
		)
		(fp_line
			(start 0.67945 0.3048)
			(end 0.67945 -0.305054)
			(stroke
				(width 0.1)
				(type default)
			)
			(layer "B.Fab")
		)
		(pad "1" smd circle
			(at 0.40005 0 180)
			(size 0 0)
			(layers "B.Cu" "B.Mask" "B.Paste")
			(net "P3V3_AUX")
		)
		(pad "2" smd circle
			(at -0.40005 0 180)
			(size 0 0)
			(layers "B.Cu" "B.Mask" "B.Paste")
			(net "PCA9543_MISC_A0")
		)
	)
	(footprint ""
		(layer "B.Cu")
		(at 202.946 -83.82 180)
		(property "Reference" "R129"
			(at 0 0 0)
			(layer "B.SilkS")
			(hide yes)
			(effects
				(font
					(size 1.27 1.27)
				)
				(justify mirror)
			)
		)
		(property "Value" ""
			(at 0 0 0)
			(layer "B.Fab")
			(effects
				(font
					(size 1.27 1.27)
				)
				(justify mirror)
			)
		)
		(duplicate_pad_numbers_are_jumpers no)
		(fp_line
			(start 0.7874 0.4064)
			(end 0.7874 -0.4064)
			(stroke
				(width 0.1524)
				(type default)
			)
			(layer "B.SilkS")
		)
		(fp_line
			(start 0.7874 -0.4064)
			(end -0.7874 -0.4064)
			(stroke
				(width 0.1524)
				(type default)
			)
			(layer "B.SilkS")
		)
		(fp_line
			(start -0.7874 0.4064)
			(end 0.7874 0.4064)
			(stroke
				(width 0.1524)
				(type default)
			)
			(layer "B.SilkS")
		)
		(fp_line
			(start -0.7874 -0.4064)
			(end -0.7874 0.4064)
			(stroke
				(width 0.1524)
				(type default)
			)
			(layer "B.SilkS")
		)
		(fp_line
			(start 0.67945 0.3048)
			(end 0.67945 -0.305054)
			(stroke
				(width 0.1)
				(type default)
			)
			(layer "B.Fab")
		)
		(fp_line
			(start 0.67945 -0.305054)
			(end 0.12065 -0.305054)
			(stroke
				(width 0.1)
				(type default)
			)
			(layer "B.Fab")
		)
		(fp_line
			(start 0.12065 0.3048)
			(end 0.67945 0.3048)
			(stroke
				(width 0.1)
				(type default)
			)
			(layer "B.Fab")
		)
		(fp_line
			(start 0.12065 0.2794)
			(end 0.12065 0.3048)
			(stroke
				(width 0.1)
				(type default)
			)
			(layer "B.Fab")
		)
		(fp_line
			(start 0.12065 -0.2794)
			(end -0.12065 -0.2794)
			(stroke
				(width 0.1)
				(type default)
			)
			(layer "B.Fab")
		)
		(fp_line
			(start 0.12065 -0.305054)
			(end 0.12065 -0.2794)
			(stroke
				(width 0.1)
				(type default)
			)
			(layer "B.Fab")
		)
		(fp_line
			(start -0.120396 0.3048)
			(end -0.120396 0.2794)
			(stroke
				(width 0.1)
				(type default)
			)
			(layer "B.Fab")
		)
		(fp_line
			(start -0.120396 0.2794)
			(end 0.12065 0.2794)
			(stroke
				(width 0.1)
				(type default)
			)
			(layer "B.Fab")
		)
		(fp_line
			(start -0.12065 -0.2794)
			(end -0.12065 -0.3048)
			(stroke
				(width 0.1)
				(type default)
			)
			(layer "B.Fab")
		)
		(fp_line
			(start -0.12065 -0.3048)
			(end -0.67945 -0.3048)
			(stroke
				(width 0.1)
				(type default)
			)
			(layer "B.Fab")
		)
		(fp_line
			(start -0.67945 0.3048)
			(end -0.120396 0.3048)
			(stroke
				(width 0.1)
				(type default)
			)
			(layer "B.Fab")
		)
		(fp_line
			(start -0.67945 -0.3048)
			(end -0.67945 0.3048)
			(stroke
				(width 0.1)
				(type default)
			)
			(layer "B.Fab")
		)
		(pad "1" smd circle
			(at 0.40005 0)
			(size 0 0)
			(layers "B.Cu" "B.Mask" "B.Paste")
			(net "SMB_HPDB_MISC_SCL")
		)
		(pad "2" smd circle
			(at -0.40005 0)
			(size 0 0)
			(layers "B.Cu" "B.Mask" "B.Paste")
			(net "P3V3_AUX")
		)
	)
	(footprint ""
		(layer "B.Cu")
		(at 232.029 -95.504 90)
		(property "Reference" "C28"
			(at 0 0 90)
			(layer "B.SilkS")
			(hide yes)
			(effects
				(font
					(size 1.27 1.27)
				)
				(justify mirror)
			)
		)
		(property "Value" ""
			(at 0 0 90)
			(layer "B.Fab")
			(effects
				(font
					(size 1.27 1.27)
				)
				(justify mirror)
			)
		)
		(duplicate_pad_numbers_are_jumpers no)
		(fp_line
			(start 2.2098 -0.9398)
			(end -2.2098 -0.9398)
			(stroke
				(width 0.1524)
				(type default)
			)
			(layer "B.SilkS")
		)
		(fp_line
			(start -2.2098 -0.9398)
			(end -2.2098 0.9398)
			(stroke
				(width 0.1524)
				(type default)
			)
			(layer "B.SilkS")
		)
		(fp_line
			(start 2.2098 0.9398)
			(end 2.2098 -0.9398)
			(stroke
				(width 0.1524)
				(type default)
			)
			(layer "B.SilkS")
		)
		(fp_line
			(start -2.2098 0.9398)
			(end 2.2098 0.9398)
			(stroke
				(width 0.1524)
				(type default)
			)
			(layer "B.SilkS")
		)
		(fp_line
			(start 1.700022 -0.899922)
			(end -1.700022 -0.899922)
			(stroke
				(width 0.1)
				(type default)
			)
			(layer "B.Fab")
		)
		(fp_line
			(start -1.700022 -0.899922)
			(end -1.700022 0.899922)
			(stroke
				(width 0.1)
				(type default)
			)
			(layer "B.Fab")
		)
		(fp_line
			(start 1.700022 0.899922)
			(end 1.700022 -0.899922)
			(stroke
				(width 0.1)
				(type default)
			)
			(layer "B.Fab")
		)
		(fp_line
			(start -1.700022 0.899922)
			(end 1.700022 0.899922)
			(stroke
				(width 0.1)
				(type default)
			)
			(layer "B.Fab")
		)
		(pad "1" smd rect
			(at 1.4732 0 90)
			(size 1.1684 1.5748)
			(layers "B.Cu" "B.Mask" "B.Paste")
			(net "P52V_HS")
		)
		(pad "2" smd rect
			(at -1.4732 0 90)
			(size 1.1684 1.5748)
			(layers "B.Cu" "B.Mask" "B.Paste")
			(net "GND")
		)
	)
	(footprint ""
		(layer "B.Cu")
		(at 186.309 -85.979)
		(property "Reference" "R5878"
			(at 0 0 0)
			(layer "B.SilkS")
			(hide yes)
			(effects
				(font
					(size 1.27 1.27)
				)
				(justify mirror)
			)
		)
		(property "Value" ""
			(at 0 0 0)
			(layer "B.Fab")
			(effects
				(font
					(size 1.27 1.27)
				)
				(justify mirror)
			)
		)
		(duplicate_pad_numbers_are_jumpers no)
		(fp_line
			(start -0.7874 -0.4064)
			(end -0.7874 0.4064)
			(stroke
				(width 0.1524)
				(type default)
			)
			(layer "B.SilkS")
		)
		(fp_line
			(start -0.7874 0.4064)
			(end 0.7874 0.4064)
			(stroke
				(width 0.1524)
				(type default)
			)
			(layer "B.SilkS")
		)
		(fp_line
			(start 0.7874 -0.4064)
			(end -0.7874 -0.4064)
			(stroke
				(width 0.1524)
				(type default)
			)
			(layer "B.SilkS")
		)
		(fp_line
			(start 0.7874 0.4064)
			(end 0.7874 -0.4064)
			(stroke
				(width 0.1524)
				(type default)
			)
			(layer "B.SilkS")
		)
		(fp_line
			(start -0.67945 -0.3048)
			(end -0.67945 0.3048)
			(stroke
				(width 0.1)
				(type default)
			)
			(layer "B.Fab")
		)
		(fp_line
			(start -0.67945 0.3048)
			(end -0.120396 0.3048)
			(stroke
				(width 0.1)
				(type default)
			)
			(layer "B.Fab")
		)
		(fp_line
			(start -0.12065 -0.3048)
			(end -0.67945 -0.3048)
			(stroke
				(width 0.1)
				(type default)
			)
			(layer "B.Fab")
		)
		(fp_line
			(start -0.12065 -0.2794)
			(end -0.12065 -0.3048)
			(stroke
				(width 0.1)
				(type default)
			)
			(layer "B.Fab")
		)
		(fp_line
			(start -0.120396 0.2794)
			(end 0.12065 0.2794)
			(stroke
				(width 0.1)
				(type default)
			)
			(layer "B.Fab")
		)
		(fp_line
			(start -0.120396 0.3048)
			(end -0.120396 0.2794)
			(stroke
				(width 0.1)
				(type default)
			)
			(layer "B.Fab")
		)
		(fp_line
			(start 0.12065 -0.305054)
			(end 0.12065 -0.2794)
			(stroke
				(width 0.1)
				(type default)
			)
			(layer "B.Fab")
		)
		(fp_line
			(start 0.12065 -0.2794)
			(end -0.12065 -0.2794)
			(stroke
				(width 0.1)
				(type default)
			)
			(layer "B.Fab")
		)
		(fp_line
			(start 0.12065 0.2794)
			(end 0.12065 0.3048)
			(stroke
				(width 0.1)
				(type default)
			)
			(layer "B.Fab")
		)
		(fp_line
			(start 0.12065 0.3048)
			(end 0.67945 0.3048)
			(stroke
				(width 0.1)
				(type default)
			)
			(layer "B.Fab")
		)
		(fp_line
			(start 0.67945 -0.305054)
			(end 0.12065 -0.305054)
			(stroke
				(width 0.1)
				(type default)
			)
			(layer "B.Fab")
		)
		(fp_line
			(start 0.67945 0.3048)
			(end 0.67945 -0.305054)
			(stroke
				(width 0.1)
				(type default)
			)
			(layer "B.Fab")
		)
		(pad "1" smd circle
			(at 0.40005 0 180)
			(size 0 0)
			(layers "B.Cu" "B.Mask" "B.Paste")
			(net "SMB_P52V_VPDB_SCL")
		)
		(pad "2" smd circle
			(at -0.40005 0 180)
			(size 0 0)
			(layers "B.Cu" "B.Mask" "B.Paste")
			(net "SMB_P52V_HSC_SCL")
		)
	)
	(footprint ""
		(layer "B.Cu")
		(at 238.76 -73.533 -90)
		(property "Reference" "C67"
			(at 0 0 90)
			(layer "B.SilkS")
			(hide yes)
			(effects
				(font
					(size 1.27 1.27)
				)
				(justify mirror)
			)
		)
		(property "Value" ""
			(at 0 0 90)
			(layer "B.Fab")
			(effects
				(font
					(size 1.27 1.27)
				)
				(justify mirror)
			)
		)
		(duplicate_pad_numbers_are_jumpers no)
		(fp_line
			(start -0.7874 0.4064)
			(end 0.7874 0.4064)
			(stroke
				(width 0.1524)
				(type default)
			)
			(layer "B.SilkS")
		)
		(fp_line
			(start 0.7874 0.4064)
			(end 0.7874 -0.4064)
			(stroke
				(width 0.1524)
				(type default)
			)
			(layer "B.SilkS")
		)
		(fp_line
			(start -0.7874 -0.4064)
			(end -0.7874 0.4064)
			(stroke
				(width 0.1524)
				(type default)
			)
			(layer "B.SilkS")
		)
		(fp_line
			(start 0.7874 -0.4064)
			(end -0.7874 -0.4064)
			(stroke
				(width 0.1524)
				(type default)
			)
			(layer "B.SilkS")
		)
		(fp_line
			(start -0.67945 0.3048)
			(end -0.120396 0.3048)
			(stroke
				(width 0.1)
				(type default)
			)
			(layer "B.Fab")
		)
		(fp_line
			(start -0.120396 0.3048)
			(end -0.120396 0.2794)
			(stroke
				(width 0.1)
				(type default)
			)
			(layer "B.Fab")
		)
		(fp_line
			(start 0.12065 0.3048)
			(end 0.67945 0.3048)
			(stroke
				(width 0.1)
				(type default)
			)
			(layer "B.Fab")
		)
		(fp_line
			(start 0.67945 0.3048)
			(end 0.67945 -0.305054)
			(stroke
				(width 0.1)
				(type default)
			)
			(layer "B.Fab")
		)
		(fp_line
			(start -0.120396 0.2794)
			(end 0.12065 0.2794)
			(stroke
				(width 0.1)
				(type default)
			)
			(layer "B.Fab")
		)
		(fp_line
			(start 0.12065 0.2794)
			(end 0.12065 0.3048)
			(stroke
				(width 0.1)
				(type default)
			)
			(layer "B.Fab")
		)
		(fp_line
			(start -0.12065 -0.2794)
			(end -0.12065 -0.3048)
			(stroke
				(width 0.1)
				(type default)
			)
			(layer "B.Fab")
		)
		(fp_line
			(start 0.12065 -0.2794)
			(end -0.12065 -0.2794)
			(stroke
				(width 0.1)
				(type default)
			)
			(layer "B.Fab")
		)
		(fp_line
			(start -0.67945 -0.3048)
			(end -0.67945 0.3048)
			(stroke
				(width 0.1)
				(type default)
			)
			(layer "B.Fab")
		)
		(fp_line
			(start -0.12065 -0.3048)
			(end -0.67945 -0.3048)
			(stroke
				(width 0.1)
				(type default)
			)
			(layer "B.Fab")
		)
		(fp_line
			(start 0.12065 -0.305054)
			(end 0.12065 -0.2794)
			(stroke
				(width 0.1)
				(type default)
			)
			(layer "B.Fab")
		)
		(fp_line
			(start 0.67945 -0.305054)
			(end 0.12065 -0.305054)
			(stroke
				(width 0.1)
				(type default)
			)
			(layer "B.Fab")
		)
		(pad "1" smd circle
			(at 0.40005 0 90)
			(size 0 0)
			(layers "B.Cu" "B.Mask" "B.Paste")
			(net "SMB_MB_PDB_R_SDA")
		)
		(pad "2" smd circle
			(at -0.40005 0 90)
			(size 0 0)
			(layers "B.Cu" "B.Mask" "B.Paste")
			(net "GND")
		)
	)
	(footprint ""
		(layer "B.Cu")
		(at 62.850014 -76.708 -90)
		(property "Reference" "PR78"
			(at 0 0 90)
			(layer "B.SilkS")
			(hide yes)
			(effects
				(font
					(size 1.27 1.27)
				)
				(justify mirror)
			)
		)
		(property "Value" ""
			(at 0 0 90)
			(layer "B.Fab")
			(effects
				(font
					(size 1.27 1.27)
				)
				(justify mirror)
			)
		)
		(duplicate_pad_numbers_are_jumpers no)
		(fp_line
			(start -0.7874 0.4064)
			(end 0.7874 0.4064)
			(stroke
				(width 0.1524)
				(type default)
			)
			(layer "B.SilkS")
		)
		(fp_line
			(start 0.7874 0.4064)
			(end 0.7874 -0.4064)
			(stroke
				(width 0.1524)
				(type default)
			)
			(layer "B.SilkS")
		)
		(fp_line
			(start -0.7874 -0.4064)
			(end -0.7874 0.4064)
			(stroke
				(width 0.1524)
				(type default)
			)
			(layer "B.SilkS")
		)
		(fp_line
			(start 0.7874 -0.4064)
			(end -0.7874 -0.4064)
			(stroke
				(width 0.1524)
				(type default)
			)
			(layer "B.SilkS")
		)
		(fp_line
			(start -0.67945 0.3048)
			(end -0.120396 0.3048)
			(stroke
				(width 0.1)
				(type default)
			)
			(layer "B.Fab")
		)
		(fp_line
			(start -0.120396 0.3048)
			(end -0.120396 0.2794)
			(stroke
				(width 0.1)
				(type default)
			)
			(layer "B.Fab")
		)
		(fp_line
			(start 0.12065 0.3048)
			(end 0.67945 0.3048)
			(stroke
				(width 0.1)
				(type default)
			)
			(layer "B.Fab")
		)
		(fp_line
			(start 0.67945 0.3048)
			(end 0.67945 -0.305054)
			(stroke
				(width 0.1)
				(type default)
			)
			(layer "B.Fab")
		)
		(fp_line
			(start -0.120396 0.2794)
			(end 0.12065 0.2794)
			(stroke
				(width 0.1)
				(type default)
			)
			(layer "B.Fab")
		)
		(fp_line
			(start 0.12065 0.2794)
			(end 0.12065 0.3048)
			(stroke
				(width 0.1)
				(type default)
			)
			(layer "B.Fab")
		)
		(fp_line
			(start -0.12065 -0.2794)
			(end -0.12065 -0.3048)
			(stroke
				(width 0.1)
				(type default)
			)
			(layer "B.Fab")
		)
		(fp_line
			(start 0.12065 -0.2794)
			(end -0.12065 -0.2794)
			(stroke
				(width 0.1)
				(type default)
			)
			(layer "B.Fab")
		)
		(fp_line
			(start -0.67945 -0.3048)
			(end -0.67945 0.3048)
			(stroke
				(width 0.1)
				(type default)
			)
			(layer "B.Fab")
		)
		(fp_line
			(start -0.12065 -0.3048)
			(end -0.67945 -0.3048)
			(stroke
				(width 0.1)
				(type default)
			)
			(layer "B.Fab")
		)
		(fp_line
			(start 0.12065 -0.305054)
			(end 0.12065 -0.2794)
			(stroke
				(width 0.1)
				(type default)
			)
			(layer "B.Fab")
		)
		(fp_line
			(start 0.67945 -0.305054)
			(end 0.12065 -0.305054)
			(stroke
				(width 0.1)
				(type default)
			)
			(layer "B.Fab")
		)
		(pad "1" smd rect
			(at 0.40005 0 270)
			(size 0.4572 0.508)
			(layers "B.Cu" "B.Mask" "B.Paste")
			(net "P12V_MB3_SENSE+")
		)
		(pad "2" smd rect
			(at -0.40005 0 270)
			(size 0.4572 0.508)
			(layers "B.Cu" "B.Mask" "B.Paste")
			(net "P12V_BRICK")
		)
	)
	(footprint ""
		(layer "B.Cu")
		(at 293.497 -53.34 90)
		(property "Reference" "PR4"
			(at 0 0 90)
			(layer "B.SilkS")
			(hide yes)
			(effects
				(font
					(size 1.27 1.27)
				)
				(justify mirror)
			)
		)
		(property "Value" ""
			(at 0 0 90)
			(layer "B.Fab")
			(effects
				(font
					(size 1.27 1.27)
				)
				(justify mirror)
			)
		)
		(duplicate_pad_numbers_are_jumpers no)
		(fp_line
			(start 1.651 -0.8382)
			(end -1.651 -0.8382)
			(stroke
				(width 0.1524)
				(type default)
			)
			(layer "B.SilkS")
		)
		(fp_line
			(start -1.651 -0.8382)
			(end -1.651 0.8382)
			(stroke
				(width 0.1524)
				(type default)
			)
			(layer "B.SilkS")
		)
		(fp_line
			(start 1.651 0.8382)
			(end 1.651 -0.8382)
			(stroke
				(width 0.1524)
				(type default)
			)
			(layer "B.SilkS")
		)
		(fp_line
			(start -1.651 0.8382)
			(end 1.651 0.8382)
			(stroke
				(width 0.1524)
				(type default)
			)
			(layer "B.SilkS")
		)
		(fp_line
			(start 1.559814 -0.7366)
			(end 1.559814 0.7366)
			(stroke
				(width 0.1)
				(type default)
			)
			(layer "B.Fab")
		)
		(fp_line
			(start 1.524 -0.7366)
			(end 1.559814 -0.7366)
			(stroke
				(width 0.1)
				(type default)
			)
			(layer "B.Fab")
		)
		(fp_line
			(start -1.524 -0.7366)
			(end 1.524 -0.7366)
			(stroke
				(width 0.1)
				(type default)
			)
			(layer "B.Fab")
		)
		(fp_line
			(start -1.560576 -0.7366)
			(end -1.524 -0.7366)
			(stroke
				(width 0.1)
				(type default)
			)
			(layer "B.Fab")
		)
		(fp_line
			(start 1.559814 0.7366)
			(end 1.524 0.7366)
			(stroke
				(width 0.1)
				(type default)
			)
			(layer "B.Fab")
		)
		(fp_line
			(start 1.524 0.7366)
			(end -1.524 0.7366)
			(stroke
				(width 0.1)
				(type default)
			)
			(layer "B.Fab")
		)
		(fp_line
			(start -1.524 0.7366)
			(end -1.560576 0.7366)
			(stroke
				(width 0.1)
				(type default)
			)
			(layer "B.Fab")
		)
		(fp_line
			(start -1.560576 0.7366)
			(end -1.560576 -0.7366)
			(stroke
				(width 0.1)
				(type default)
			)
			(layer "B.Fab")
		)
		(pad "1" smd rect
			(at 0.94996 0 90)
			(size 1.1176 1.3716)
			(layers "B.Cu" "B.Mask" "B.Paste")
			(net "P52V_1")
		)
		(pad "2" smd rect
			(at -0.94996 0 90)
			(size 1.1176 1.3716)
			(layers "B.Cu" "B.Mask" "B.Paste")
			(net "P52V_HS1_UVH")
		)
	)
	(footprint ""
		(layer "B.Cu")
		(at 274.955 -46.482 -90)
		(property "Reference" "R5907"
			(at 0 0 90)
			(layer "B.SilkS")
			(hide yes)
			(effects
				(font
					(size 1.27 1.27)
				)
				(justify mirror)
			)
		)
		(property "Value" ""
			(at 0 0 90)
			(layer "B.Fab")
			(effects
				(font
					(size 1.27 1.27)
				)
				(justify mirror)
			)
		)
		(duplicate_pad_numbers_are_jumpers no)
		(fp_line
			(start -0.7874 0.4064)
			(end 0.7874 0.4064)
			(stroke
				(width 0.1524)
				(type default)
			)
			(layer "B.SilkS")
		)
		(fp_line
			(start 0.7874 0.4064)
			(end 0.7874 -0.4064)
			(stroke
				(width 0.1524)
				(type default)
			)
			(layer "B.SilkS")
		)
		(fp_line
			(start -0.7874 -0.4064)
			(end -0.7874 0.4064)
			(stroke
				(width 0.1524)
				(type default)
			)
			(layer "B.SilkS")
		)
		(fp_line
			(start 0.7874 -0.4064)
			(end -0.7874 -0.4064)
			(stroke
				(width 0.1524)
				(type default)
			)
			(layer "B.SilkS")
		)
		(fp_line
			(start -0.67945 0.3048)
			(end -0.120396 0.3048)
			(stroke
				(width 0.1)
				(type default)
			)
			(layer "B.Fab")
		)
		(fp_line
			(start -0.120396 0.3048)
			(end -0.120396 0.2794)
			(stroke
				(width 0.1)
				(type default)
			)
			(layer "B.Fab")
		)
		(fp_line
			(start 0.12065 0.3048)
			(end 0.67945 0.3048)
			(stroke
				(width 0.1)
				(type default)
			)
			(layer "B.Fab")
		)
		(fp_line
			(start 0.67945 0.3048)
			(end 0.67945 -0.305054)
			(stroke
				(width 0.1)
				(type default)
			)
			(layer "B.Fab")
		)
		(fp_line
			(start -0.120396 0.2794)
			(end 0.12065 0.2794)
			(stroke
				(width 0.1)
				(type default)
			)
			(layer "B.Fab")
		)
		(fp_line
			(start 0.12065 0.2794)
			(end 0.12065 0.3048)
			(stroke
				(width 0.1)
				(type default)
			)
			(layer "B.Fab")
		)
		(fp_line
			(start -0.12065 -0.2794)
			(end -0.12065 -0.3048)
			(stroke
				(width 0.1)
				(type default)
			)
			(layer "B.Fab")
		)
		(fp_line
			(start 0.12065 -0.2794)
			(end -0.12065 -0.2794)
			(stroke
				(width 0.1)
				(type default)
			)
			(layer "B.Fab")
		)
		(fp_line
			(start -0.67945 -0.3048)
			(end -0.67945 0.3048)
			(stroke
				(width 0.1)
				(type default)
			)
			(layer "B.Fab")
		)
		(fp_line
			(start -0.12065 -0.3048)
			(end -0.67945 -0.3048)
			(stroke
				(width 0.1)
				(type default)
			)
			(layer "B.Fab")
		)
		(fp_line
			(start 0.12065 -0.305054)
			(end 0.12065 -0.2794)
			(stroke
				(width 0.1)
				(type default)
			)
			(layer "B.Fab")
		)
		(fp_line
			(start 0.67945 -0.305054)
			(end 0.12065 -0.305054)
			(stroke
				(width 0.1)
				(type default)
			)
			(layer "B.Fab")
		)
		(pad "1" smd circle
			(at 0.40005 0 90)
			(size 0 0)
			(layers "B.Cu" "B.Mask" "B.Paste")
			(net "P52V_HS1_ADR0")
		)
		(pad "2" smd circle
			(at -0.40005 0 90)
			(size 0 0)
			(layers "B.Cu" "B.Mask" "B.Paste")
			(net "GND_FIELD_SIGNAL")
		)
	)
	(footprint ""
		(layer "B.Cu")
		(at 215.265 -91.059 90)
		(property "Reference" "R33"
			(at 0 0 90)
			(layer "B.SilkS")
			(hide yes)
			(effects
				(font
					(size 1.27 1.27)
				)
				(justify mirror)
			)
		)
		(property "Value" ""
			(at 0 0 90)
			(layer "B.Fab")
			(effects
				(font
					(size 1.27 1.27)
				)
				(justify mirror)
			)
		)
		(duplicate_pad_numbers_are_jumpers no)
		(fp_line
			(start 0.7874 -0.4064)
			(end -0.7874 -0.4064)
			(stroke
				(width 0.1524)
				(type default)
			)
			(layer "B.SilkS")
		)
		(fp_line
			(start -0.7874 -0.4064)
			(end -0.7874 0.4064)
			(stroke
				(width 0.1524)
				(type default)
			)
			(layer "B.SilkS")
		)
		(fp_line
			(start 0.7874 0.4064)
			(end 0.7874 -0.4064)
			(stroke
				(width 0.1524)
				(type default)
			)
			(layer "B.SilkS")
		)
		(fp_line
			(start -0.7874 0.4064)
			(end 0.7874 0.4064)
			(stroke
				(width 0.1524)
				(type default)
			)
			(layer "B.SilkS")
		)
		(fp_line
			(start 0.67945 -0.305054)
			(end 0.12065 -0.305054)
			(stroke
				(width 0.1)
				(type default)
			)
			(layer "B.Fab")
		)
		(fp_line
			(start 0.12065 -0.305054)
			(end 0.12065 -0.2794)
			(stroke
				(width 0.1)
				(type default)
			)
			(layer "B.Fab")
		)
		(fp_line
			(start -0.12065 -0.3048)
			(end -0.67945 -0.3048)
			(stroke
				(width 0.1)
				(type default)
			)
			(layer "B.Fab")
		)
		(fp_line
			(start -0.67945 -0.3048)
			(end -0.67945 0.3048)
			(stroke
				(width 0.1)
				(type default)
			)
			(layer "B.Fab")
		)
		(fp_line
			(start 0.12065 -0.2794)
			(end -0.12065 -0.2794)
			(stroke
				(width 0.1)
				(type default)
			)
			(layer "B.Fab")
		)
		(fp_line
			(start -0.12065 -0.2794)
			(end -0.12065 -0.3048)
			(stroke
				(width 0.1)
				(type default)
			)
			(layer "B.Fab")
		)
		(fp_line
			(start 0.12065 0.2794)
			(end 0.12065 0.3048)
			(stroke
				(width 0.1)
				(type default)
			)
			(layer "B.Fab")
		)
		(fp_line
			(start -0.120396 0.2794)
			(end 0.12065 0.2794)
			(stroke
				(width 0.1)
				(type default)
			)
			(layer "B.Fab")
		)
		(fp_line
			(start 0.67945 0.3048)
			(end 0.67945 -0.305054)
			(stroke
				(width 0.1)
				(type default)
			)
			(layer "B.Fab")
		)
		(fp_line
			(start 0.12065 0.3048)
			(end 0.67945 0.3048)
			(stroke
				(width 0.1)
				(type default)
			)
			(layer "B.Fab")
		)
		(fp_line
			(start -0.120396 0.3048)
			(end -0.120396 0.2794)
			(stroke
				(width 0.1)
				(type default)
			)
			(layer "B.Fab")
		)
		(fp_line
			(start -0.67945 0.3048)
			(end -0.120396 0.3048)
			(stroke
				(width 0.1)
				(type default)
			)
			(layer "B.Fab")
		)
		(pad "1" smd circle
			(at 0.40005 0 270)
			(size 0 0)
			(layers "B.Cu" "B.Mask" "B.Paste")
			(net "GND")
		)
		(pad "2" smd circle
			(at -0.40005 0 270)
			(size 0 0)
			(layers "B.Cu" "B.Mask" "B.Paste")
			(net "FAN_PWR_EN_BUF_R")
		)
	)
	(footprint ""
		(layer "B.Cu")
		(at 265.049 -38.354 180)
		(property "Reference" "R5906"
			(at 0 0 0)
			(layer "B.SilkS")
			(hide yes)
			(effects
				(font
					(size 1.27 1.27)
				)
				(justify mirror)
			)
		)
		(property "Value" ""
			(at 0 0 0)
			(layer "B.Fab")
			(effects
				(font
					(size 1.27 1.27)
				)
				(justify mirror)
			)
		)
		(duplicate_pad_numbers_are_jumpers no)
		(fp_line
			(start 0.7874 0.4064)
			(end 0.7874 -0.4064)
			(stroke
				(width 0.1524)
				(type default)
			)
			(layer "B.SilkS")
		)
		(fp_line
			(start 0.7874 -0.4064)
			(end -0.7874 -0.4064)
			(stroke
				(width 0.1524)
				(type default)
			)
			(layer "B.SilkS")
		)
		(fp_line
			(start -0.7874 0.4064)
			(end 0.7874 0.4064)
			(stroke
				(width 0.1524)
				(type default)
			)
			(layer "B.SilkS")
		)
		(fp_line
			(start -0.7874 -0.4064)
			(end -0.7874 0.4064)
			(stroke
				(width 0.1524)
				(type default)
			)
			(layer "B.SilkS")
		)
		(fp_line
			(start 0.67945 0.3048)
			(end 0.67945 -0.305054)
			(stroke
				(width 0.1)
				(type default)
			)
			(layer "B.Fab")
		)
		(fp_line
			(start 0.67945 -0.305054)
			(end 0.12065 -0.305054)
			(stroke
				(width 0.1)
				(type default)
			)
			(layer "B.Fab")
		)
		(fp_line
			(start 0.12065 0.3048)
			(end 0.67945 0.3048)
			(stroke
				(width 0.1)
				(type default)
			)
			(layer "B.Fab")
		)
		(fp_line
			(start 0.12065 0.2794)
			(end 0.12065 0.3048)
			(stroke
				(width 0.1)
				(type default)
			)
			(layer "B.Fab")
		)
		(fp_line
			(start 0.12065 -0.2794)
			(end -0.12065 -0.2794)
			(stroke
				(width 0.1)
				(type default)
			)
			(layer "B.Fab")
		)
		(fp_line
			(start 0.12065 -0.305054)
			(end 0.12065 -0.2794)
			(stroke
				(width 0.1)
				(type default)
			)
			(layer "B.Fab")
		)
		(fp_line
			(start -0.120396 0.3048)
			(end -0.120396 0.2794)
			(stroke
				(width 0.1)
				(type default)
			)
			(layer "B.Fab")
		)
		(fp_line
			(start -0.120396 0.2794)
			(end 0.12065 0.2794)
			(stroke
				(width 0.1)
				(type default)
			)
			(layer "B.Fab")
		)
		(fp_line
			(start -0.12065 -0.2794)
			(end -0.12065 -0.3048)
			(stroke
				(width 0.1)
				(type default)
			)
			(layer "B.Fab")
		)
		(fp_line
			(start -0.12065 -0.3048)
			(end -0.67945 -0.3048)
			(stroke
				(width 0.1)
				(type default)
			)
			(layer "B.Fab")
		)
		(fp_line
			(start -0.67945 0.3048)
			(end -0.120396 0.3048)
			(stroke
				(width 0.1)
				(type default)
			)
			(layer "B.Fab")
		)
		(fp_line
			(start -0.67945 -0.3048)
			(end -0.67945 0.3048)
			(stroke
				(width 0.1)
				(type default)
			)
			(layer "B.Fab")
		)
		(pad "1" smd circle
			(at 0.40005 0)
			(size 0 0)
			(layers "B.Cu" "B.Mask" "B.Paste")
			(net "P52V_HS1_INTVCC")
		)
		(pad "2" smd circle
			(at -0.40005 0)
			(size 0 0)
			(layers "B.Cu" "B.Mask" "B.Paste")
			(net "P52V_HS1_ADR1")
		)
	)
	(footprint ""
		(layer "B.Cu")
		(at 56.642 -77.47 180)
		(property "Reference" "C62"
			(at 0 0 0)
			(layer "B.SilkS")
			(hide yes)
			(effects
				(font
					(size 1.27 1.27)
				)
				(justify mirror)
			)
		)
		(property "Value" ""
			(at 0 0 0)
			(layer "B.Fab")
			(effects
				(font
					(size 1.27 1.27)
				)
				(justify mirror)
			)
		)
		(duplicate_pad_numbers_are_jumpers no)
		(fp_line
			(start 0.7874 0.4064)
			(end 0.7874 -0.4064)
			(stroke
				(width 0.1524)
				(type default)
			)
			(layer "B.SilkS")
		)
		(fp_line
			(start 0.7874 -0.4064)
			(end -0.7874 -0.4064)
			(stroke
				(width 0.1524)
				(type default)
			)
			(layer "B.SilkS")
		)
		(fp_line
			(start -0.7874 0.4064)
			(end 0.7874 0.4064)
			(stroke
				(width 0.1524)
				(type default)
			)
			(layer "B.SilkS")
		)
		(fp_line
			(start -0.7874 -0.4064)
			(end -0.7874 0.4064)
			(stroke
				(width 0.1524)
				(type default)
			)
			(layer "B.SilkS")
		)
		(fp_line
			(start 0.67945 0.3048)
			(end 0.67945 -0.305054)
			(stroke
				(width 0.1)
				(type default)
			)
			(layer "B.Fab")
		)
		(fp_line
			(start 0.67945 -0.305054)
			(end 0.12065 -0.305054)
			(stroke
				(width 0.1)
				(type default)
			)
			(layer "B.Fab")
		)
		(fp_line
			(start 0.12065 0.3048)
			(end 0.67945 0.3048)
			(stroke
				(width 0.1)
				(type default)
			)
			(layer "B.Fab")
		)
		(fp_line
			(start 0.12065 0.2794)
			(end 0.12065 0.3048)
			(stroke
				(width 0.1)
				(type default)
			)
			(layer "B.Fab")
		)
		(fp_line
			(start 0.12065 -0.2794)
			(end -0.12065 -0.2794)
			(stroke
				(width 0.1)
				(type default)
			)
			(layer "B.Fab")
		)
		(fp_line
			(start 0.12065 -0.305054)
			(end 0.12065 -0.2794)
			(stroke
				(width 0.1)
				(type default)
			)
			(layer "B.Fab")
		)
		(fp_line
			(start -0.120396 0.3048)
			(end -0.120396 0.2794)
			(stroke
				(width 0.1)
				(type default)
			)
			(layer "B.Fab")
		)
		(fp_line
			(start -0.120396 0.2794)
			(end 0.12065 0.2794)
			(stroke
				(width 0.1)
				(type default)
			)
			(layer "B.Fab")
		)
		(fp_line
			(start -0.12065 -0.2794)
			(end -0.12065 -0.3048)
			(stroke
				(width 0.1)
				(type default)
			)
			(layer "B.Fab")
		)
		(fp_line
			(start -0.12065 -0.3048)
			(end -0.67945 -0.3048)
			(stroke
				(width 0.1)
				(type default)
			)
			(layer "B.Fab")
		)
		(fp_line
			(start -0.67945 0.3048)
			(end -0.120396 0.3048)
			(stroke
				(width 0.1)
				(type default)
			)
			(layer "B.Fab")
		)
		(fp_line
			(start -0.67945 -0.3048)
			(end -0.67945 0.3048)
			(stroke
				(width 0.1)
				(type default)
			)
			(layer "B.Fab")
		)
		(pad "1" smd circle
			(at 0.40005 0)
			(size 0 0)
			(layers "B.Cu" "B.Mask" "B.Paste")
			(net "P12V_BRICK3_ALERT_N")
		)
		(pad "2" smd circle
			(at -0.40005 0)
			(size 0 0)
			(layers "B.Cu" "B.Mask" "B.Paste")
			(net "GND")
		)
	)
	(footprint ""
		(layer "B.Cu")
		(at 144.653 -114.046 -90)
		(property "Reference" "R169"
			(at 0 0 90)
			(layer "B.SilkS")
			(hide yes)
			(effects
				(font
					(size 1.27 1.27)
				)
				(justify mirror)
			)
		)
		(property "Value" ""
			(at 0 0 90)
			(layer "B.Fab")
			(effects
				(font
					(size 1.27 1.27)
				)
				(justify mirror)
			)
		)
		(duplicate_pad_numbers_are_jumpers no)
		(fp_line
			(start -0.7874 0.4064)
			(end 0.7874 0.4064)
			(stroke
				(width 0.1524)
				(type default)
			)
			(layer "B.SilkS")
		)
		(fp_line
			(start 0.7874 0.4064)
			(end 0.7874 -0.4064)
			(stroke
				(width 0.1524)
				(type default)
			)
			(layer "B.SilkS")
		)
		(fp_line
			(start -0.7874 -0.4064)
			(end -0.7874 0.4064)
			(stroke
				(width 0.1524)
				(type default)
			)
			(layer "B.SilkS")
		)
		(fp_line
			(start 0.7874 -0.4064)
			(end -0.7874 -0.4064)
			(stroke
				(width 0.1524)
				(type default)
			)
			(layer "B.SilkS")
		)
		(fp_line
			(start -0.67945 0.3048)
			(end -0.120396 0.3048)
			(stroke
				(width 0.1)
				(type default)
			)
			(layer "B.Fab")
		)
		(fp_line
			(start -0.120396 0.3048)
			(end -0.120396 0.2794)
			(stroke
				(width 0.1)
				(type default)
			)
			(layer "B.Fab")
		)
		(fp_line
			(start 0.12065 0.3048)
			(end 0.67945 0.3048)
			(stroke
				(width 0.1)
				(type default)
			)
			(layer "B.Fab")
		)
		(fp_line
			(start 0.67945 0.3048)
			(end 0.67945 -0.305054)
			(stroke
				(width 0.1)
				(type default)
			)
			(layer "B.Fab")
		)
		(fp_line
			(start -0.120396 0.2794)
			(end 0.12065 0.2794)
			(stroke
				(width 0.1)
				(type default)
			)
			(layer "B.Fab")
		)
		(fp_line
			(start 0.12065 0.2794)
			(end 0.12065 0.3048)
			(stroke
				(width 0.1)
				(type default)
			)
			(layer "B.Fab")
		)
		(fp_line
			(start -0.12065 -0.2794)
			(end -0.12065 -0.3048)
			(stroke
				(width 0.1)
				(type default)
			)
			(layer "B.Fab")
		)
		(fp_line
			(start 0.12065 -0.2794)
			(end -0.12065 -0.2794)
			(stroke
				(width 0.1)
				(type default)
			)
			(layer "B.Fab")
		)
		(fp_line
			(start -0.67945 -0.3048)
			(end -0.67945 0.3048)
			(stroke
				(width 0.1)
				(type default)
			)
			(layer "B.Fab")
		)
		(fp_line
			(start -0.12065 -0.3048)
			(end -0.67945 -0.3048)
			(stroke
				(width 0.1)
				(type default)
			)
			(layer "B.Fab")
		)
		(fp_line
			(start 0.12065 -0.305054)
			(end 0.12065 -0.2794)
			(stroke
				(width 0.1)
				(type default)
			)
			(layer "B.Fab")
		)
		(fp_line
			(start 0.67945 -0.305054)
			(end 0.12065 -0.305054)
			(stroke
				(width 0.1)
				(type default)
			)
			(layer "B.Fab")
		)
		(pad "1" smd circle
			(at 0.40005 0 90)
			(size 0 0)
			(layers "B.Cu" "B.Mask" "B.Paste")
			(net "BRICK_P12V0_EN_R_N")
		)
		(pad "2" smd circle
			(at -0.40005 0 90)
			(size 0 0)
			(layers "B.Cu" "B.Mask" "B.Paste")
			(net "BRICK_P12V0_EN_N")
		)
	)
	(footprint ""
		(layer "B.Cu")
		(at 142.850108 -76.708 -90)
		(property "Reference" "PR50"
			(at 0 0 90)
			(layer "B.SilkS")
			(hide yes)
			(effects
				(font
					(size 1.27 1.27)
				)
				(justify mirror)
			)
		)
		(property "Value" ""
			(at 0 0 90)
			(layer "B.Fab")
			(effects
				(font
					(size 1.27 1.27)
				)
				(justify mirror)
			)
		)
		(duplicate_pad_numbers_are_jumpers no)
		(fp_line
			(start -0.7874 0.4064)
			(end 0.7874 0.4064)
			(stroke
				(width 0.1524)
				(type default)
			)
			(layer "B.SilkS")
		)
		(fp_line
			(start 0.7874 0.4064)
			(end 0.7874 -0.4064)
			(stroke
				(width 0.1524)
				(type default)
			)
			(layer "B.SilkS")
		)
		(fp_line
			(start -0.7874 -0.4064)
			(end -0.7874 0.4064)
			(stroke
				(width 0.1524)
				(type default)
			)
			(layer "B.SilkS")
		)
		(fp_line
			(start 0.7874 -0.4064)
			(end -0.7874 -0.4064)
			(stroke
				(width 0.1524)
				(type default)
			)
			(layer "B.SilkS")
		)
		(fp_line
			(start -0.67945 0.3048)
			(end -0.120396 0.3048)
			(stroke
				(width 0.1)
				(type default)
			)
			(layer "B.Fab")
		)
		(fp_line
			(start -0.120396 0.3048)
			(end -0.120396 0.2794)
			(stroke
				(width 0.1)
				(type default)
			)
			(layer "B.Fab")
		)
		(fp_line
			(start 0.12065 0.3048)
			(end 0.67945 0.3048)
			(stroke
				(width 0.1)
				(type default)
			)
			(layer "B.Fab")
		)
		(fp_line
			(start 0.67945 0.3048)
			(end 0.67945 -0.305054)
			(stroke
				(width 0.1)
				(type default)
			)
			(layer "B.Fab")
		)
		(fp_line
			(start -0.120396 0.2794)
			(end 0.12065 0.2794)
			(stroke
				(width 0.1)
				(type default)
			)
			(layer "B.Fab")
		)
		(fp_line
			(start 0.12065 0.2794)
			(end 0.12065 0.3048)
			(stroke
				(width 0.1)
				(type default)
			)
			(layer "B.Fab")
		)
		(fp_line
			(start -0.12065 -0.2794)
			(end -0.12065 -0.3048)
			(stroke
				(width 0.1)
				(type default)
			)
			(layer "B.Fab")
		)
		(fp_line
			(start 0.12065 -0.2794)
			(end -0.12065 -0.2794)
			(stroke
				(width 0.1)
				(type default)
			)
			(layer "B.Fab")
		)
		(fp_line
			(start -0.67945 -0.3048)
			(end -0.67945 0.3048)
			(stroke
				(width 0.1)
				(type default)
			)
			(layer "B.Fab")
		)
		(fp_line
			(start -0.12065 -0.3048)
			(end -0.67945 -0.3048)
			(stroke
				(width 0.1)
				(type default)
			)
			(layer "B.Fab")
		)
		(fp_line
			(start 0.12065 -0.305054)
			(end 0.12065 -0.2794)
			(stroke
				(width 0.1)
				(type default)
			)
			(layer "B.Fab")
		)
		(fp_line
			(start 0.67945 -0.305054)
			(end 0.12065 -0.305054)
			(stroke
				(width 0.1)
				(type default)
			)
			(layer "B.Fab")
		)
		(pad "1" smd rect
			(at 0.40005 0 270)
			(size 0.4572 0.508)
			(layers "B.Cu" "B.Mask" "B.Paste")
			(net "P12V_MB0_SENSE+")
		)
		(pad "2" smd rect
			(at -0.40005 0 270)
			(size 0.4572 0.508)
			(layers "B.Cu" "B.Mask" "B.Paste")
			(net "P12V_BRICK")
		)
	)
	(footprint ""
		(layer "B.Cu")
		(at 223.012 -90.043 -90)
		(property "Reference" "R37"
			(at 0 0 90)
			(layer "B.SilkS")
			(hide yes)
			(effects
				(font
					(size 1.27 1.27)
				)
				(justify mirror)
			)
		)
		(property "Value" ""
			(at 0 0 90)
			(layer "B.Fab")
			(effects
				(font
					(size 1.27 1.27)
				)
				(justify mirror)
			)
		)
		(duplicate_pad_numbers_are_jumpers no)
		(fp_line
			(start -0.7874 0.4064)
			(end 0.7874 0.4064)
			(stroke
				(width 0.1524)
				(type default)
			)
			(layer "B.SilkS")
		)
		(fp_line
			(start 0.7874 0.4064)
			(end 0.7874 -0.4064)
			(stroke
				(width 0.1524)
				(type default)
			)
			(layer "B.SilkS")
		)
		(fp_line
			(start -0.7874 -0.4064)
			(end -0.7874 0.4064)
			(stroke
				(width 0.1524)
				(type default)
			)
			(layer "B.SilkS")
		)
		(fp_line
			(start 0.7874 -0.4064)
			(end -0.7874 -0.4064)
			(stroke
				(width 0.1524)
				(type default)
			)
			(layer "B.SilkS")
		)
		(fp_line
			(start -0.67945 0.3048)
			(end -0.120396 0.3048)
			(stroke
				(width 0.1)
				(type default)
			)
			(layer "B.Fab")
		)
		(fp_line
			(start -0.120396 0.3048)
			(end -0.120396 0.2794)
			(stroke
				(width 0.1)
				(type default)
			)
			(layer "B.Fab")
		)
		(fp_line
			(start 0.12065 0.3048)
			(end 0.67945 0.3048)
			(stroke
				(width 0.1)
				(type default)
			)
			(layer "B.Fab")
		)
		(fp_line
			(start 0.67945 0.3048)
			(end 0.67945 -0.305054)
			(stroke
				(width 0.1)
				(type default)
			)
			(layer "B.Fab")
		)
		(fp_line
			(start -0.120396 0.2794)
			(end 0.12065 0.2794)
			(stroke
				(width 0.1)
				(type default)
			)
			(layer "B.Fab")
		)
		(fp_line
			(start 0.12065 0.2794)
			(end 0.12065 0.3048)
			(stroke
				(width 0.1)
				(type default)
			)
			(layer "B.Fab")
		)
		(fp_line
			(start -0.12065 -0.2794)
			(end -0.12065 -0.3048)
			(stroke
				(width 0.1)
				(type default)
			)
			(layer "B.Fab")
		)
		(fp_line
			(start 0.12065 -0.2794)
			(end -0.12065 -0.2794)
			(stroke
				(width 0.1)
				(type default)
			)
			(layer "B.Fab")
		)
		(fp_line
			(start -0.67945 -0.3048)
			(end -0.67945 0.3048)
			(stroke
				(width 0.1)
				(type default)
			)
			(layer "B.Fab")
		)
		(fp_line
			(start -0.12065 -0.3048)
			(end -0.67945 -0.3048)
			(stroke
				(width 0.1)
				(type default)
			)
			(layer "B.Fab")
		)
		(fp_line
			(start 0.12065 -0.305054)
			(end 0.12065 -0.2794)
			(stroke
				(width 0.1)
				(type default)
			)
			(layer "B.Fab")
		)
		(fp_line
			(start 0.67945 -0.305054)
			(end 0.12065 -0.305054)
			(stroke
				(width 0.1)
				(type default)
			)
			(layer "B.Fab")
		)
		(pad "1" smd circle
			(at 0.40005 0 90)
			(size 0 0)
			(layers "B.Cu" "B.Mask" "B.Paste")
			(net "FRU_WP_N")
		)
		(pad "2" smd circle
			(at -0.40005 0 90)
			(size 0 0)
			(layers "B.Cu" "B.Mask" "B.Paste")
			(net "GND")
		)
	)
	(gr_poly
		(pts
			(xy 43.4594 -63.0174) (xy 43.4594 -62.1284) (xy 43.43527 -62.10427) (xy 41.90873 -62.10427) (xy 41.8592 -62.1538)
			(xy 41.8592 -63.1698) (xy 41.91 -63.2206) (xy 43.2562 -63.2206)
		)
		(stroke
			(width 0)
			(type solid)
		)
		(fill yes)
		(layer "F.Cu")
		(net "P3V3_AUX")
	)
	(gr_poly
		(pts
			(xy 43.572176 -61.707522) (xy 43.572176 -59.472322) (xy 43.432476 -59.332622) (xy 42.741596 -59.332622)
			(xy 42.678096 -59.396122) (xy 42.678096 -61.669422) (xy 42.770044 -61.76137) (xy 43.518328 -61.76137)
		)
		(stroke
			(width 0)
			(type solid)
		)
		(fill yes)
		(layer "F.Cu")
		(net "P12V_HPDB_0_FLTB")
	)
	(gr_poly
		(pts
			(xy 75.71232 -52.48148) (xy 75.71232 -49.3649) (xy 75.61834 -49.27092) (xy 74.06894 -49.27092) (xy 74.03338 -49.30648)
			(xy 74.03338 -52.54498) (xy 74.08164 -52.59324) (xy 75.60056 -52.59324)
		)
		(stroke
			(width 0)
			(type solid)
		)
		(fill yes)
		(layer "F.Cu")
		(net "GND")
	)
	(gr_poly
		(pts
			(xy 81.17332 -52.48148) (xy 81.17332 -49.3649) (xy 81.07934 -49.27092) (xy 79.52994 -49.27092) (xy 79.49438 -49.30648)
			(xy 79.49438 -52.54498) (xy 79.54264 -52.59324) (xy 81.06156 -52.59324)
		)
		(stroke
			(width 0)
			(type solid)
		)
		(fill yes)
		(layer "F.Cu")
		(net "GND")
	)
	(gr_poly
		(pts
			(xy 86.63432 -52.48148) (xy 86.63432 -49.3649) (xy 86.54034 -49.27092) (xy 84.99094 -49.27092) (xy 84.95538 -49.30648)
			(xy 84.95538 -52.54498) (xy 85.00364 -52.59324) (xy 86.52256 -52.59324)
		)
		(stroke
			(width 0)
			(type solid)
		)
		(fill yes)
		(layer "F.Cu")
		(net "GND")
	)
	(gr_poly
		(pts
			(xy 92.09532 -52.48148) (xy 92.09532 -49.3649) (xy 92.00134 -49.27092) (xy 90.45194 -49.27092) (xy 90.41638 -49.30648)
			(xy 90.41638 -52.54498) (xy 90.46464 -52.59324) (xy 91.98356 -52.59324)
		)
		(stroke
			(width 0)
			(type solid)
		)
		(fill yes)
		(layer "F.Cu")
		(net "GND")
	)
	(gr_poly
		(pts
			(xy 97.55632 -52.48148) (xy 97.55632 -49.3649) (xy 97.46234 -49.27092) (xy 95.91294 -49.27092) (xy 95.87738 -49.30648)
			(xy 95.87738 -52.54498) (xy 95.92564 -52.59324) (xy 97.44456 -52.59324)
		)
		(stroke
			(width 0)
			(type solid)
		)
		(fill yes)
		(layer "F.Cu")
		(net "GND")
	)
	(gr_poly
		(pts
			(xy 103.01732 -52.48148) (xy 103.01732 -49.3649) (xy 102.92334 -49.27092) (xy 101.37394 -49.27092)
			(xy 101.33838 -49.30648) (xy 101.33838 -52.54498) (xy 101.38664 -52.59324) (xy 102.90556 -52.59324)
		)
		(stroke
			(width 0)
			(type solid)
		)
		(fill yes)
		(layer "F.Cu")
		(net "GND")
	)
	(gr_poly
		(pts
			(xy 108.47832 -52.48148) (xy 108.47832 -49.3649) (xy 108.38434 -49.27092) (xy 106.83494 -49.27092)
			(xy 106.79938 -49.30648) (xy 106.79938 -52.54498) (xy 106.84764 -52.59324) (xy 108.36656 -52.59324)
		)
		(stroke
			(width 0)
			(type solid)
		)
		(fill yes)
		(layer "F.Cu")
		(net "GND")
	)
	(gr_poly
		(pts
			(xy 153.81732 -52.35448) (xy 153.81732 -49.2379) (xy 153.72334 -49.14392) (xy 152.17394 -49.14392)
			(xy 152.13838 -49.17948) (xy 152.13838 -52.41798) (xy 152.18664 -52.46624) (xy 153.70556 -52.46624)
		)
		(stroke
			(width 0)
			(type solid)
		)
		(fill yes)
		(layer "F.Cu")
		(net "GND")
	)
	(gr_poly
		(pts
			(xy 159.27832 -52.35448) (xy 159.27832 -49.2379) (xy 159.18434 -49.14392) (xy 157.63494 -49.14392)
			(xy 157.59938 -49.17948) (xy 157.59938 -52.41798) (xy 157.64764 -52.46624) (xy 159.16656 -52.46624)
		)
		(stroke
			(width 0)
			(type solid)
		)
		(fill yes)
		(layer "F.Cu")
		(net "GND")
	)
	(gr_poly
		(pts
			(xy 164.73932 -52.35448) (xy 164.73932 -49.2379) (xy 164.64534 -49.14392) (xy 163.09594 -49.14392)
			(xy 163.06038 -49.17948) (xy 163.06038 -52.41798) (xy 163.10864 -52.46624) (xy 164.62756 -52.46624)
		)
		(stroke
			(width 0)
			(type solid)
		)
		(fill yes)
		(layer "F.Cu")
		(net "GND")
	)
	(gr_poly
		(pts
			(xy 170.20032 -52.35448) (xy 170.20032 -49.2379) (xy 170.10634 -49.14392) (xy 168.55694 -49.14392)
			(xy 168.52138 -49.17948) (xy 168.52138 -52.41798) (xy 168.56964 -52.46624) (xy 170.08856 -52.46624)
		)
		(stroke
			(width 0)
			(type solid)
		)
		(fill yes)
		(layer "F.Cu")
		(net "GND")
	)
	(gr_poly
		(pts
			(xy 175.66132 -52.35448) (xy 175.66132 -49.2379) (xy 175.56734 -49.14392) (xy 174.01794 -49.14392)
			(xy 173.98238 -49.17948) (xy 173.98238 -52.41798) (xy 174.03064 -52.46624) (xy 175.54956 -52.46624)
		)
		(stroke
			(width 0)
			(type solid)
		)
		(fill yes)
		(layer "F.Cu")
		(net "GND")
	)
	(gr_poly
		(pts
			(xy 181.11978 -52.35448) (xy 181.11978 -49.2379) (xy 181.0258 -49.14392) (xy 179.4764 -49.14392)
			(xy 179.44084 -49.17948) (xy 179.44084 -52.41798) (xy 179.4891 -52.46624) (xy 181.00802 -52.46624)
		)
		(stroke
			(width 0)
			(type solid)
		)
		(fill yes)
		(layer "F.Cu")
		(net "GND")
	)
	(gr_poly
		(pts
			(xy 186.58078 -52.35448) (xy 186.58078 -49.2379) (xy 186.4868 -49.14392) (xy 184.9374 -49.14392)
			(xy 184.90184 -49.17948) (xy 184.90184 -52.41798) (xy 184.9501 -52.46624) (xy 186.46902 -52.46624)
		)
		(stroke
			(width 0)
			(type solid)
		)
		(fill yes)
		(layer "F.Cu")
		(net "GND")
	)
	(gr_poly
		(pts
			(xy 242.5954 -94.6785) (xy 242.5954 -92.59824) (xy 242.50396 -92.5068) (xy 214.77224 -92.5068) (xy 214.63508 -92.64396)
			(xy 214.63508 -94.55912) (xy 214.81796 -94.742) (xy 242.5319 -94.742)
		)
		(stroke
			(width 0)
			(type solid)
		)
		(fill yes)
		(layer "F.Cu")
		(net "GND")
	)
	(gr_poly
		(pts
			(xy 273.852894 -24.923242) (xy 273.852894 -22.931374) (xy 273.75612 -22.8346) (xy 272.3896 -22.8346)
			(xy 272.3388 -22.8854) (xy 272.3388 -24.8666) (xy 272.4404 -24.9682) (xy 273.807936 -24.9682)
		)
		(stroke
			(width 0)
			(type solid)
		)
		(fill yes)
		(layer "F.Cu")
		(net "P52V_1_R")
	)
	(gr_poly
		(pts
			(xy 274.9296 -129.667) (xy 274.9296 -128.3716) (xy 274.8788 -128.3208) (xy 270.0274 -128.3208) (xy 269.9766 -128.3716)
			(xy 269.9766 -129.667) (xy 270.0274 -129.7178) (xy 274.8788 -129.7178)
		)
		(stroke
			(width 0)
			(type solid)
		)
		(fill yes)
		(layer "F.Cu")
		(net "P52V_HS1_GATE1")
	)
	(gr_poly
		(pts
			(xy 274.9296 -117.602) (xy 274.9296 -116.3066) (xy 274.8788 -116.2558) (xy 270.0274 -116.2558) (xy 269.9766 -116.3066)
			(xy 269.9766 -117.602) (xy 270.0274 -117.6528) (xy 274.8788 -117.6528)
		)
		(stroke
			(width 0)
			(type solid)
		)
		(fill yes)
		(layer "F.Cu")
		(net "P52V_HS1_GATE2")
	)
	(gr_poly
		(pts
			(xy 274.9296 -105.537) (xy 274.9296 -104.2416) (xy 274.8788 -104.1908) (xy 270.0274 -104.1908) (xy 269.9766 -104.2416)
			(xy 269.9766 -105.537) (xy 270.0274 -105.5878) (xy 274.8788 -105.5878)
		)
		(stroke
			(width 0)
			(type solid)
		)
		(fill yes)
		(layer "F.Cu")
		(net "P52V_HS1_GATE3")
	)
	(gr_poly
		(pts
			(xy 274.9296 -93.472) (xy 274.9296 -92.1766) (xy 274.8788 -92.1258) (xy 270.256 -92.1258) (xy 269.9766 -92.4052)
			(xy 269.9766 -93.345) (xy 270.1544 -93.5228) (xy 274.8788 -93.5228)
		)
		(stroke
			(width 0)
			(type solid)
		)
		(fill yes)
		(layer "F.Cu")
		(net "P52V_HS1_GATE4")
	)
	(gr_poly
		(pts
			(xy 274.9296 -81.407) (xy 274.9296 -80.1116) (xy 274.8788 -80.0608) (xy 270.0274 -80.0608) (xy 269.9766 -80.1116)
			(xy 269.9766 -81.407) (xy 270.0274 -81.4578) (xy 274.8788 -81.4578)
		)
		(stroke
			(width 0)
			(type solid)
		)
		(fill yes)
		(layer "F.Cu")
		(net "P52V_HS1_GATE5")
	)
	(gr_poly
		(pts
			(xy 274.9296 -69.342) (xy 274.9296 -68.0466) (xy 274.8788 -67.9958) (xy 270.0274 -67.9958) (xy 269.9766 -68.0466)
			(xy 269.9766 -69.342) (xy 270.0274 -69.3928) (xy 274.8788 -69.3928)
		)
		(stroke
			(width 0)
			(type solid)
		)
		(fill yes)
		(layer "F.Cu")
		(net "P52V_HS1_GATE6")
	)
	(gr_poly
		(pts
			(xy 277.740872 -51.3588) (xy 277.740872 -49.978564) (xy 277.688802 -49.926494) (xy 276.030436 -49.926494)
			(xy 275.941536 -50.015394) (xy 275.941536 -51.318668) (xy 276.030436 -51.407568) (xy 277.692104 -51.407568)
		)
		(stroke
			(width 0)
			(type solid)
		)
		(fill yes)
		(layer "F.Cu")
		(net "P52V_HS")
	)
	(gr_poly
		(pts
			(xy 286.5374 -143.6624) (xy 286.5374 -135.10006) (xy 286.12084 -134.6835) (xy 279.25522 -134.6835)
			(xy 278.765 -135.17372) (xy 278.765 -143.8148) (xy 279.3746 -144.4244) (xy 285.7754 -144.4244)
		)
		(stroke
			(width 0)
			(type solid)
		)
		(fill yes)
		(layer "F.Cu")
		(net "GND")
	)
	(gr_poly
		(pts
			(xy 302.3743 -46.341538) (xy 302.3743 -38.5191) (xy 302.2981 -38.4429) (xy 298.9199 -38.4429) (xy 298.7548 -38.608)
			(xy 298.7548 -46.355) (xy 298.855892 -46.456092) (xy 302.259492 -46.456092)
		)
		(stroke
			(width 0)
			(type solid)
		)
		(fill yes)
		(layer "F.Cu")
		(net "P52V_1_FUSE_1")
	)
	(gr_poly
		(pts
			(xy 277.536656 -34.068258) (xy 277.536656 -32.977836) (xy 277.371556 -32.812736) (xy 276.51583 -32.812736)
			(xy 275.241512 -32.812736) (xy 275.12899 -32.925258) (xy 275.12899 -33.672272) (xy 275.559774 -34.103056)
			(xy 277.502112 -34.103056)
		)
		(stroke
			(width 0)
			(type solid)
		)
		(fill yes)
		(layer "F.Cu")
		(net "P52V_1_R")
	)
	(gr_poly
		(pts
			(xy 266.462764 -33.566608) (xy 266.462764 -32.99206) (xy 267.14958 -32.305244) (xy 267.14958 -31.97098)
			(xy 266.930378 -31.751778) (xy 264.999978 -31.751778) (xy 264.932922 -31.818834) (xy 264.932922 -33.559496)
			(xy 264.980674 -33.607248) (xy 266.422124 -33.607248)
		)
		(stroke
			(width 0)
			(type solid)
		)
		(fill yes)
		(layer "F.Cu")
		(net "HS1_TMR2")
	)
	(gr_poly
		(pts
			(xy 272.8976 -32.8676) (xy 272.8976 -31.4198) (xy 272.8976 -31.2166) (xy 272.6944 -31.0134) (xy 272.4912 -31.0134)
			(xy 270.9672 -31.0134) (xy 270.5862 -31.3944) (xy 270.5862 -32.9438) (xy 270.637 -32.9946) (xy 272.7706 -32.9946)
		)
		(stroke
			(width 0)
			(type solid)
		)
		(fill yes)
		(layer "F.Cu")
		(net "GND")
	)
	(gr_poly
		(pts
			(xy 288.511742 -32.121856) (xy 288.511742 -30.553406) (xy 288.42081 -30.462474) (xy 288.387536 -30.4292)
			(xy 284.73019 -30.4292) (xy 284.696916 -30.462474) (xy 284.618938 -30.540452) (xy 284.618938 -32.138874)
			(xy 284.667198 -32.187134) (xy 288.446464 -32.187134)
		)
		(stroke
			(width 0)
			(type solid)
		)
		(fill yes)
		(layer "F.Cu")
		(net "P52V_HS")
	)
	(gr_poly
		(pts
			(xy 62.778386 -63.07836) (xy 62.778386 -59.61634) (xy 62.656466 -59.49442) (xy 60.856876 -59.49442)
			(xy 60.84189 -59.509406) (xy 60.84189 -61.248798) (xy 60.623704 -61.466984) (xy 60.623704 -63.126112)
			(xy 60.647072 -63.14948) (xy 62.125606 -63.14948) (xy 62.707266 -63.14948)
		)
		(stroke
			(width 0)
			(type solid)
		)
		(fill yes)
		(layer "F.Cu")
		(net "GND")
	)
	(gr_poly
		(pts
			(xy 102.402386 -62.95136) (xy 102.402386 -59.48934) (xy 102.280466 -59.36742) (xy 100.480368 -59.36742)
			(xy 100.466906 -59.380882) (xy 100.466906 -61.120782) (xy 100.24745 -61.340238) (xy 100.24745 -63.008764)
			(xy 100.261166 -63.02248) (xy 101.749606 -63.02248) (xy 102.331266 -63.02248)
		)
		(stroke
			(width 0)
			(type solid)
		)
		(fill yes)
		(layer "F.Cu")
		(net "GND")
	)
	(gr_poly
		(pts
			(xy 141.391386 -63.20536) (xy 141.391386 -59.74334) (xy 141.269466 -59.62142) (xy 139.473178 -59.62142)
			(xy 139.45616 -59.638438) (xy 139.45616 -61.374782) (xy 139.236196 -61.594746) (xy 139.236196 -63.259462)
			(xy 139.253214 -63.27648) (xy 140.738606 -63.27648) (xy 141.320266 -63.27648)
		)
		(stroke
			(width 0)
			(type solid)
		)
		(fill yes)
		(layer "F.Cu")
		(net "GND")
	)
	(gr_poly
		(pts
			(xy 181.39156 -63.20536) (xy 181.39156 -59.74334) (xy 181.26964 -59.62142) (xy 179.470812 -59.62142)
			(xy 179.456334 -59.635898) (xy 179.456334 -61.373258) (xy 179.235862 -61.59373) (xy 179.235862 -63.257938)
			(xy 179.254404 -63.27648) (xy 180.73878 -63.27648) (xy 181.32044 -63.27648)
		)
		(stroke
			(width 0)
			(type solid)
		)
		(fill yes)
		(layer "F.Cu")
		(net "GND")
	)
	(gr_poly
		(pts
			(xy 265.179302 -38.32479) (xy 265.179302 -37.474652) (xy 265.456924 -37.19703) (xy 265.456924 -36.593526)
			(xy 265.456924 -36.174934) (xy 265.405108 -36.123118) (xy 264.9347 -36.123118) (xy 264.89406 -36.163758)
			(xy 264.89406 -38.320472) (xy 264.907522 -38.333934) (xy 265.170158 -38.333934)
		)
		(stroke
			(width 0)
			(type solid)
		)
		(fill yes)
		(layer "F.Cu")
		(net "P52V_HS1_DVCC")
	)
	(gr_poly
		(pts
			(xy 261.747254 -48.636936) (xy 261.747254 -45.729652) (xy 261.216394 -45.198792) (xy 261.216394 -44.41952)
			(xy 261.18693 -44.390056) (xy 260.898386 -44.390056) (xy 260.876034 -44.412408) (xy 260.876034 -46.933612)
			(xy 260.592824 -47.216822) (xy 260.592824 -48.611536) (xy 260.638036 -48.656748) (xy 261.727442 -48.656748)
		)
		(stroke
			(width 0)
			(type solid)
		)
		(fill yes)
		(layer "F.Cu")
		(net "P52V_HS1_VDSFB")
	)
	(gr_poly
		(pts
			(xy 292.836854 -41.302432) (xy 296.045636 -41.302432) (xy 296.078148 -41.26992) (xy 296.078148 -40.070786)
			(xy 296.045382 -40.03802) (xy 293.404036 -40.03802) (xy 292.001194 -41.440862) (xy 291.100764 -41.440862)
			(xy 291.070284 -41.471342) (xy 291.070284 -41.709594) (xy 291.104828 -41.744138) (xy 292.395148 -41.744138)
		)
		(stroke
			(width 0)
			(type solid)
		)
		(fill yes)
		(layer "F.Cu")
		(net "P52V_HS1_VCP")
	)
	(gr_poly
		(pts
			(xy 191.516 -17.831308) (xy 191.516 -6.604) (xy 191.262 -6.35) (xy 185.723276 -6.35) (xy 185.543952 -6.529324)
			(xy 185.543698 -6.529578)
			(arc
				(start 185.198004 -6.875272)
				(mid 185.186893 -6.891806)
				(end 185.183018 -6.91134)
			)
			(xy 185.183018 -17.837658) (xy 185.602372 -18.257012) (xy 191.090296 -18.257012)
		)
		(stroke
			(width 0)
			(type solid)
		)
		(fill yes)
		(layer "F.Cu")
		(net "P3V3_AUX")
	)
	(gr_poly
		(pts
			(xy 261.211822 -38.266624) (xy 261.211822 -35.711384) (xy 261.134098 -35.63366) (xy 259.586222 -35.63366)
			(xy 259.52323 -35.696652) (xy 259.52323 -36.85413) (xy 259.52323 -37.210238) (xy 259.809996 -37.497004)
			(xy 260.773926 -37.497004) (xy 260.863334 -37.586412) (xy 260.863334 -38.280848) (xy 260.88594 -38.303454)
			(xy 261.174992 -38.303454)
		)
		(stroke
			(width 0)
			(type solid)
		)
		(fill yes)
		(layer "F.Cu")
		(net "P52V_1_R")
	)
	(gr_poly
		(pts
			(xy 274.13712 -38.869112) (xy 274.13712 -35.6108) (xy 273.254978 -34.728658) (xy 270.618712 -34.728658)
			(xy 270.577818 -34.769552) (xy 270.584422 -34.769552) (xy 270.584422 -35.898328) (xy 270.62049 -35.934396)
			(xy 272.189956 -35.934396) (xy 273.04873 -36.79317) (xy 273.04873 -38.865302) (xy 273.09699 -38.913562)
			(xy 274.09267 -38.913562)
		)
		(stroke
			(width 0)
			(type solid)
		)
		(fill yes)
		(layer "F.Cu")
		(net "P52V_HS1_DVCC")
	)
	(gr_poly
		(pts
			(xy 296.084244 -44.916852) (xy 296.084244 -44.224702) (xy 296.084244 -43.04919) (xy 296.028364 -42.99331)
			(xy 292.947852 -42.99331) (xy 292.389306 -42.434764) (xy 291.1094 -42.434764) (xy 291.075872 -42.468292)
			(xy 291.075872 -42.728896) (xy 291.107876 -42.7609) (xy 292.17493 -42.7609) (xy 293.69766 -44.28363)
			(xy 294.434006 -45.019976) (xy 295.98112 -45.019976)
		)
		(stroke
			(width 0)
			(type solid)
		)
		(fill yes)
		(layer "F.Cu")
		(net "P52V_HS")
	)
	(gr_poly
		(pts
			(xy 177.6603 -17.779492) (xy 177.6603 -17.0307) (xy 177.6603 -15.8369) (xy 177.6603 -14.8971) (xy 177.6603 -13.9319)
			(xy 177.6603 -13.0429) (xy 177.5206 -12.9032) (xy 176.403 -12.9032) (xy 176.3776 -12.8778) (xy 176.2125 -12.7127)
			(xy 164.8333 -12.7127) (xy 164.592 -12.954) (xy 164.592 -17.653) (xy 165.23589 -18.29689) (xy 177.142902 -18.29689)
		)
		(stroke
			(width 0)
			(type solid)
		)
		(fill yes)
		(layer "F.Cu")
		(net "GND")
	)
	(gr_poly
		(pts
			(xy 195.58 -18.161) (xy 195.58 -6.604) (xy 195.326 -6.35) (xy 191.897 -6.35) (xy 191.755522 -6.491478)
			(arc
				(start 191.755522 -6.62305)
				(mid 191.744411 -6.639584)
				(end 191.740536 -6.659118)
			)
			(arc
				(start 191.740536 -18.105882)
				(mid 191.744437 -18.125405)
				(end 191.755522 -18.14195)
			)
			(xy 191.866774 -18.253202) (xy 195.487798 -18.253202)
		)
		(stroke
			(width 0)
			(type solid)
		)
		(fill yes)
		(layer "F.Cu")
		(net "GND")
	)
	(gr_poly
		(pts
			(xy 259.846826 -51.294792) (xy 259.846826 -45.156374) (xy 259.91693 -45.08627) (xy 260.5024 -44.5008)
			(xy 260.731 -44.2722) (xy 260.731 -43.9674) (xy 260.7056 -43.942) (xy 260.0198 -43.942) (xy 259.9944 -43.9674)
			(xy 257.948938 -46.012862) (xy 257.948938 -47.336456) (xy 257.948938 -50.420016) (xy 257.948938 -50.528982)
			(xy 258.72186 -51.301904) (xy 259.839714 -51.301904)
		)
		(stroke
			(width 0)
			(type solid)
		)
		(fill yes)
		(layer "F.Cu")
		(net "P52V_HS")
	)
	(gr_poly
		(pts
			(xy 178.5366 -14.9352) (xy 178.5366 -14.859) (xy 178.5366 -14.0716) (xy 178.2318 -13.7668) (xy 178.2318 -13.1064)
			(xy 178.2064 -13.081) (xy 177.927 -13.081) (xy 177.9016 -13.1064) (xy 177.9016 -13.9446) (xy 177.9016 -14.097)
			(xy 177.9016 -14.2494) (xy 177.9778 -14.3256) (xy 177.9778 -14.859) (xy 177.9778 -14.9352) (xy 178.0286 -14.986)
			(xy 178.4858 -14.986)
		)
		(stroke
			(width 0)
			(type solid)
		)
		(fill yes)
		(layer "F.Cu")
		(net "P3V3_AUX_VCC")
	)
	(gr_poly
		(pts
			(xy 178.18989 -10.92073) (xy 178.18989 -9.87933) (xy 178.46929 -9.59993) (xy 178.46929 -9.11733)
			(xy 178.46929 -9.045448) (xy 177.993548 -8.569706) (xy 177.383694 -8.569706) (xy 177.0634 -8.89)
			(xy 176.94529 -9.00811) (xy 176.94529 -9.06653) (xy 176.94529 -9.49833) (xy 177.04689 -9.59993) (xy 177.73269 -9.59993)
			(xy 177.91049 -9.77773) (xy 177.91049 -10.92073) (xy 177.93589 -10.94613) (xy 178.16449 -10.94613)
		)
		(stroke
			(width 0)
			(type solid)
		)
		(fill yes)
		(layer "F.Cu")
		(net "GND")
	)
	(gr_poly
		(pts
			(xy 263.919208 -50.677826) (xy 264.082022 -50.515012) (xy 264.082022 -48.937672) (xy 263.20115 -48.0568)
			(xy 263.20115 -44.363386) (xy 263.180576 -44.342812) (xy 262.888476 -44.342812) (xy 262.864346 -44.366942)
			(xy 262.864346 -45.216572) (xy 262.510778 -45.57014) (xy 262.510778 -49.346358) (xy 262.504936 -49.3522)
			(xy 261.936738 -49.920398) (xy 260.631686 -49.920398) (xy 260.620764 -49.93132) (xy 260.620764 -51.293776)
			(xy 260.624574 -51.297586) (xy 263.299448 -51.297586)
		)
		(stroke
			(width 0)
			(type solid)
		)
		(fill yes)
		(layer "F.Cu")
		(net "P52V_HS1_FB")
	)
	(gr_poly
		(pts
			(xy 279.80259 -51.775614) (xy 279.80259 -50.3682) (xy 279.80259 -49.97577) (xy 279.80259 -48.483266)
			(xy 281.964892 -46.320964) (xy 282.931108 -46.320964) (xy 284.027118 -45.224954) (xy 284.027118 -44.947332)
			(xy 283.993336 -44.91355) (xy 283.034994 -44.91355) (xy 282.701746 -45.246798) (xy 279.066244 -45.246798)
			(xy 278.977598 -45.335444) (xy 278.977598 -48.112426) (xy 278.513032 -48.576992) (xy 278.513032 -51.854608)
			(xy 278.653494 -51.99507) (xy 279.583134 -51.99507)
		)
		(stroke
			(width 0)
			(type solid)
		)
		(fill yes)
		(layer "F.Cu")
		(net "P52V_HS1_ISET")
	)
	(gr_poly
		(pts
			(arc
				(start 46.851824 -131.953)
				(mid 46.871347 -131.949099)
				(end 46.887892 -131.938014)
			)
			(arc
				(start 46.98492 -131.840986)
				(mid 46.996031 -131.824452)
				(end 46.999906 -131.804918)
			)
			(arc
				(start 46.999906 -126.386082)
				(mid 46.996005 -126.366559)
				(end 46.98492 -126.350014)
			)
			(arc
				(start 46.887892 -126.252986)
				(mid 46.871358 -126.241875)
				(end 46.851824 -126.238)
			)
			(xy 45.734732 -126.238) (xy 45.607732 -126.365) (xy 45.607732 -131.826) (xy 45.734732 -131.953)
		)
		(stroke
			(width 0)
			(type solid)
		)
		(fill yes)
		(layer "F.Cu")
		(net "GND")
	)
	(gr_poly
		(pts
			(arc
				(start 59.043824 -131.953)
				(mid 59.063347 -131.949099)
				(end 59.079892 -131.938014)
			)
			(arc
				(start 59.17692 -131.840986)
				(mid 59.188031 -131.824452)
				(end 59.191906 -131.804918)
			)
			(arc
				(start 59.191906 -126.386082)
				(mid 59.188005 -126.366559)
				(end 59.17692 -126.350014)
			)
			(arc
				(start 59.079892 -126.252986)
				(mid 59.063358 -126.241875)
				(end 59.043824 -126.238)
			)
			(xy 57.926732 -126.238) (xy 57.799732 -126.365) (xy 57.799732 -131.826) (xy 57.926732 -131.953)
		)
		(stroke
			(width 0)
			(type solid)
		)
		(fill yes)
		(layer "F.Cu")
		(net "GND")
	)
	(gr_poly
		(pts
			(arc
				(start 71.235824 -131.953)
				(mid 71.255347 -131.949099)
				(end 71.271892 -131.938014)
			)
			(arc
				(start 71.36892 -131.840986)
				(mid 71.380031 -131.824452)
				(end 71.383906 -131.804918)
			)
			(arc
				(start 71.383906 -126.386082)
				(mid 71.380005 -126.366559)
				(end 71.36892 -126.350014)
			)
			(arc
				(start 71.271892 -126.252986)
				(mid 71.255358 -126.241875)
				(end 71.235824 -126.238)
			)
			(xy 70.118732 -126.238) (xy 69.991732 -126.365) (xy 69.991732 -131.826) (xy 70.118732 -131.953)
		)
		(stroke
			(width 0)
			(type solid)
		)
		(fill yes)
		(layer "F.Cu")
		(net "GND")
	)
	(gr_poly
		(pts
			(arc
				(start 86.851744 -131.953)
				(mid 86.871267 -131.949099)
				(end 86.887812 -131.938014)
			)
			(arc
				(start 86.98484 -131.840986)
				(mid 86.995951 -131.824452)
				(end 86.999826 -131.804918)
			)
			(arc
				(start 86.999826 -126.386082)
				(mid 86.995925 -126.366559)
				(end 86.98484 -126.350014)
			)
			(arc
				(start 86.887812 -126.252986)
				(mid 86.871278 -126.241875)
				(end 86.851744 -126.238)
			)
			(xy 85.734652 -126.238) (xy 85.607652 -126.365) (xy 85.607652 -131.826) (xy 85.734652 -131.953)
		)
		(stroke
			(width 0)
			(type solid)
		)
		(fill yes)
		(layer "F.Cu")
		(net "GND")
	)
	(gr_poly
		(pts
			(arc
				(start 99.043744 -131.953)
				(mid 99.063267 -131.949099)
				(end 99.079812 -131.938014)
			)
			(arc
				(start 99.17684 -131.840986)
				(mid 99.187951 -131.824452)
				(end 99.191826 -131.804918)
			)
			(arc
				(start 99.191826 -126.386082)
				(mid 99.187925 -126.366559)
				(end 99.17684 -126.350014)
			)
			(arc
				(start 99.079812 -126.252986)
				(mid 99.063278 -126.241875)
				(end 99.043744 -126.238)
			)
			(xy 97.926652 -126.238) (xy 97.799652 -126.365) (xy 97.799652 -131.826) (xy 97.926652 -131.953)
		)
		(stroke
			(width 0)
			(type solid)
		)
		(fill yes)
		(layer "F.Cu")
		(net "GND")
	)
	(gr_poly
		(pts
			(arc
				(start 111.235744 -131.953)
				(mid 111.255267 -131.949099)
				(end 111.271812 -131.938014)
			)
			(arc
				(start 111.36884 -131.840986)
				(mid 111.379951 -131.824452)
				(end 111.383826 -131.804918)
			)
			(arc
				(start 111.383826 -126.386082)
				(mid 111.379925 -126.366559)
				(end 111.36884 -126.350014)
			)
			(arc
				(start 111.271812 -126.252986)
				(mid 111.255278 -126.241875)
				(end 111.235744 -126.238)
			)
			(xy 110.118652 -126.238) (xy 109.991652 -126.365) (xy 109.991652 -131.826) (xy 110.118652 -131.953)
		)
		(stroke
			(width 0)
			(type solid)
		)
		(fill yes)
		(layer "F.Cu")
		(net "GND")
	)
	(gr_poly
		(pts
			(arc
				(start 126.851918 -131.953)
				(mid 126.871441 -131.949099)
				(end 126.887986 -131.938014)
			)
			(arc
				(start 126.985014 -131.840986)
				(mid 126.996125 -131.824452)
				(end 127 -131.804918)
			)
			(arc
				(start 127 -126.386082)
				(mid 126.996099 -126.366559)
				(end 126.985014 -126.350014)
			)
			(arc
				(start 126.887986 -126.252986)
				(mid 126.871452 -126.241875)
				(end 126.851918 -126.238)
			)
			(xy 125.734826 -126.238) (xy 125.607826 -126.365) (xy 125.607826 -131.826) (xy 125.734826 -131.953)
		)
		(stroke
			(width 0)
			(type solid)
		)
		(fill yes)
		(layer "F.Cu")
		(net "GND")
	)
	(gr_poly
		(pts
			(arc
				(start 139.043918 -131.953)
				(mid 139.063441 -131.949099)
				(end 139.079986 -131.938014)
			)
			(arc
				(start 139.177014 -131.840986)
				(mid 139.188125 -131.824452)
				(end 139.192 -131.804918)
			)
			(arc
				(start 139.192 -126.386082)
				(mid 139.188099 -126.366559)
				(end 139.177014 -126.350014)
			)
			(arc
				(start 139.079986 -126.252986)
				(mid 139.063452 -126.241875)
				(end 139.043918 -126.238)
			)
			(xy 137.926826 -126.238) (xy 137.799826 -126.365) (xy 137.799826 -131.826) (xy 137.926826 -131.953)
		)
		(stroke
			(width 0)
			(type solid)
		)
		(fill yes)
		(layer "F.Cu")
		(net "GND")
	)
	(gr_poly
		(pts
			(arc
				(start 151.235918 -131.953)
				(mid 151.255441 -131.949099)
				(end 151.271986 -131.938014)
			)
			(arc
				(start 151.369014 -131.840986)
				(mid 151.380125 -131.824452)
				(end 151.384 -131.804918)
			)
			(arc
				(start 151.384 -126.386082)
				(mid 151.380099 -126.366559)
				(end 151.369014 -126.350014)
			)
			(arc
				(start 151.271986 -126.252986)
				(mid 151.255452 -126.241875)
				(end 151.235918 -126.238)
			)
			(xy 150.118826 -126.238) (xy 149.991826 -126.365) (xy 149.991826 -131.826) (xy 150.118826 -131.953)
		)
		(stroke
			(width 0)
			(type solid)
		)
		(fill yes)
		(layer "F.Cu")
		(net "GND")
	)
	(gr_poly
		(pts
			(arc
				(start 166.852092 -131.953)
				(mid 166.871615 -131.949099)
				(end 166.88816 -131.938014)
			)
			(arc
				(start 166.985188 -131.840986)
				(mid 166.996299 -131.824452)
				(end 167.000174 -131.804918)
			)
			(arc
				(start 167.000174 -126.386082)
				(mid 166.996273 -126.366559)
				(end 166.985188 -126.350014)
			)
			(arc
				(start 166.88816 -126.252986)
				(mid 166.871626 -126.241875)
				(end 166.852092 -126.238)
			)
			(xy 165.735 -126.238) (xy 165.608 -126.365) (xy 165.608 -131.826) (xy 165.735 -131.953)
		)
		(stroke
			(width 0)
			(type solid)
		)
		(fill yes)
		(layer "F.Cu")
		(net "GND")
	)
	(gr_poly
		(pts
			(arc
				(start 179.044092 -131.953)
				(mid 179.063615 -131.949099)
				(end 179.08016 -131.938014)
			)
			(arc
				(start 179.177188 -131.840986)
				(mid 179.188299 -131.824452)
				(end 179.192174 -131.804918)
			)
			(arc
				(start 179.192174 -126.386082)
				(mid 179.188273 -126.366559)
				(end 179.177188 -126.350014)
			)
			(arc
				(start 179.08016 -126.252986)
				(mid 179.063626 -126.241875)
				(end 179.044092 -126.238)
			)
			(xy 177.927 -126.238) (xy 177.8 -126.365) (xy 177.8 -131.826) (xy 177.927 -131.953)
		)
		(stroke
			(width 0)
			(type solid)
		)
		(fill yes)
		(layer "F.Cu")
		(net "GND")
	)
	(gr_poly
		(pts
			(arc
				(start 191.236092 -131.953)
				(mid 191.255615 -131.949099)
				(end 191.27216 -131.938014)
			)
			(arc
				(start 191.369188 -131.840986)
				(mid 191.380299 -131.824452)
				(end 191.384174 -131.804918)
			)
			(arc
				(start 191.384174 -126.386082)
				(mid 191.380273 -126.366559)
				(end 191.369188 -126.350014)
			)
			(arc
				(start 191.27216 -126.252986)
				(mid 191.255626 -126.241875)
				(end 191.236092 -126.238)
			)
			(xy 190.119 -126.238) (xy 189.992 -126.365) (xy 189.992 -131.826) (xy 190.119 -131.953)
		)
		(stroke
			(width 0)
			(type solid)
		)
		(fill yes)
		(layer "F.Cu")
		(net "GND")
	)
	(gr_poly
		(pts
			(xy 176.403 -12.1666) (xy 177.8 -12.1666) (xy 177.8254 -12.1412) (xy 177.8254 -11.8872) (xy 177.8 -11.8618)
			(xy 176.5046 -11.8618) (xy 176.1998 -11.8618) (xy 175.4378 -11.0998) (xy 174.8917 -10.5537) (xy 174.879 -10.5537)
			(xy 174.6123 -10.287) (xy 172.085 -10.287) (xy 171.5516 -9.7536) (xy 165.6334 -9.7536) (xy 164.8333 -10.5537)
			(xy 164.0967 -10.5537) (xy 163.9316 -10.7188) (xy 163.9316 -12.1412) (xy 164.1094 -12.319) (xy 164.1602 -12.3698)
			(xy 170.053 -12.3698) (xy 176.1998 -12.3698)
		)
		(stroke
			(width 0)
			(type solid)
		)
		(fill yes)
		(layer "F.Cu")
		(net "SW_P12V_FILT__P3V3_AUX")
	)
	(gr_poly
		(pts
			(xy 183.515 -15.494) (xy 183.515 -14.605) (xy 183.515 -11.303) (xy 183.388 -11.176) (xy 182.626 -11.176)
			(xy 181.3306 -11.176) (xy 181.135528 -11.371072) (xy 181.135528 -11.904472) (xy 180.721 -12.319)
			(xy 179.578 -12.319) (xy 179.5272 -12.3698) (xy 176.5046 -12.3698) (xy 176.4792 -12.3952) (xy 176.4792 -12.6492)
			(xy 176.5046 -12.6746) (xy 179.2351 -12.6746) (xy 179.7431 -13.1826) (xy 179.7431 -14.5161) (xy 179.959 -14.732)
			(xy 180.213 -14.986) (xy 180.213 -15.6718) (xy 180.5178 -15.9766) (xy 183.0324 -15.9766)
		)
		(stroke
			(width 0)
			(type solid)
		)
		(fill yes)
		(layer "F.Cu")
		(net "SW_P3V3_AUX_PH")
	)
	(gr_poly
		(pts
			(xy 294.1828 -49.784) (xy 294.1828 -48.502062) (xy 294.109648 -48.42891) (xy 290.34359 -48.42891)
			(xy 289.890708 -47.976028) (xy 288.959036 -47.044356) (xy 288.959036 -44.952158) (xy 289.855148 -44.056046)
			(xy 289.855148 -40.406066) (xy 290.97224 -39.288974) (xy 290.97224 -38.550342) (xy 290.89223 -38.470332)
			(xy 288.672524 -38.470332) (xy 288.568892 -38.573964) (xy 288.568892 -40.34917) (xy 288.326322 -40.59174)
			(xy 288.326322 -44.648628) (xy 288.617152 -44.939458) (xy 288.617152 -47.875952) (xy 288.8996 -48.1584)
			(xy 288.8996 -49.78781) (xy 288.9758 -49.86401) (xy 294.10279 -49.86401)
		)
		(stroke
			(width 0)
			(type solid)
		)
		(fill yes)
		(layer "F.Cu")
		(net "P52V_HS1_VCC")
	)
	(gr_poly
		(pts
			(xy 298.9072 -95.3262) (xy 298.9072 -89.4842) (xy 297.561 -88.138) (xy 296.36974 -88.138) (xy 295.58234 -87.3506)
			(xy 295.58234 -84.1502) (xy 295.402 -83.96986) (xy 295.402 -83.0834) (xy 295.8084 -82.677) (xy 298.831 -82.677)
			(xy 298.958 -82.55) (xy 298.958 -78.88986) (xy 298.63034 -78.5622) (xy 298.63034 -77.8764) (xy 298.958 -77.54874)
			(xy 298.958 -61.722) (xy 298.069 -60.833) (xy 279.518618 -60.833) (xy 279.189688 -61.16193) (xy 279.189688 -95.494348)
			(xy 279.389332 -95.693992) (xy 295.270428 -95.693992) (xy 298.539408 -95.693992)
		)
		(stroke
			(width 0)
			(type solid)
		)
		(fill yes)
		(layer "F.Cu")
		(net "P52V_HS1_DRAIN_2")
	)
	(gr_poly
		(pts
			(xy 295.63568 -131.60756)
			(arc
				(start 295.63568 -120.05691)
				(mid 295.475402 -119.6975)
				(end 295.63568 -119.33809)
			)
			(xy 295.63568 -118.57228) (xy 296.13606 -118.0719) (xy 298.7675 -118.0719) (xy 298.958 -117.8814)
			(xy 298.958 -115.025678) (xy 298.670472 -114.73815) (xy 298.670472 -114.082068) (xy 298.958 -113.79454)
			(xy 298.958 -97.409) (xy 298.576746 -97.027746) (xy 279.402794 -97.027746) (xy 279.21331 -97.21723)
			(xy 279.21331 -131.566412) (xy 279.726898 -132.08) (xy 295.16324 -132.08)
		)
		(stroke
			(width 0)
			(type solid)
		)
		(fill yes)
		(layer "F.Cu")
		(net "P52V_HS1_DRAIN_1")
	)
	(gr_poly
		(pts
			(arc
				(start 40.477186 -61.652912)
				(mid 40.496543 -61.649079)
				(end 40.513 -61.63818)
			)
			(arc
				(start 40.609774 -61.541406)
				(mid 40.620885 -61.524872)
				(end 40.62476 -61.505338)
			)
			(arc
				(start 40.62476 -60.912502)
				(mid 40.620859 -60.892979)
				(end 40.609774 -60.876434)
			)
			(arc
				(start 40.487346 -60.754006)
				(mid 40.470812 -60.742895)
				(end 40.451278 -60.73902)
			)
			(arc
				(start 38.283642 -60.73902)
				(mid 38.264119 -60.742921)
				(end 38.247574 -60.754006)
			)
			(arc
				(start 38.150546 -60.851034)
				(mid 38.139435 -60.867568)
				(end 38.13556 -60.887102)
			)
			(arc
				(start 38.13556 -61.581538)
				(mid 38.139461 -61.601061)
				(end 38.150546 -61.617606)
			)
			(arc
				(start 38.17112 -61.63818)
				(mid 38.187566 -61.649106)
				(end 38.206934 -61.652912)
			)
		)
		(stroke
			(width 0)
			(type solid)
		)
		(fill yes)
		(layer "F.Cu")
		(net "GND")
	)
	(gr_poly
		(pts
			(arc
				(start 238.124238 -39.3065)
				(mid 238.143761 -39.302599)
				(end 238.160306 -39.291514)
			)
			(arc
				(start 238.605314 -38.846506)
				(mid 238.616425 -38.829972)
				(end 238.6203 -38.810438)
			)
			(arc
				(start 238.6203 -29.434282)
				(mid 238.616399 -29.414759)
				(end 238.605314 -29.398214)
			)
			(arc
				(start 238.101886 -28.894786)
				(mid 238.085352 -28.883675)
				(end 238.065818 -28.8798)
			)
			(arc
				(start 215.918542 -28.8798)
				(mid 215.899019 -28.883701)
				(end 215.882474 -28.894786)
			)
			(arc
				(start 215.467946 -29.309314)
				(mid 215.456835 -29.325848)
				(end 215.45296 -29.345382)
			)
			(arc
				(start 215.45296 -38.767258)
				(mid 215.456861 -38.786781)
				(end 215.467946 -38.803326)
			)
			(arc
				(start 215.956134 -39.291514)
				(mid 215.972668 -39.302625)
				(end 215.992202 -39.3065)
			)
		)
		(stroke
			(width 0)
			(type solid)
		)
		(fill yes)
		(layer "F.Cu")
		(net "GND")
	)
	(gr_poly
		(pts
			(arc
				(start 39.058596 -60.21578)
				(mid 39.078119 -60.211879)
				(end 39.094664 -60.200794)
			)
			(arc
				(start 39.521892 -59.773566)
				(mid 39.538426 -59.762455)
				(end 39.55796 -59.75858)
			)
			(arc
				(start 40.590978 -59.75858)
				(mid 40.610501 -59.754679)
				(end 40.627046 -59.743594)
			)
			(arc
				(start 40.673274 -59.697366)
				(mid 40.684385 -59.680832)
				(end 40.68826 -59.661298)
			)
			(arc
				(start 40.68826 -59.37758)
				(mid 40.673381 -59.341659)
				(end 40.63746 -59.32678)
			)
			(xy 39.45382 -59.32678) (xy 39.389812 -59.390788) (xy 35.837368 -59.390788) (xy 35.73526 -59.492896)
			(arc
				(start 35.73526 -60.042298)
				(mid 35.739161 -60.061821)
				(end 35.750246 -60.078366)
			)
			(arc
				(start 35.872674 -60.200794)
				(mid 35.889208 -60.211905)
				(end 35.908742 -60.21578)
			)
		)
		(stroke
			(width 0)
			(type solid)
		)
		(fill yes)
		(layer "F.Cu")
		(net "P12V_HPDB_0_PD")
	)
	(gr_poly
		(pts
			(xy 281.101038 -44.196) (xy 282.009088 -44.196) (xy 282.072842 -44.259754) (xy 283.983684 -44.259754)
			(xy 284.020768 -44.22267) (xy 284.020768 -43.985942) (xy 283.968952 -43.934126)
			(arc
				(start 282.983178 -43.934126)
				(mid 282.892347 -43.969947)
				(end 282.795472 -43.982132)
			)
			(arc
				(start 282.795472 -43.982132)
				(mid 282.698599 -43.969939)
				(end 282.607766 -43.934126)
			)
			(xy 282.592526 -43.934126)
			(arc
				(start 282.566364 -43.907964)
				(mid 282.519054 -43.867644)
				(end 282.478734 -43.820334)
			)
			(xy 282.3464 -43.688) (xy 281.9146 -43.688) (xy 281.6352 -43.4086) (xy 281.6352 -42.926) (xy 281.080718 -42.371518)
			(xy 279.378156 -42.371518) (xy 279.333706 -42.415968) (xy 279.333706 -43.171364) (xy 279.992582 -43.83024)
			(xy 279.992582 -44.27093) (xy 280.06294 -44.341288) (xy 280.95575 -44.341288)
		)
		(stroke
			(width 0)
			(type solid)
		)
		(fill yes)
		(layer "F.Cu")
		(net "P52V_HS1_VCAP")
	)
	(gr_poly
		(pts
			(arc
				(start 40.552878 -62.61862)
				(mid 40.572401 -62.614719)
				(end 40.588946 -62.603634)
			)
			(arc
				(start 40.609774 -62.582806)
				(mid 40.620885 -62.566272)
				(end 40.62476 -62.546738)
			)
			(arc
				(start 40.62476 -61.953902)
				(mid 40.620859 -61.934379)
				(end 40.609774 -61.917834)
			)
			(xy 40.60698 -61.91504) (xy 40.588438 -61.90742)
			(arc
				(start 37.928042 -61.90742)
				(mid 37.908519 -61.903519)
				(end 37.891974 -61.892434)
			)
			(arc
				(start 37.718746 -61.719206)
				(mid 37.707635 -61.702672)
				(end 37.70376 -61.683138)
			)
			(arc
				(start 37.70376 -60.861702)
				(mid 37.699859 -60.842179)
				(end 37.688774 -60.825634)
			)
			(arc
				(start 37.642546 -60.779406)
				(mid 37.626012 -60.768295)
				(end 37.606478 -60.76442)
			)
			(arc
				(start 36.886642 -60.76442)
				(mid 36.867119 -60.768321)
				(end 36.850574 -60.779406)
			)
			(arc
				(start 36.753546 -60.876434)
				(mid 36.742435 -60.892968)
				(end 36.73856 -60.912502)
			)
			(arc
				(start 36.73856 -62.114938)
				(mid 36.742461 -62.134461)
				(end 36.753546 -62.151006)
			)
			(arc
				(start 37.206174 -62.603634)
				(mid 37.222708 -62.614745)
				(end 37.242242 -62.61862)
			)
		)
		(stroke
			(width 0)
			(type solid)
		)
		(fill yes)
		(layer "F.Cu")
		(net "P12V_BRICK")
	)
	(gr_poly
		(pts
			(xy 51.275742 -72.394572)
			(arc
				(start 51.275742 -70.886066)
				(mid 51.286853 -70.869532)
				(end 51.290728 -70.849998)
			)
			(arc
				(start 51.290728 -69.339714)
				(mid 51.286827 -69.320191)
				(end 51.275742 -69.303646)
			)
			(arc
				(start 50.678334 -68.706238)
				(mid 50.6618 -68.695127)
				(end 50.642266 -68.691252)
			)
			(arc
				(start 50.373788 -68.691252)
				(mid 50.354265 -68.687351)
				(end 50.33772 -68.676266)
			)
			(arc
				(start 49.765712 -68.104258)
				(mid 49.739799 -68.090471)
				(end 49.710594 -68.093336)
			)
			(xy 49.696116 -68.099178) (xy 49.679098 -68.124832)
			(arc
				(start 49.679098 -68.780914)
				(mid 49.965905 -68.888872)
				(end 50.2285 -69.046852)
			)
			(arc
				(start 50.228754 -69.046852)
				(mid 50.493105 -69.287425)
				(end 50.70094 -69.57822)
			)
			(xy 50.704242 -69.584062) (xy 50.704242 -69.584316)
			(arc
				(start 50.72761 -69.607684)
				(mid 50.738721 -69.624218)
				(end 50.742596 -69.643752)
			)
			(xy 50.742596 -69.656706)
			(arc
				(start 50.74793 -69.66712)
				(mid 50.876337 -70.028645)
				(end 50.919888 -70.409816)
			)
			(arc
				(start 50.919634 -70.410324)
				(mid 50.907488 -70.612046)
				(end 50.871374 -70.810882)
			)
			(arc
				(start 50.871374 -70.810882)
				(mid 50.760778 -71.12513)
				(end 50.590704 -71.411592)
			)
			(xy 50.590704 -72.548496) (xy 50.726086 -72.683878) (xy 50.986436 -72.683878)
		)
		(stroke
			(width 0)
			(type solid)
		)
		(fill yes)
		(layer "F.Cu")
		(net "GND")
	)
	(gr_poly
		(pts
			(xy 274.909026 -143.51) (xy 274.909026 -132.933694) (xy 274.828 -132.852668) (xy 269.987268 -132.852668)
			(xy 267.4366 -130.302) (xy 267.4366 -127.56134) (xy 268.63294 -126.365) (xy 274.701 -126.365) (xy 274.93468 -126.13132)
			(xy 274.93468 -120.894348) (xy 274.828 -120.787668) (xy 268.63294 -120.787668) (xy 267.4366 -119.591328)
			(xy 267.4366 -115.49634) (xy 268.63294 -114.3) (xy 274.701 -114.3) (xy 275.04263 -113.95837) (xy 275.04263 -108.937298)
			(xy 274.828 -108.722668) (xy 268.63294 -108.722668) (xy 267.4366 -107.526328) (xy 267.4366 -103.43134)
			(xy 268.63294 -102.235) (xy 274.701 -102.235) (xy 275.00199 -101.93401) (xy 275.00199 -96.831658)
			(xy 274.828 -96.657668) (xy 268.63294 -96.657668) (xy 267.4366 -95.461328) (xy 267.4366 -91.36634)
			(xy 268.63294 -90.17) (xy 274.701 -90.17) (xy 275.015706 -89.855294) (xy 275.015706 -84.780374) (xy 274.828 -84.592668)
			(xy 268.63294 -84.592668) (xy 267.4366 -83.396328) (xy 267.4366 -79.30134) (xy 268.63294 -78.105)
			(xy 274.701 -78.105) (xy 275.029168 -77.776832) (xy 275.029168 -72.728836) (xy 274.828 -72.527668)
			(xy 268.63294 -72.527668) (xy 267.4366 -71.331328) (xy 267.4366 -67.23634) (xy 268.63294 -66.04)
			(xy 274.701 -66.04) (xy 275.00199 -65.73901) (xy 275.00199 -61.341) (xy 258.760214 -61.341) (xy 254.569214 -65.532)
			(xy 245.5672 -65.532) (xy 244.348 -66.7512) (xy 244.348 -95.377) (xy 243.3828 -96.3422) (xy 198.3232 -96.3422)
			(xy 197.229476 -97.435924) (xy 197.229476 -114.428524) (xy 197.993 -115.192048) (xy 223.573848 -115.192048)
			(xy 224.282 -115.9002) (xy 224.282 -134.366) (xy 224.917 -135.001) (xy 231.775 -135.001) (xy 236.601 -130.175)
			(xy 265.049 -130.175) (xy 269.367 -134.493) (xy 269.367 -143.195548) (xy 270.002 -143.830548) (xy 274.588478 -143.830548)
		)
		(stroke
			(width 0)
			(type solid)
		)
		(fill yes)
		(layer "F.Cu")
		(net "P52V_HS")
	)
	(gr_poly
		(pts
			(arc
				(start 62.787276 -70.562724)
				(mid 62.782152 -70.487236)
				(end 62.780418 -70.411594)
			)
			(arc
				(start 62.780418 -70.409816)
				(mid 63.275293 -69.215083)
				(end 64.470026 -68.720208)
			)
			(arc
				(start 64.470026 -68.720208)
				(mid 65.114688 -68.848047)
				(end 65.661794 -69.212206)
			)
			(xy 66.802 -68.072) (xy 66.802 -66.548) (xy 66.294 -66.04) (xy 64.2874 -66.04) (xy 64.0588 -66.2686)
			(xy 64.0588 -67.703446)
			(arc
				(start 63.89243 -67.869816)
				(mid 63.587113 -68.606915)
				(end 62.850014 -68.912232)
			)
			(arc
				(start 62.850014 -68.912232)
				(mid 62.795712 -68.910856)
				(end 62.741556 -68.906644)
			)
			(xy 62.475872 -69.172328) (xy 62.475872 -70.857872) (xy 62.484 -70.866)
		)
		(stroke
			(width 0)
			(type solid)
		)
		(fill yes)
		(layer "F.Cu")
		(net "P12V_BRICK")
	)
	(gr_poly
		(pts
			(arc
				(start 102.787196 -70.562724)
				(mid 102.782072 -70.487236)
				(end 102.780338 -70.411594)
			)
			(arc
				(start 102.780338 -70.409816)
				(mid 103.275213 -69.215083)
				(end 104.469946 -68.720208)
			)
			(arc
				(start 104.469946 -68.720208)
				(mid 105.114608 -68.848047)
				(end 105.661714 -69.212206)
			)
			(xy 106.80192 -68.072) (xy 106.80192 -66.548) (xy 106.29392 -66.04) (xy 104.28732 -66.04) (xy 104.05872 -66.2686)
			(xy 104.05872 -67.703446)
			(arc
				(start 103.89235 -67.869816)
				(mid 103.587033 -68.606915)
				(end 102.849934 -68.912232)
			)
			(arc
				(start 102.849934 -68.912232)
				(mid 102.795632 -68.910856)
				(end 102.741476 -68.906644)
			)
			(xy 102.29596 -69.35216) (xy 101.86924 -69.35216) (xy 101.727 -69.4944) (xy 101.727 -70.8406) (xy 101.7524 -70.866)
			(xy 102.48392 -70.866)
		)
		(stroke
			(width 0)
			(type solid)
		)
		(fill yes)
		(layer "F.Cu")
		(net "P12V_BRICK")
	)
	(gr_poly
		(pts
			(arc
				(start 142.78737 -70.562724)
				(mid 142.782246 -70.487236)
				(end 142.780512 -70.411594)
			)
			(arc
				(start 142.780512 -70.409816)
				(mid 143.275387 -69.215083)
				(end 144.47012 -68.720208)
			)
			(arc
				(start 144.47012 -68.720208)
				(mid 145.114782 -68.848047)
				(end 145.661888 -69.212206)
			)
			(xy 146.802094 -68.072) (xy 146.802094 -66.548) (xy 146.294094 -66.04) (xy 144.287494 -66.04) (xy 144.058894 -66.2686)
			(xy 144.058894 -67.703446)
			(arc
				(start 143.892524 -67.869816)
				(mid 143.587207 -68.606915)
				(end 142.850108 -68.912232)
			)
			(arc
				(start 142.848838 -68.912232)
				(mid 142.795172 -68.910823)
				(end 142.74165 -68.906644)
			)
			(xy 142.296134 -69.35216) (xy 141.869414 -69.35216) (xy 141.727174 -69.4944) (xy 141.727174 -70.8406)
			(xy 141.752574 -70.866) (xy 142.484094 -70.866)
		)
		(stroke
			(width 0)
			(type solid)
		)
		(fill yes)
		(layer "F.Cu")
		(net "P12V_BRICK")
	)
	(gr_poly
		(pts
			(arc
				(start 182.787544 -70.562724)
				(mid 182.78242 -70.487236)
				(end 182.780686 -70.411594)
			)
			(arc
				(start 182.780686 -70.409816)
				(mid 183.275561 -69.215083)
				(end 184.470294 -68.720208)
			)
			(arc
				(start 184.470294 -68.720208)
				(mid 185.114956 -68.848047)
				(end 185.662062 -69.212206)
			)
			(xy 186.802268 -68.072) (xy 186.802268 -66.548) (xy 186.294268 -66.04) (xy 184.287668 -66.04) (xy 184.059068 -66.2686)
			(xy 184.059068 -67.703446)
			(arc
				(start 183.892698 -67.869816)
				(mid 183.587381 -68.606915)
				(end 182.850282 -68.912232)
			)
			(arc
				(start 182.849012 -68.912232)
				(mid 182.795346 -68.910823)
				(end 182.741824 -68.906644)
			)
			(xy 182.296308 -69.35216) (xy 181.869588 -69.35216) (xy 181.727348 -69.4944) (xy 181.727348 -70.8406)
			(xy 181.752748 -70.866) (xy 182.484268 -70.866)
		)
		(stroke
			(width 0)
			(type solid)
		)
		(fill yes)
		(layer "F.Cu")
		(net "P12V_BRICK")
	)
	(gr_poly
		(pts
			(arc
				(start 35.8902 -146.49196)
				(mid 35.926121 -146.477081)
				(end 35.941 -146.44116)
			)
			(arc
				(start 35.941 -146.035268)
				(mid 35.926121 -145.999347)
				(end 35.8902 -145.984468)
			)
			(arc
				(start 4.99999 -145.984468)
				(mid 2.182524 -144.817436)
				(end 1.015492 -141.99997)
			)
			(arc
				(start 1.015492 -131.729988)
				(mid 1.596724 -130.326643)
				(end 2.999994 -129.745232)
			)
			(arc
				(start 9.600184 -129.745232)
				(mid 10.411927 -129.509478)
				(end 10.971022 -128.875536)
			)
			(arc
				(start 10.971022 -128.875536)
				(mid 10.975739 -128.850764)
				(end 10.967974 -128.826768)
			)
			(arc
				(start 10.922 -128.754124)
				(mid 10.903525 -128.73697)
				(end 10.879074 -128.730756)
			)
			(arc
				(start 10.503916 -128.730756)
				(mid 10.479029 -128.737127)
				(end 10.460482 -128.754886)
			)
			(arc
				(start 10.460482 -128.754886)
				(mid 10.093498 -129.108938)
				(end 9.600184 -129.237994)
			)
			(arc
				(start 2.999994 -129.237994)
				(mid 1.237888 -129.967882)
				(end 0.508 -131.729988)
			)
			(arc
				(start 0.508 -141.99997)
				(mid 1.823673 -145.176287)
				(end 4.99999 -146.49196)
			)
		)
		(stroke
			(width 0)
			(type solid)
		)
		(fill yes)
		(layer "F.Cu")
		(net "GND")
	)
	(gr_poly
		(pts
			(xy 320.421 -120.6754) (xy 320.421 -77.089) (xy 319.659 -76.327) (xy 308.442614 -76.327) (xy 305.943 -73.827386)
			(xy 305.943 -55.88) (xy 301.786036 -51.723036) (xy 292.599364 -51.723036) (xy 292.5572 -51.7652)
			(xy 292.5572 -54.3052) (xy 292.6842 -54.4322) (xy 296.561256 -54.4322) (xy 300.269656 -58.1406) (xy 300.269656 -77.509624)
			(xy 300.632368 -77.872336) (xy 300.632368 -78.558136) (xy 300.271434 -78.91907) (xy 300.271434 -82.517234)
			(xy 300.4312 -82.677) (xy 303.4538 -82.677) (xy 303.68748 -82.91068) (xy 303.68748 -87.32012) (xy 302.8696 -88.138)
			(xy 301.625 -88.138) (xy 300.271434 -89.491566) (xy 300.271434 -101.454966) (xy 306.278033 -101.454966)
			(xy 306.28204 -101.252216) (xy 306.294053 -101.049782) (xy 306.314054 -100.847981) (xy 306.342013 -100.647127)
			(xy 306.377884 -100.447535) (xy 306.421613 -100.249516) (xy 306.473131 -100.053379) (xy 306.532357 -99.859431)
			(xy 306.599199 -99.667973) (xy 306.673553 -99.479306) (xy 306.755302 -99.293724) (xy 306.84432 -99.111516)
			(xy 306.940466 -98.932967) (xy 307.043591 -98.758356) (xy 307.153534 -98.587956) (xy 307.270123 -98.422032)
			(xy 307.393176 -98.260843) (xy 307.522501 -98.104642) (xy 307.657896 -97.953672) (xy 307.799149 -97.808168)
			(xy 307.946041 -97.668359) (xy 308.098341 -97.534462) (xy 308.255812 -97.406687) (xy 308.418209 -97.285232)
			(xy 308.585276 -97.170288) (xy 308.756755 -97.062034) (xy 308.932376 -96.960639) (xy 309.111866 -96.866261)
			(xy 309.294944 -96.779049) (xy 309.481325 -96.699137) (xy 309.670718 -96.62665) (xy 309.862826 -96.561703)
			(xy 310.05735 -96.504395) (xy 310.253986 -96.454818) (xy 310.452428 -96.413047) (xy 310.652365 -96.379149)
			(xy 310.853484 -96.353177) (xy 311.055473 -96.33517) (xy 311.258016 -96.325157) (xy 311.460796 -96.323153)
			(xy 311.663497 -96.329163) (xy 311.865802 -96.343175) (xy 312.067396 -96.36517) (xy 312.267963 -96.395111)
			(xy 312.467191 -96.432952) (xy 312.664769 -96.478635) (xy 312.860387 -96.532088) (xy 313.053741 -96.593227)
			(xy 313.244529 -96.661958) (xy 313.432452 -96.738172) (xy 313.617218 -96.821751) (xy 313.798537 -96.912564)
			(xy 313.976128 -97.010469) (xy 314.149711 -97.115314) (xy 314.319017 -97.226935) (xy 314.483782 -97.345157)
			(xy 314.643747 -97.469797) (xy 314.798663 -97.600658) (xy 314.948288 -97.737538) (xy 315.092388 -97.880222)
			(xy 315.23074 -98.028488) (xy 315.363125 -98.182104) (xy 315.489339 -98.340829) (xy 315.609183 -98.504418)
			(xy 315.722471 -98.672613) (xy 315.829026 -98.845152) (xy 315.928681 -99.021767) (xy 316.021281 -99.20218)
			(xy 316.106681 -99.386111) (xy 316.184748 -99.573272) (xy 316.25536 -99.763372) (xy 316.318406 -99.956112)
			(xy 316.373789 -100.151193) (xy 316.421421 -100.34831) (xy 316.461229 -100.547154) (xy 316.493151 -100.747416)
			(xy 316.517135 -100.948782) (xy 316.533146 -101.150939) (xy 316.541157 -101.353571) (xy 316.541658 -101.454966)
			(xy 316.541157 -101.556361) (xy 316.533146 -101.758993) (xy 316.517135 -101.96115) (xy 316.493151 -102.162516)
			(xy 316.461229 -102.362778) (xy 316.421421 -102.561622) (xy 316.373789 -102.758739) (xy 316.318406 -102.95382)
			(xy 316.25536 -103.14656) (xy 316.184748 -103.33666) (xy 316.106681 -103.523821) (xy 316.021281 -103.707752)
			(xy 315.928681 -103.888165) (xy 315.829026 -104.06478) (xy 315.722471 -104.237319) (xy 315.609183 -104.405514)
			(xy 315.489339 -104.569103) (xy 315.363125 -104.727828) (xy 315.23074 -104.881444) (xy 315.092388 -105.02971)
			(xy 314.948288 -105.172394) (xy 314.798663 -105.309274) (xy 314.643747 -105.440135) (xy 314.483782 -105.564775)
			(xy 314.319017 -105.682997) (xy 314.149711 -105.794618) (xy 313.976128 -105.899463) (xy 313.798537 -105.997368)
			(xy 313.617218 -106.088181) (xy 313.432452 -106.17176) (xy 313.244529 -106.247974) (xy 313.053741 -106.316705)
			(xy 312.860387 -106.377844) (xy 312.664769 -106.431297) (xy 312.467191 -106.47698) (xy 312.267963 -106.514821)
			(xy 312.067396 -106.544762) (xy 311.865802 -106.566757) (xy 311.663497 -106.580769) (xy 311.460796 -106.586779)
			(xy 311.258016 -106.584775) (xy 311.055473 -106.574762) (xy 310.853484 -106.556755) (xy 310.652365 -106.530783)
			(xy 310.452428 -106.496885) (xy 310.253986 -106.455114) (xy 310.05735 -106.405537) (xy 309.862826 -106.348229)
			(xy 309.670718 -106.283282) (xy 309.481325 -106.210795) (xy 309.294944 -106.130883) (xy 309.111866 -106.043671)
			(xy 308.932376 -105.949293) (xy 308.756755 -105.847898) (xy 308.585276 -105.739644) (xy 308.418209 -105.6247)
			(xy 308.255812 -105.503245) (xy 308.098341 -105.37547) (xy 307.946041 -105.241573) (xy 307.799149 -105.101764)
			(xy 307.657896 -104.95626) (xy 307.522501 -104.80529) (xy 307.393176 -104.649089) (xy 307.270123 -104.4879)
			(xy 307.153534 -104.321976) (xy 307.043591 -104.151576) (xy 306.940466 -103.976965) (xy 306.84432 -103.798416)
			(xy 306.755302 -103.616208) (xy 306.673553 -103.430626) (xy 306.599199 -103.241959) (xy 306.532357 -103.050501)
			(xy 306.473131 -102.856553) (xy 306.421613 -102.660416) (xy 306.377884 -102.462397) (xy 306.342013 -102.262805)
			(xy 306.314054 -102.061951) (xy 306.294053 -101.86015) (xy 306.28204 -101.657716) (xy 306.278033 -101.454966)
			(xy 300.271434 -101.454966) (xy 300.271434 -113.73866) (xy 300.660562 -114.127788) (xy 300.660562 -114.676428)
			(xy 300.271434 -115.065556) (xy 300.271434 -117.8433) (xy 300.500034 -118.0719) (xy 303.3522 -118.0719)
			(xy 303.8094 -118.5291) (xy 303.8094 -120.9294) (xy 304.5714 -121.6914) (xy 319.405 -121.6914)
		)
		(stroke
			(width 0)
			(type solid)
		)
		(fill yes)
		(layer "F.Cu")
		(net "P52V_1")
	)
	(gr_poly
		(pts
			(arc
				(start 10.879328 -116.229384)
				(mid 10.903825 -116.223087)
				(end 10.922254 -116.205762)
			)
			(arc
				(start 10.967974 -116.133118)
				(mid 10.975912 -116.109154)
				(end 10.971276 -116.08435)
			)
			(arc
				(start 10.971276 -116.08435)
				(mid 10.411929 -115.450247)
				(end 9.59993 -115.2144)
			)
			(arc
				(start 2.999994 -115.2144)
				(mid 1.596739 -114.633153)
				(end 1.015492 -113.229898)
			)
			(arc
				(start 1.015492 -34.569908)
				(mid 1.596724 -33.166563)
				(end 2.999994 -32.585152)
			)
			(arc
				(start 9.600184 -32.585152)
				(mid 10.411884 -32.349217)
				(end 10.971022 -31.715202)
			)
			(arc
				(start 10.971022 -31.715202)
				(mid 10.975855 -31.690284)
				(end 10.967974 -31.66618)
			)
			(arc
				(start 10.922 -31.59379)
				(mid 10.903574 -31.576459)
				(end 10.879074 -31.570168)
			)
			(arc
				(start 10.50417 -31.570168)
				(mid 10.479274 -31.576687)
				(end 10.460736 -31.594552)
			)
			(arc
				(start 10.460736 -31.594552)
				(mid 10.093692 -31.948846)
				(end 9.600184 -32.077914)
			)
			(arc
				(start 2.999994 -32.077914)
				(mid 1.237888 -32.807802)
				(end 0.508 -34.569908)
			)
			(arc
				(start 0.508 -113.229898)
				(mid 1.237888 -114.992004)
				(end 2.999994 -115.721892)
			)
			(arc
				(start 9.59993 -115.721892)
				(mid 10.093358 -115.850938)
				(end 10.460482 -116.205)
			)
			(arc
				(start 10.460482 -116.205)
				(mid 10.479002 -116.222897)
				(end 10.503916 -116.229384)
			)
		)
		(stroke
			(width 0)
			(type solid)
		)
		(fill yes)
		(layer "F.Cu")
		(net "GND")
	)
	(gr_poly
		(pts
			(xy 13.237718 -90.932) (xy 13.247787 -90.931573) (xy 13.266386 -90.923854) (xy 13.273786 -90.917014)
			(xy 14.217142 -89.973658) (xy 14.223988 -89.96626) (xy 14.231716 -89.947661) (xy 14.232128 -89.93759)
			(xy 14.232128 -89.925906) (xy 14.231112 -89.920826) (xy 14.227544 -89.902107) (xy 14.223726 -89.864189)
			(xy 14.223492 -89.845134) (xy 14.223492 -89.84488) (xy 14.223979 -89.81763) (xy 14.231738 -89.763684)
			(xy 14.247095 -89.711392) (xy 14.269737 -89.661817) (xy 14.299204 -89.615969) (xy 14.334895 -89.574781)
			(xy 14.376085 -89.539092) (xy 14.421935 -89.509628) (xy 14.471511 -89.486988) (xy 14.523804 -89.471634)
			(xy 14.57775 -89.463878) (xy 14.605 -89.463372) (xy 14.625351 -89.463647) (xy 14.665822 -89.467979)
			(xy 14.685772 -89.472008) (xy 14.698472 -89.474802) (xy 14.723364 -89.467436) (xy 31.261304 -72.929496)
			(xy 31.261304 -61.829696) (xy 33.90392 -59.18708) (xy 35.52952 -59.18708) (xy 35.575748 -59.140852)
			(xy 39.167308 -59.140852) (xy 39.191438 -59.116722) (xy 39.198848 -59.110041) (xy 39.217285 -59.10247)
			(xy 39.227252 -59.10199) (xy 40.596566 -59.10199) (xy 40.606631 -59.101554) (xy 40.625217 -59.093822)
			(xy 40.632634 -59.087004) (xy 40.687752 -59.031886) (xy 40.687752 -55.327804) (xy 40.513 -55.153052)
			(xy 40.513 -51.9049) (xy 39.878 -51.2699) (xy 31.0769 -51.2699) (xy 27.148282 -55.198518) (xy 37.9222 -55.198518)
			(xy 37.9222 -53.78958) (xy 38.286436 -53.425344) (xy 39.642542 -53.425344) (xy 39.831264 -53.614066)
			(xy 39.831264 -55.227982) (xy 39.677594 -55.381652) (xy 38.105334 -55.381652) (xy 37.9222 -55.198518)
			(xy 27.148282 -55.198518) (xy 21.463 -60.8838) (xy 21.463 -73.67016) (xy 11.043666 -84.08924) (xy 11.036554 -84.102448)
			(xy 11.033506 -84.117942) (xy 11.03503 -84.132928) (xy 11.038078 -84.14004) (xy 11.079734 -84.24037)
			(xy 11.105134 -84.257388) (xy 11.120628 -84.257388) (xy 11.160544 -84.257937) (xy 11.239934 -84.266334)
			(xy 11.318013 -84.282979) (xy 11.393925 -84.30769) (xy 11.466839 -84.340198) (xy 11.535958 -84.380146)
			(xy 11.600525 -84.427098) (xy 11.659833 -84.480538) (xy 11.713232 -84.539883) (xy 11.760139 -84.604482)
			(xy 11.80004 -84.673628) (xy 11.832498 -84.746565) (xy 11.857157 -84.822494) (xy 11.873749 -84.900584)
			(xy 11.88209 -84.97998) (xy 11.882628 -85.019896) (xy 11.882106 -85.05983) (xy 11.873757 -85.139262)
			(xy 11.857152 -85.217386) (xy 11.832472 -85.293346) (xy 11.799987 -85.36631) (xy 11.760054 -85.435479)
			(xy 11.713109 -85.500095) (xy 11.659667 -85.55945) (xy 11.600314 -85.612894) (xy 11.535699 -85.659841)
			(xy 11.466531 -85.699777) (xy 11.393568 -85.732264) (xy 11.317609 -85.756946) (xy 11.239486 -85.773554)
			(xy 11.160054 -85.781904) (xy 11.12012 -85.782404) (xy 11.081304 -85.781918) (xy 11.004074 -85.774018)
			(xy 10.928047 -85.758308) (xy 10.854011 -85.734952) (xy 10.782733 -85.70419) (xy 10.714951 -85.666342)
			(xy 10.651367 -85.6218) (xy 10.592641 -85.571025) (xy 10.565638 -85.543136) (xy 10.55243 -85.529928)
			(xy 10.522712 -85.523832) (xy 10.508488 -85.52942) (xy 10.420604 -85.564218) (xy 10.411331 -85.568373)
			(xy 10.396834 -85.582587) (xy 10.388983 -85.60131) (xy 10.3886 -85.611462) (xy 10.3886 -85.729572)
			(xy 10.389059 -85.739208) (xy 10.396229 -85.757102) (xy 10.40257 -85.76437) (xy 10.428652 -85.792473)
			(xy 10.47566 -85.853051) (xy 10.51635 -85.918042) (xy 10.55031 -85.986789) (xy 10.577197 -86.058598)
			(xy 10.59674 -86.132743) (xy 10.608741 -86.208476) (xy 10.613079 -86.285031) (xy 10.612865 -86.289896)
			(xy 11.627106 -86.289896) (xy 11.63115 -86.211442) (xy 11.643239 -86.13382) (xy 11.663246 -86.057852)
			(xy 11.690957 -85.984344) (xy 11.72608 -85.914075) (xy 11.768242 -85.84779) (xy 11.816996 -85.786191)
			(xy 11.871825 -85.729931) (xy 11.932148 -85.679607) (xy 11.997326 -85.635753) (xy 12.066667 -85.598832)
			(xy 12.139438 -85.569237) (xy 12.214865 -85.547282) (xy 12.29215 -85.533198) (xy 12.370474 -85.527135)
			(xy 12.449006 -85.529158) (xy 12.526914 -85.539244) (xy 12.603371 -85.557288) (xy 12.677569 -85.583098)
			(xy 12.748719 -85.6164) (xy 12.816068 -85.656841) (xy 12.878902 -85.703992) (xy 12.936554 -85.757355)
			(xy 12.988414 -85.816362) (xy 13.033933 -85.880389) (xy 13.072626 -85.948757) (xy 13.104085 -86.020741)
			(xy 13.127976 -86.095578) (xy 13.144045 -86.172475) (xy 13.152122 -86.250617) (xy 13.152628 -86.289896)
			(xy 13.152122 -86.329175) (xy 13.144045 -86.407317) (xy 13.127976 -86.484214) (xy 13.104085 -86.559051)
			(xy 13.072626 -86.631035) (xy 13.033933 -86.699403) (xy 12.988414 -86.76343) (xy 12.936554 -86.822437)
			(xy 12.878902 -86.8758) (xy 12.816068 -86.922951) (xy 12.748719 -86.963392) (xy 12.677569 -86.996694)
			(xy 12.603371 -87.022504) (xy 12.526914 -87.040548) (xy 12.449006 -87.050634) (xy 12.370474 -87.052657)
			(xy 12.29215 -87.046594) (xy 12.214865 -87.03251) (xy 12.139438 -87.010555) (xy 12.066667 -86.98096)
			(xy 11.997326 -86.944039) (xy 11.932148 -86.900185) (xy 11.871825 -86.849861) (xy 11.816996 -86.793601)
			(xy 11.768242 -86.732002) (xy 11.72608 -86.665717) (xy 11.690957 -86.595448) (xy 11.663246 -86.52194)
			(xy 11.643239 -86.445972) (xy 11.63115 -86.36835) (xy 11.627106 -86.289896) (xy 10.612865 -86.289896)
			(xy 10.609711 -86.361634) (xy 10.598669 -86.437512) (xy 10.580067 -86.511899) (xy 10.554091 -86.584043)
			(xy 10.521004 -86.653214) (xy 10.481141 -86.718715) (xy 10.434903 -86.779883) (xy 10.409174 -86.80831)
			(xy 10.402824 -86.815168) (xy 10.39241 -86.841076) (xy 10.390654 -86.845643) (xy 10.388731 -86.855235)
			(xy 10.3886 -86.860126) (xy 10.3886 -88.259666) (xy 10.388738 -88.264556) (xy 10.390659 -88.274148)
			(xy 10.39241 -88.278716) (xy 10.402824 -88.304624) (xy 10.409174 -88.311482) (xy 10.434681 -88.339673)
			(xy 10.480584 -88.400281) (xy 10.520225 -88.465158) (xy 10.55321 -88.533659) (xy 10.579211 -88.605104)
			(xy 10.59797 -88.678782) (xy 10.609301 -88.753962) (xy 10.613091 -88.829897) (xy 10.609302 -88.905832)
			(xy 10.597971 -88.981012) (xy 10.579213 -89.054691) (xy 10.553212 -89.126136) (xy 10.520228 -89.194637)
			(xy 10.480588 -89.259514) (xy 10.434685 -89.320123) (xy 10.409174 -89.34831) (xy 10.402824 -89.355168)
			(xy 10.39241 -89.381076) (xy 10.390654 -89.385643) (xy 10.388731 -89.395235) (xy 10.3886 -89.400126)
			(xy 10.3886 -90.402918) (xy 10.389027 -90.412987) (xy 10.396746 -90.431586) (xy 10.403586 -90.438986)
			(xy 10.881614 -90.917014) (xy 10.889009 -90.923868) (xy 10.907608 -90.93161) (xy 10.917682 -90.932)
		)
		(stroke
			(width 0)
			(type solid)
		)
		(fill yes)
		(layer "F.Cu")
		(net "P12V_HPDB")
	)
	(gr_poly
		(pts
			(arc
				(start 323.000116 -146.49196)
				(mid 326.176433 -145.176287)
				(end 327.492106 -141.99997)
			)
			(arc
				(start 327.492106 -4.99999)
				(mid 326.176433 -1.823673)
				(end 323.000116 -0.508)
			)
			(arc
				(start 4.99999 -0.508)
				(mid 1.823673 -1.823673)
				(end 0.508 -4.99999)
			)
			(arc
				(start 0.508 -16.070072)
				(mid 1.237888 -17.832178)
				(end 2.999994 -18.562066)
			)
			(arc
				(start 9.600184 -18.562066)
				(mid 10.093621 -18.69126)
				(end 10.460736 -19.045428)
			)
			(arc
				(start 10.460736 -19.045428)
				(mid 10.479256 -19.063325)
				(end 10.50417 -19.069812)
			)
			(arc
				(start 10.879074 -19.069812)
				(mid 10.903571 -19.063515)
				(end 10.922 -19.04619)
			)
			(arc
				(start 10.967974 -18.9738)
				(mid 10.975762 -18.949691)
				(end 10.971022 -18.924778)
			)
			(arc
				(start 10.971022 -18.924778)
				(mid 10.411984 -18.290605)
				(end 9.600184 -18.054828)
			)
			(arc
				(start 2.999994 -18.054828)
				(mid 1.596829 -17.473671)
				(end 1.015492 -16.07058)
			)
			(arc
				(start 1.015492 -4.99999)
				(mid 2.182524 -2.182524)
				(end 4.99999 -1.015492)
			)
			(arc
				(start 323.000116 -1.015492)
				(mid 325.817582 -2.182524)
				(end 326.984614 -4.99999)
			)
			(arc
				(start 326.984614 -141.99997)
				(mid 325.817582 -144.817436)
				(end 323.000116 -145.984468)
			)
			(arc
				(start 236.7788 -145.984468)
				(mid 236.742879 -145.999347)
				(end 236.728 -146.035268)
			)
			(arc
				(start 236.728 -146.44116)
				(mid 236.742879 -146.477081)
				(end 236.7788 -146.49196)
			)
		)
		(stroke
			(width 0)
			(type solid)
		)
		(fill yes)
		(layer "F.Cu")
		(net "GND")
	)
	(gr_poly
		(pts
			(xy 324.569328 -69.215) (xy 324.578018 -69.21465) (xy 324.594385 -69.208803) (xy 324.601332 -69.20357)
			(xy 324.605142 -69.200268) (xy 325.406766 -68.398644) (xy 325.409474 -68.395794) (xy 325.414072 -68.389418)
			(xy 325.41591 -68.385944) (xy 325.418491 -68.380517) (xy 325.421312 -68.368837) (xy 325.421498 -68.36283)
			(xy 325.421498 -4.886706) (xy 325.421154 -4.878014) (xy 325.415315 -4.86164) (xy 325.410068 -4.854702)
			(xy 325.406766 -4.850892) (xy 322.343526 -1.787652) (xy 322.339796 -1.784129) (xy 322.331223 -1.778497)
			(xy 322.326508 -1.776476) (xy 322.317872 -1.77292) (xy 295.852088 -1.77292) (xy 295.847134 -1.773039)
			(xy 295.837412 -1.774958) (xy 295.832784 -1.77673) (xy 295.82364 -1.78054) (xy 295.817544 -1.786636)
			(xy 278.816308 -1.786636) (xy 278.807616 -1.786981) (xy 278.791244 -1.792823) (xy 278.784304 -1.798066)
			(xy 278.780494 -1.801368) (xy 278.106378 -2.475484) (xy 278.102855 -2.479213) (xy 278.097221 -2.487786)
			(xy 278.095202 -2.492502) (xy 278.091646 -2.501138) (xy 278.091646 -14.702172) (xy 309.793126 -14.702172)
			(xy 309.793126 -14.497668) (xy 309.801155 -14.29332) (xy 309.8172 -14.089446) (xy 309.841237 -13.886358)
			(xy 309.873229 -13.684371) (xy 309.913126 -13.483796) (xy 309.960866 -13.284941) (xy 310.016377 -13.088114)
			(xy 310.079573 -12.893619) (xy 310.150355 -12.701754) (xy 310.228616 -12.512816) (xy 310.314234 -12.327096)
			(xy 310.407077 -12.144881) (xy 310.507003 -11.966451) (xy 310.613856 -11.792082) (xy 310.727473 -11.622043)
			(xy 310.847678 -11.456595) (xy 310.974286 -11.295993) (xy 311.107101 -11.140487) (xy 311.245919 -10.990314)
			(xy 311.390526 -10.845707) (xy 311.540699 -10.706889) (xy 311.696205 -10.574074) (xy 311.856807 -10.447466)
			(xy 312.022255 -10.327261) (xy 312.192294 -10.213644) (xy 312.366663 -10.106791) (xy 312.545093 -10.006865)
			(xy 312.727308 -9.914022) (xy 312.913028 -9.828404) (xy 313.101966 -9.750143) (xy 313.293831 -9.679361)
			(xy 313.488326 -9.616165) (xy 313.685153 -9.560654) (xy 313.884008 -9.512914) (xy 314.084583 -9.473017)
			(xy 314.28657 -9.441025) (xy 314.489658 -9.416988) (xy 314.693532 -9.400943) (xy 314.89788 -9.392914)
			(xy 315.102384 -9.392914) (xy 315.306732 -9.400943) (xy 315.510606 -9.416988) (xy 315.713694 -9.441025)
			(xy 315.915681 -9.473017) (xy 316.116256 -9.512914) (xy 316.315111 -9.560654) (xy 316.511938 -9.616165)
			(xy 316.706433 -9.679361) (xy 316.898298 -9.750143) (xy 317.087236 -9.828404) (xy 317.272956 -9.914022)
			(xy 317.455171 -10.006865) (xy 317.633601 -10.106791) (xy 317.80797 -10.213644) (xy 317.978009 -10.327261)
			(xy 318.143457 -10.447466) (xy 318.304059 -10.574074) (xy 318.459565 -10.706889) (xy 318.609738 -10.845707)
			(xy 318.754345 -10.990314) (xy 318.893163 -11.140487) (xy 319.025978 -11.295993) (xy 319.152586 -11.456595)
			(xy 319.272791 -11.622043) (xy 319.386408 -11.792082) (xy 319.493261 -11.966451) (xy 319.593187 -12.144881)
			(xy 319.68603 -12.327096) (xy 319.771648 -12.512816) (xy 319.849909 -12.701754) (xy 319.920691 -12.893619)
			(xy 319.983887 -13.088114) (xy 320.039398 -13.284941) (xy 320.087138 -13.483796) (xy 320.127035 -13.684371)
			(xy 320.159027 -13.886358) (xy 320.183064 -14.089446) (xy 320.199109 -14.29332) (xy 320.207138 -14.497668)
			(xy 320.20764 -14.59992) (xy 320.207138 -14.702172) (xy 320.199109 -14.90652) (xy 320.183064 -15.110394)
			(xy 320.159027 -15.313482) (xy 320.127035 -15.515469) (xy 320.087138 -15.716044) (xy 320.039398 -15.914899)
			(xy 319.983887 -16.111726) (xy 319.920691 -16.306221) (xy 319.849909 -16.498086) (xy 319.771648 -16.687024)
			(xy 319.68603 -16.872744) (xy 319.593187 -17.054959) (xy 319.493261 -17.233389) (xy 319.386408 -17.407758)
			(xy 319.272791 -17.577797) (xy 319.152586 -17.743245) (xy 319.025978 -17.903847) (xy 318.893163 -18.059353)
			(xy 318.754345 -18.209526) (xy 318.609738 -18.354133) (xy 318.459565 -18.492951) (xy 318.304059 -18.625766)
			(xy 318.143457 -18.752374) (xy 317.978009 -18.872579) (xy 317.80797 -18.986196) (xy 317.633601 -19.093049)
			(xy 317.455171 -19.192975) (xy 317.272956 -19.285818) (xy 317.087236 -19.371436) (xy 316.898298 -19.449697)
			(xy 316.706433 -19.520479) (xy 316.511938 -19.583675) (xy 316.315111 -19.639186) (xy 316.116256 -19.686926)
			(xy 315.915681 -19.726823) (xy 315.713694 -19.758815) (xy 315.510606 -19.782852) (xy 315.306732 -19.798897)
			(xy 315.102384 -19.806926) (xy 314.89788 -19.806926) (xy 314.693532 -19.798897) (xy 314.489658 -19.782852)
			(xy 314.28657 -19.758815) (xy 314.084583 -19.726823) (xy 313.884008 -19.686926) (xy 313.685153 -19.639186)
			(xy 313.488326 -19.583675) (xy 313.293831 -19.520479) (xy 313.101966 -19.449697) (xy 312.913028 -19.371436)
			(xy 312.727308 -19.285818) (xy 312.545093 -19.192975) (xy 312.366663 -19.093049) (xy 312.192294 -18.986196)
			(xy 312.022255 -18.872579) (xy 311.856807 -18.752374) (xy 311.696205 -18.625766) (xy 311.540699 -18.492951)
			(xy 311.390526 -18.354133) (xy 311.245919 -18.209526) (xy 311.107101 -18.059353) (xy 310.974286 -17.903847)
			(xy 310.847678 -17.743245) (xy 310.727473 -17.577797) (xy 310.613856 -17.407758) (xy 310.507003 -17.233389)
			(xy 310.407077 -17.054959) (xy 310.314234 -16.872744) (xy 310.228616 -16.687024) (xy 310.150355 -16.498086)
			(xy 310.079573 -16.306221) (xy 310.016377 -16.111726) (xy 309.960866 -15.914899) (xy 309.913126 -15.716044)
			(xy 309.873229 -15.515469) (xy 309.841237 -15.313482) (xy 309.8172 -15.110394) (xy 309.801155 -14.90652)
			(xy 309.793126 -14.702172) (xy 278.091646 -14.702172) (xy 278.091646 -18.312892) (xy 278.092065 -18.322911)
			(xy 278.099735 -18.341423) (xy 278.113909 -18.355586) (xy 278.132427 -18.363243) (xy 278.142446 -18.363692)
			(xy 279.00884 -18.363692) (xy 279.06976 -18.364175) (xy 279.191351 -18.371957) (xy 279.312196 -18.387495)
			(xy 279.431802 -18.410724) (xy 279.549678 -18.441549) (xy 279.665343 -18.479845) (xy 279.778324 -18.525454)
			(xy 279.88816 -18.57819) (xy 279.994401 -18.637838) (xy 280.096612 -18.704154) (xy 280.194376 -18.776867)
			(xy 280.287294 -18.855679) (xy 280.374985 -18.940268) (xy 280.457091 -19.030288) (xy 280.533275 -19.125371)
			(xy 280.568654 -19.174968) (xy 280.574699 -19.182793) (xy 280.591291 -19.193517) (xy 280.600912 -19.195796)
			(xy 280.610056 -19.196558) (xy 283.996892 -19.196558) (xy 284.006962 -19.196981) (xy 284.025563 -19.2047)
			(xy 284.03296 -19.211544) (xy 287.191958 -22.370542) (xy 287.194807 -22.373251) (xy 287.201182 -22.37785)
			(xy 287.204658 -22.379686) (xy 287.210085 -22.382268) (xy 287.221765 -22.385089) (xy 287.227772 -22.385274)
			(xy 290.148518 -22.385274) (xy 290.157209 -22.384925) (xy 290.173575 -22.379078) (xy 290.180522 -22.373844)
			(xy 290.184332 -22.370542) (xy 290.797488 -21.757386) (xy 290.804882 -21.750528) (xy 290.823481 -21.742776)
			(xy 290.833556 -21.7424) (xy 297.870118 -21.7424) (xy 297.880187 -21.742827) (xy 297.898786 -21.750546)
			(xy 297.906186 -21.757386) (xy 298.435014 -22.286214) (xy 298.441868 -22.293609) (xy 298.44961 -22.312208)
			(xy 298.45 -22.322282) (xy 298.45 -26.115518) (xy 298.449573 -26.125587) (xy 298.441854 -26.144186)
			(xy 298.435014 -26.151586) (xy 298.2087 -26.3779) (xy 298.205177 -26.381629) (xy 298.199544 -26.390202)
			(xy 298.197524 -26.394918) (xy 298.193968 -26.403554) (xy 298.193968 -33.692846) (xy 298.194322 -33.701534)
			(xy 298.20018 -33.717892) (xy 298.205398 -33.72485) (xy 298.2087 -33.72866) (xy 298.892468 -34.412428)
			(xy 298.895317 -34.415137) (xy 298.901692 -34.419736) (xy 298.905168 -34.421572) (xy 298.910595 -34.424154)
			(xy 298.922275 -34.426973) (xy 298.928282 -34.42716) (xy 303.214278 -34.42716) (xy 303.224341 -34.427599)
			(xy 303.242919 -34.43534) (xy 303.250346 -34.442146) (xy 304.74031 -35.93211) (xy 304.747165 -35.939505)
			(xy 304.75491 -35.958104) (xy 304.755296 -35.968178) (xy 304.755296 -44.304966) (xy 306.278033 -44.304966)
			(xy 306.28204 -44.102216) (xy 306.294053 -43.899782) (xy 306.314054 -43.697981) (xy 306.342013 -43.497127)
			(xy 306.377884 -43.297535) (xy 306.421613 -43.099516) (xy 306.473131 -42.903379) (xy 306.532357 -42.709431)
			(xy 306.599199 -42.517973) (xy 306.673553 -42.329306) (xy 306.755302 -42.143724) (xy 306.84432 -41.961516)
			(xy 306.940466 -41.782967) (xy 307.043591 -41.608356) (xy 307.153534 -41.437956) (xy 307.270123 -41.272032)
			(xy 307.393176 -41.110843) (xy 307.522501 -40.954642) (xy 307.657896 -40.803672) (xy 307.799149 -40.658168)
			(xy 307.946041 -40.518359) (xy 308.098341 -40.384462) (xy 308.255812 -40.256687) (xy 308.418209 -40.135232)
			(xy 308.585276 -40.020288) (xy 308.756755 -39.912034) (xy 308.932376 -39.810639) (xy 309.111866 -39.716261)
			(xy 309.294944 -39.629049) (xy 309.481325 -39.549137) (xy 309.670718 -39.47665) (xy 309.862826 -39.411703)
			(xy 310.05735 -39.354395) (xy 310.253986 -39.304818) (xy 310.452428 -39.263047) (xy 310.652365 -39.229149)
			(xy 310.853484 -39.203177) (xy 311.055473 -39.18517) (xy 311.258016 -39.175157) (xy 311.460796 -39.173153)
			(xy 311.663497 -39.179163) (xy 311.865802 -39.193175) (xy 312.067396 -39.21517) (xy 312.267963 -39.245111)
			(xy 312.467191 -39.282952) (xy 312.664769 -39.328635) (xy 312.860387 -39.382088) (xy 313.053741 -39.443227)
			(xy 313.244529 -39.511958) (xy 313.432452 -39.588172) (xy 313.617218 -39.671751) (xy 313.798537 -39.762564)
			(xy 313.976128 -39.860469) (xy 314.149711 -39.965314) (xy 314.319017 -40.076935) (xy 314.483782 -40.195157)
			(xy 314.643747 -40.319797) (xy 314.798663 -40.450658) (xy 314.948288 -40.587538) (xy 315.092388 -40.730222)
			(xy 315.23074 -40.878488) (xy 315.363125 -41.032104) (xy 315.489339 -41.190829) (xy 315.609183 -41.354418)
			(xy 315.722471 -41.522613) (xy 315.829026 -41.695152) (xy 315.928681 -41.871767) (xy 316.021281 -42.05218)
			(xy 316.106681 -42.236111) (xy 316.184748 -42.423272) (xy 316.25536 -42.613372) (xy 316.318406 -42.806112)
			(xy 316.373789 -43.001193) (xy 316.421421 -43.19831) (xy 316.461229 -43.397154) (xy 316.493151 -43.597416)
			(xy 316.517135 -43.798782) (xy 316.533146 -44.000939) (xy 316.541157 -44.203571) (xy 316.541658 -44.304966)
			(xy 316.541157 -44.406361) (xy 316.533146 -44.608993) (xy 316.517135 -44.81115) (xy 316.493151 -45.012516)
			(xy 316.461229 -45.212778) (xy 316.421421 -45.411622) (xy 316.373789 -45.608739) (xy 316.318406 -45.80382)
			(xy 316.25536 -45.99656) (xy 316.184748 -46.18666) (xy 316.106681 -46.373821) (xy 316.021281 -46.557752)
			(xy 315.928681 -46.738165) (xy 315.829026 -46.91478) (xy 315.722471 -47.087319) (xy 315.609183 -47.255514)
			(xy 315.489339 -47.419103) (xy 315.363125 -47.577828) (xy 315.23074 -47.731444) (xy 315.092388 -47.87971)
			(xy 314.948288 -48.022394) (xy 314.798663 -48.159274) (xy 314.643747 -48.290135) (xy 314.483782 -48.414775)
			(xy 314.319017 -48.532997) (xy 314.149711 -48.644618) (xy 313.976128 -48.749463) (xy 313.798537 -48.847368)
			(xy 313.617218 -48.938181) (xy 313.432452 -49.02176) (xy 313.244529 -49.097974) (xy 313.053741 -49.166705)
			(xy 312.860387 -49.227844) (xy 312.664769 -49.281297) (xy 312.467191 -49.32698) (xy 312.267963 -49.364821)
			(xy 312.067396 -49.394762) (xy 311.865802 -49.416757) (xy 311.663497 -49.430769) (xy 311.460796 -49.436779)
			(xy 311.258016 -49.434775) (xy 311.055473 -49.424762) (xy 310.853484 -49.406755) (xy 310.652365 -49.380783)
			(xy 310.452428 -49.346885) (xy 310.253986 -49.305114) (xy 310.05735 -49.255537) (xy 309.862826 -49.198229)
			(xy 309.670718 -49.133282) (xy 309.481325 -49.060795) (xy 309.294944 -48.980883) (xy 309.111866 -48.893671)
			(xy 308.932376 -48.799293) (xy 308.756755 -48.697898) (xy 308.585276 -48.589644) (xy 308.418209 -48.4747)
			(xy 308.255812 -48.353245) (xy 308.098341 -48.22547) (xy 307.946041 -48.091573) (xy 307.799149 -47.951764)
			(xy 307.657896 -47.80626) (xy 307.522501 -47.65529) (xy 307.393176 -47.499089) (xy 307.270123 -47.3379)
			(xy 307.153534 -47.171976) (xy 307.043591 -47.001576) (xy 306.940466 -46.826965) (xy 306.84432 -46.648416)
			(xy 306.755302 -46.466208) (xy 306.673553 -46.280626) (xy 306.599199 -46.091959) (xy 306.532357 -45.900501)
			(xy 306.473131 -45.706553) (xy 306.421613 -45.510416) (xy 306.377884 -45.312397) (xy 306.342013 -45.112805)
			(xy 306.314054 -44.911951) (xy 306.294053 -44.71015) (xy 306.28204 -44.507716) (xy 306.278033 -44.304966)
			(xy 304.755296 -44.304966) (xy 304.755296 -48.320452) (xy 304.75565 -48.329141) (xy 304.761503 -48.345502)
			(xy 304.766726 -48.352456) (xy 304.770028 -48.356266) (xy 309.611014 -53.197252) (xy 309.617861 -53.204649)
			(xy 309.62559 -53.223248) (xy 309.626 -53.23332) (xy 309.626 -68.558918) (xy 309.626348 -68.567609)
			(xy 309.632193 -68.583977) (xy 309.63743 -68.590922) (xy 309.640732 -68.594732) (xy 310.246268 -69.200268)
			(xy 310.249118 -69.202975) (xy 310.255495 -69.207572) (xy 310.258968 -69.209412) (xy 310.264396 -69.211992)
			(xy 310.276075 -69.214809) (xy 310.282082 -69.215)
		)
		(stroke
			(width 0)
			(type solid)
		)
		(fill yes)
		(layer "F.Cu")
		(net "GND")
	)
	(gr_poly
		(pts
			(xy 281.766518 -57.3024) (xy 281.776587 -57.301973) (xy 281.795186 -57.294254) (xy 281.802586 -57.287414)
			(xy 281.848814 -57.241186) (xy 281.855668 -57.233791) (xy 281.86341 -57.215192) (xy 281.8638 -57.205118)
			(xy 281.8638 -54.580282) (xy 281.864227 -54.570213) (xy 281.871946 -54.551614) (xy 281.878786 -54.544214)
			(xy 282.306014 -54.116986) (xy 282.313409 -54.110132) (xy 282.332008 -54.10239) (xy 282.342082 -54.102)
			(xy 290.351718 -54.102) (xy 290.361787 -54.101573) (xy 290.380386 -54.093854) (xy 290.387786 -54.087014)
			(xy 290.510214 -53.964586) (xy 290.517068 -53.957191) (xy 290.52481 -53.938592) (xy 290.5252 -53.928518)
			(xy 290.5252 -51.6382) (xy 290.524712 -51.628192) (xy 290.517052 -51.609701) (xy 290.502899 -51.595548)
			(xy 290.484408 -51.587888) (xy 290.4744 -51.5874) (xy 288.920682 -51.5874) (xy 288.910613 -51.586973)
			(xy 288.892014 -51.579254) (xy 288.884614 -51.572414) (xy 288.082736 -50.770536) (xy 288.075896 -50.763136)
			(xy 288.068179 -50.744537) (xy 288.06775 -50.734468) (xy 288.06775 -50.304954) (xy 288.06394 -50.291746)
			(xy 288.060384 -50.28565) (xy 288.056877 -50.279546) (xy 288.053001 -50.266016) (xy 288.052764 -50.25898)
			(xy 288.052764 -49.453292) (xy 288.052339 -49.443223) (xy 288.044618 -49.424624) (xy 288.037778 -49.417224)
			(xy 288.015934 -49.39538) (xy 288.008822 -49.388014) (xy 287.990026 -49.380394) (xy 287.607248 -49.380394)
			(xy 287.597182 -49.380826) (xy 287.57859 -49.388553) (xy 287.57118 -49.39538) (xy 287.512252 -49.454308)
			(xy 287.504886 -49.46142) (xy 287.497266 -49.480216) (xy 287.497266 -50.440082) (xy 287.496827 -50.450145)
			(xy 287.489088 -50.468725) (xy 287.48228 -50.47615) (xy 287.286192 -50.672238) (xy 287.278796 -50.67909)
			(xy 287.260197 -50.686831) (xy 287.250124 -50.687224) (xy 285.500318 -50.687224) (xy 285.490268 -50.686718)
			(xy 285.471708 -50.678996) (xy 285.46425 -50.672238) (xy 285.279592 -50.48758) (xy 285.27275 -50.48018)
			(xy 285.265024 -50.461582) (xy 285.264606 -50.451512) (xy 285.264606 -49.487328) (xy 285.26417 -49.477263)
			(xy 285.256438 -49.458677) (xy 285.24962 -49.45126) (xy 285.20517 -49.40681) (xy 285.198058 -49.399444)
			(xy 285.179262 -49.391824) (xy 280.713688 -49.391824) (xy 280.703619 -49.39225) (xy 280.68502 -49.39997)
			(xy 280.67762 -49.40681) (xy 280.632916 -49.451514) (xy 280.62555 -49.458626) (xy 280.61793 -49.477422)
			(xy 280.61793 -53.0352) (xy 280.284936 -53.368194) (xy 274.730464 -53.368194) (xy 273.85645 -52.49418)
			(xy 273.85645 -48.93183) (xy 274.77212 -48.01616) (xy 275.722842 -48.01616) (xy 275.73024 -48.009314)
			(xy 275.748839 -48.001585) (xy 275.75891 -48.001174) (xy 278.682196 -48.001174) (xy 278.692266 -48.000751)
			(xy 278.710869 -47.993035) (xy 278.718264 -47.986188) (xy 278.743664 -47.960788) (xy 278.750512 -47.953391)
			(xy 278.758248 -47.934792) (xy 278.75865 -47.92472) (xy 278.75865 -46.444662) (xy 278.758218 -46.434596)
			(xy 278.750489 -46.416006) (xy 278.743664 -46.408594) (xy 278.729186 -46.394116) (xy 278.722074 -46.38675)
			(xy 278.703278 -46.37913) (xy 277.549864 -46.37913) (xy 277.539796 -46.378701) (xy 277.521198 -46.370981)
			(xy 277.513796 -46.364144) (xy 277.277322 -46.12767) (xy 277.270478 -46.120271) (xy 277.262751 -46.101673)
			(xy 277.262336 -46.091602) (xy 277.262336 -44.964858) (xy 277.262768 -44.954792) (xy 277.270497 -44.936202)
			(xy 277.277322 -44.92879) (xy 277.847044 -44.359068) (xy 277.853891 -44.35167) (xy 277.861623 -44.333072)
			(xy 277.86203 -44.323) (xy 277.86203 -43.42384) (xy 277.862465 -43.413775) (xy 277.870198 -43.395189)
			(xy 277.877016 -43.387772) (xy 278.002746 -43.262042) (xy 278.010145 -43.255198) (xy 278.028744 -43.247474)
			(xy 278.038814 -43.247056) (xy 278.593804 -43.247056) (xy 278.603873 -43.246631) (xy 278.622472 -43.23891)
			(xy 278.629872 -43.23207) (xy 278.676608 -43.185334) (xy 278.683443 -43.177932) (xy 278.691152 -43.159333)
			(xy 278.691594 -43.149266) (xy 278.691594 -41.933876) (xy 278.691166 -41.923808) (xy 278.683445 -41.90521)
			(xy 278.676608 -41.897808) (xy 278.144986 -41.366186) (xy 278.137874 -41.35882) (xy 278.119078 -41.3512)
			(xy 275.433282 -41.3512) (xy 275.423213 -41.351627) (xy 275.404614 -41.359346) (xy 275.397214 -41.366186)
			(xy 274.989036 -41.774364) (xy 274.98167 -41.781476) (xy 274.97405 -41.800272) (xy 274.97405 -45.322744)
			(xy 274.973617 -45.33281) (xy 274.965886 -45.351398) (xy 274.959064 -45.358812) (xy 272.580862 -47.737014)
			(xy 272.573466 -47.743864) (xy 272.554866 -47.751598) (xy 272.544794 -47.752) (xy 270.785082 -47.752)
			(xy 270.775013 -47.752427) (xy 270.756414 -47.760146) (xy 270.749014 -47.766986) (xy 270.651986 -47.864014)
			(xy 270.64462 -47.871126) (xy 270.637 -47.889922) (xy 270.637 -48.873918) (xy 270.636573 -48.883987)
			(xy 270.628854 -48.902586) (xy 270.622014 -48.909986) (xy 270.397986 -49.134014) (xy 270.390591 -49.140868)
			(xy 270.371992 -49.14861) (xy 270.361918 -49.149) (xy 266.086082 -49.149) (xy 266.076013 -49.148573)
			(xy 266.057414 -49.140854) (xy 266.050014 -49.134014) (xy 265.697462 -48.781462) (xy 265.690615 -48.774064)
			(xy 265.682884 -48.755466) (xy 265.682476 -48.745394) (xy 265.682476 -44.130214) (xy 265.758676 -44.054014)
			(xy 266.455652 -44.054014) (xy 266.465681 -44.053603) (xy 266.484216 -44.045942) (xy 266.498407 -44.031769)
			(xy 266.506091 -44.013242) (xy 266.506452 -44.003214) (xy 266.506452 -38.68039) (xy 266.50603 -38.670374)
			(xy 266.498357 -38.651868) (xy 266.484183 -38.637711) (xy 266.465669 -38.630059) (xy 266.455652 -38.62959)
			(xy 264.802874 -38.62959) (xy 264.792806 -38.629162) (xy 264.774209 -38.62144) (xy 264.766806 -38.614604)
			(xy 264.7061 -38.553898) (xy 264.699254 -38.546499) (xy 264.69152 -38.527901) (xy 264.691114 -38.51783)
			(xy 264.691114 -38.296088) (xy 264.690606 -38.29558) (xy 264.690606 -33.168844) (xy 264.690173 -33.158778)
			(xy 264.682445 -33.140188) (xy 264.67562 -33.132776) (xy 264.364216 -32.821372) (xy 264.357372 -32.813973)
			(xy 264.349645 -32.795375) (xy 264.34923 -32.785304) (xy 264.34923 -31.789878) (xy 264.349658 -31.77981)
			(xy 264.357381 -31.761214) (xy 264.364216 -31.75381) (xy 264.78484 -31.333186) (xy 264.792236 -31.326336)
			(xy 264.810836 -31.318603) (xy 264.820908 -31.3182) (xy 267.085318 -31.3182) (xy 267.095387 -31.318627)
			(xy 267.113986 -31.326346) (xy 267.121386 -31.333186) (xy 267.447014 -31.658814) (xy 267.453868 -31.666209)
			(xy 267.46161 -31.684808) (xy 267.462 -31.694882) (xy 267.462 -33.608518) (xy 267.462427 -33.618587)
			(xy 267.470146 -33.637186) (xy 267.476986 -33.644586) (xy 268.239748 -34.407348) (xy 268.246592 -34.414747)
			(xy 268.254318 -34.433345) (xy 268.254734 -34.443416) (xy 268.254734 -35.322002) (xy 268.255158 -35.332071)
			(xy 268.262877 -35.350672) (xy 268.26972 -35.35807) (xy 268.460474 -35.548824) (xy 268.467873 -35.555667)
			(xy 268.486472 -35.563386) (xy 268.496542 -35.56381) (xy 269.987014 -35.56381) (xy 269.997083 -35.563385)
			(xy 270.015685 -35.555668) (xy 270.023082 -35.548824) (xy 270.190214 -35.381692) (xy 270.197068 -35.374297)
			(xy 270.204814 -35.355698) (xy 270.2052 -35.345624) (xy 270.2052 -31.390082) (xy 270.205627 -31.380013)
			(xy 270.213346 -31.361414) (xy 270.220186 -31.354014) (xy 270.825214 -30.748986) (xy 270.832609 -30.742132)
			(xy 270.851208 -30.73439) (xy 270.861282 -30.734) (xy 278.07793 -30.734) (xy 279.893014 -32.549084)
			(xy 279.893014 -33.538414) (xy 279.899868 -33.545809) (xy 279.90761 -33.564408) (xy 279.908 -33.574482)
			(xy 279.908 -35.488118) (xy 279.908427 -35.498187) (xy 279.916146 -35.516786) (xy 279.922986 -35.524186)
			(xy 279.969214 -35.570414) (xy 279.976609 -35.577268) (xy 279.995208 -35.58501) (xy 280.005282 -35.5854)
			(xy 280.725118 -35.5854) (xy 280.735187 -35.584973) (xy 280.753786 -35.577254) (xy 280.761186 -35.570414)
			(xy 280.807414 -35.524186) (xy 280.814268 -35.516791) (xy 280.82201 -35.498192) (xy 280.8224 -35.488118)
			(xy 280.8224 -33.980882) (xy 280.822827 -33.970813) (xy 280.830546 -33.952214) (xy 280.837386 -33.944814)
			(xy 281.112214 -33.669986) (xy 281.119609 -33.663132) (xy 281.138208 -33.65539) (xy 281.148282 -33.655)
			(xy 281.995118 -33.655) (xy 282.005187 -33.655427) (xy 282.023786 -33.663146) (xy 282.031186 -33.669986)
			(xy 283.169614 -34.808414) (xy 283.177009 -34.815268) (xy 283.195608 -34.82301) (xy 283.205682 -34.8234)
			(xy 283.392118 -34.8234) (xy 283.402187 -34.823827) (xy 283.420786 -34.831546) (xy 283.428186 -34.838386)
			(xy 284.134814 -35.545014) (xy 284.142209 -35.551868) (xy 284.160808 -35.55961) (xy 284.170882 -35.56)
			(xy 285.347918 -35.56) (xy 285.357987 -35.559573) (xy 285.376586 -35.551854) (xy 285.383986 -35.545014)
			(xy 285.481014 -35.447986) (xy 285.487868 -35.440591) (xy 285.49561 -35.421992) (xy 285.496 -35.411918)
			(xy 285.496 -34.946082) (xy 285.495573 -34.936013) (xy 285.487854 -34.917414) (xy 285.481014 -34.910014)
			(xy 285.129986 -34.558986) (xy 285.122874 -34.55162) (xy 285.104078 -34.544) (xy 284.213046 -34.544)
			(xy 284.20298 -34.543567) (xy 284.18439 -34.535839) (xy 284.176978 -34.529014) (xy 282.031186 -32.383222)
			(xy 282.024343 -32.375823) (xy 282.016623 -32.357224) (xy 282.0162 -32.347154) (xy 282.0162 -29.789882)
			(xy 282.016627 -29.779813) (xy 282.024346 -29.761214) (xy 282.031186 -29.753814) (xy 283.230828 -28.554172)
			(xy 283.238225 -28.547322) (xy 283.256823 -28.539587) (xy 283.266896 -28.539186) (xy 283.91612 -28.539186)
			(xy 283.929328 -28.535376) (xy 283.935424 -28.53182) (xy 283.941532 -28.528325) (xy 283.955062 -28.524475)
			(xy 283.962094 -28.5242) (xy 289.157918 -28.5242) (xy 289.167987 -28.524627) (xy 289.186586 -28.532346)
			(xy 289.193986 -28.539186) (xy 289.209988 -28.555188) (xy 289.209988 -28.557474) (xy 290.525454 -29.87294)
			(xy 290.532299 -29.880339) (xy 290.540026 -29.898937) (xy 290.54044 -29.909008) (xy 290.54044 -34.482278)
			(xy 290.540001 -34.492341) (xy 290.53226 -34.510919) (xy 290.525454 -34.518346) (xy 290.159186 -34.884614)
			(xy 290.151791 -34.891468) (xy 290.133192 -34.89921) (xy 290.123118 -34.8996) (xy 287.658302 -34.8996)
			(xy 287.648232 -34.900023) (xy 287.629627 -34.907737) (xy 287.622234 -34.914586) (xy 287.591246 -34.945574)
			(xy 287.58388 -34.952686) (xy 287.57626 -34.971482) (xy 287.57626 -37.896038) (xy 287.575829 -37.906104)
			(xy 287.5681 -37.924695) (xy 287.561274 -37.932106) (xy 287.136586 -38.356794) (xy 287.12922 -38.363906)
			(xy 287.1216 -38.382702) (xy 287.1216 -39.403782) (xy 287.121162 -39.413846) (xy 287.113426 -39.432428)
			(xy 287.106614 -39.43985) (xy 287.037526 -39.508938) (xy 287.030127 -39.51578) (xy 287.011528 -39.523497)
			(xy 287.001458 -39.523924) (xy 284.280356 -39.523924) (xy 284.27029 -39.524356) (xy 284.251699 -39.532084)
			(xy 284.244288 -39.53891) (xy 284.24378 -39.539418) (xy 284.236928 -39.546814) (xy 284.229187 -39.565413)
			(xy 284.228794 -39.575486) (xy 284.228794 -45.104304) (xy 284.229283 -45.114312) (xy 284.236943 -45.132803)
			(xy 284.251095 -45.146956) (xy 284.269586 -45.154617) (xy 284.279594 -45.155104) (xy 287.00476 -45.155104)
			(xy 287.014825 -45.15467) (xy 287.033414 -45.146941) (xy 287.040828 -45.140118) (xy 287.049972 -45.130974)
			(xy 287.056817 -45.123575) (xy 287.064547 -45.104977) (xy 287.064958 -45.094906) (xy 287.064958 -39.948104)
			(xy 287.065382 -39.938035) (xy 287.073102 -39.919435) (xy 287.079944 -39.912036) (xy 287.441894 -39.550086)
			(xy 287.448739 -39.542687) (xy 287.456469 -39.524089) (xy 287.45688 -39.514018) (xy 287.45688 -38.624002)
			(xy 287.457302 -38.613931) (xy 287.465014 -38.595324) (xy 287.471866 -38.587934) (xy 288.292794 -37.767006)
			(xy 288.364422 -37.695378) (xy 291.23259 -37.695378) (xy 291.23259 -32.244538) (xy 291.233606 -32.243522)
			(xy 291.400738 -32.07639) (xy 291.400738 -29.272738) (xy 289.066986 -26.938986) (xy 289.059874 -26.93162)
			(xy 289.041078 -26.924) (xy 267.66393 -26.924) (xy 267.653865 -26.924436) (xy 267.63528 -26.932168)
			(xy 267.627862 -26.938986) (xy 267.134848 -27.432) (xy 275.141688 -27.432) (xy 275.145761 -27.376341)
			(xy 275.157896 -27.321868) (xy 275.177832 -27.269742) (xy 275.205146 -27.221074) (xy 275.239254 -27.176902)
			(xy 275.279431 -27.138167) (xy 275.324819 -27.105695) (xy 275.374451 -27.080177) (xy 275.427271 -27.062158)
			(xy 275.48215 -27.052021) (xy 275.537921 -27.049983) (xy 275.593395 -27.056086) (xy 275.647388 -27.070202)
			(xy 275.698751 -27.092029) (xy 275.746389 -27.121102) (xy 275.789285 -27.156801) (xy 275.826527 -27.198365)
			(xy 275.857321 -27.244909) (xy 275.881009 -27.29544) (xy 275.897087 -27.348882) (xy 275.905213 -27.404096)
			(xy 275.905722 -27.432) (xy 275.905213 -27.459904) (xy 275.897087 -27.515118) (xy 275.881009 -27.56856)
			(xy 275.857321 -27.619091) (xy 275.826527 -27.665635) (xy 275.789285 -27.707199) (xy 275.746389 -27.742898)
			(xy 275.698751 -27.771971) (xy 275.647388 -27.793798) (xy 275.593395 -27.807914) (xy 275.537921 -27.814017)
			(xy 275.48215 -27.811979) (xy 275.427271 -27.801842) (xy 275.374451 -27.783823) (xy 275.324819 -27.758305)
			(xy 275.279431 -27.725833) (xy 275.239254 -27.687098) (xy 275.205146 -27.642926) (xy 275.177832 -27.594258)
			(xy 275.157896 -27.542132) (xy 275.145761 -27.487659) (xy 275.141688 -27.432) (xy 267.134848 -27.432)
			(xy 266.626848 -27.94) (xy 271.118328 -27.94) (xy 271.122401 -27.884341) (xy 271.134536 -27.829868)
			(xy 271.154472 -27.777742) (xy 271.181786 -27.729074) (xy 271.215894 -27.684902) (xy 271.256071 -27.646167)
			(xy 271.301459 -27.613695) (xy 271.351091 -27.588177) (xy 271.403911 -27.570158) (xy 271.45879 -27.560021)
			(xy 271.514561 -27.557983) (xy 271.570035 -27.564086) (xy 271.624028 -27.578202) (xy 271.675391 -27.600029)
			(xy 271.723029 -27.629102) (xy 271.765925 -27.664801) (xy 271.803167 -27.706365) (xy 271.833961 -27.752909)
			(xy 271.857649 -27.80344) (xy 271.873727 -27.856882) (xy 271.881853 -27.912096) (xy 271.882362 -27.94)
			(xy 271.881853 -27.967904) (xy 271.873727 -28.023118) (xy 271.857649 -28.07656) (xy 271.833961 -28.127091)
			(xy 271.803167 -28.173635) (xy 271.765925 -28.215199) (xy 271.723029 -28.250898) (xy 271.675391 -28.279971)
			(xy 271.624028 -28.301798) (xy 271.570035 -28.315914) (xy 271.514561 -28.322017) (xy 271.45879 -28.319979)
			(xy 271.403911 -28.309842) (xy 271.351091 -28.291823) (xy 271.301459 -28.266305) (xy 271.256071 -28.233833)
			(xy 271.215894 -28.195098) (xy 271.181786 -28.150926) (xy 271.154472 -28.102258) (xy 271.134536 -28.050132)
			(xy 271.122401 -27.995659) (xy 271.118328 -27.94) (xy 266.626848 -27.94) (xy 264.432034 -30.134814)
			(xy 264.424636 -30.141659) (xy 264.406037 -30.149383) (xy 264.395966 -30.1498) (xy 261.641082 -30.1498)
			(xy 261.631013 -30.150227) (xy 261.612414 -30.157946) (xy 261.605014 -30.164786) (xy 261.076186 -30.693614)
			(xy 261.068791 -30.700468) (xy 261.050192 -30.70821) (xy 261.040118 -30.7086) (xy 257.932682 -30.7086)
			(xy 257.922613 -30.709027) (xy 257.904014 -30.716746) (xy 257.896614 -30.723586) (xy 255.919986 -32.700214)
			(xy 255.91262 -32.707326) (xy 255.905 -32.726122) (xy 255.905 -44.174918) (xy 255.904573 -44.184987)
			(xy 255.896854 -44.203586) (xy 255.890014 -44.210986) (xy 253.760986 -46.340014) (xy 253.75362 -46.347126)
			(xy 253.746 -46.365922) (xy 253.746 -50.728372) (xy 253.746436 -50.738436) (xy 253.754169 -50.757022)
			(xy 253.760986 -50.76444) (xy 254.405892 -51.409346) (xy 256.043938 -51.409346) (xy 256.043938 -46.56836)
			(xy 256.044333 -46.558287) (xy 256.052074 -46.539689) (xy 256.058924 -46.532292) (xy 257.511296 -45.07992)
			(xy 257.511296 -35.993578) (xy 258.078732 -35.426142) (xy 258.078986 -35.425888) (xy 259.545074 -33.9598)
			(xy 259.552489 -33.952979) (xy 259.571077 -33.945248) (xy 259.581142 -33.944814) (xy 262.491982 -33.944814)
			(xy 262.502051 -33.945245) (xy 262.520649 -33.952961) (xy 262.52805 -33.9598) (xy 264.137902 -35.569652)
			(xy 264.144714 -35.577074) (xy 264.15245 -35.595657) (xy 264.152888 -35.60572) (xy 264.152888 -36.54679)
			(xy 264.153295 -36.556862) (xy 264.161026 -36.575461) (xy 264.167874 -36.582858) (xy 264.380472 -36.795456)
			(xy 264.387281 -36.802881) (xy 264.39502 -36.821461) (xy 264.395458 -36.831524) (xy 264.395458 -38.51656)
			(xy 264.395023 -38.526628) (xy 264.38731 -38.545227) (xy 264.380472 -38.552628) (xy 264.324338 -38.608762)
			(xy 264.316914 -38.615573) (xy 264.298333 -38.623311) (xy 264.28827 -38.623748) (xy 262.880094 -38.623748)
			(xy 262.870066 -38.624116) (xy 262.85154 -38.631797) (xy 262.837366 -38.645986) (xy 262.829705 -38.66452)
			(xy 262.829294 -38.674548) (xy 262.829294 -43.673776) (xy 262.829707 -43.683847) (xy 262.837433 -43.702446)
			(xy 262.84428 -43.709844) (xy 263.173464 -44.039028) (xy 263.180879 -44.045849) (xy 263.199467 -44.053579)
			(xy 263.209532 -44.054014) (xy 264.850626 -44.054014) (xy 264.90295 -44.106338) (xy 264.90295 -45.10278)
			(xy 264.903373 -45.11285) (xy 264.911094 -45.131448) (xy 264.917936 -45.138848) (xy 265.022838 -45.24375)
			(xy 265.029596 -45.251208) (xy 265.037318 -45.269768) (xy 265.037824 -45.279818) (xy 265.037824 -47.615094)
			(xy 265.037416 -47.625166) (xy 265.029685 -47.643764) (xy 265.022838 -47.651162) (xy 264.936986 -47.737014)
			(xy 264.929586 -47.743854) (xy 264.910987 -47.751573) (xy 264.900918 -47.752) (xy 264.358882 -47.752)
			(xy 264.348808 -47.75239) (xy 264.330209 -47.760132) (xy 264.322814 -47.766986) (xy 264.301986 -47.787814)
			(xy 264.29462 -47.794926) (xy 264.287 -47.813722) (xy 264.287 -52.701444) (xy 263.602978 -53.385466)
			(xy 258.020058 -53.385466) (xy 256.043938 -51.409346) (xy 254.405892 -51.409346) (xy 260.28396 -57.287414)
			(xy 260.291358 -57.29426) (xy 260.309957 -57.301986) (xy 260.320028 -57.3024)
		)
		(stroke
			(width 0)
			(type solid)
		)
		(fill yes)
		(layer "F.Cu")
		(net "GND_FIELD_SIGNAL")
	)
	(gr_poly
		(pts
			(xy 192.685162 -115.268756) (xy 192.695226 -115.26832) (xy 192.71381 -115.260585) (xy 192.72123 -115.25377)
			(xy 194.980814 -112.994186) (xy 194.987668 -112.986791) (xy 194.99541 -112.968192) (xy 194.9958 -112.958118)
			(xy 194.9958 -82.113882) (xy 194.995373 -82.103813) (xy 194.987654 -82.085214) (xy 194.980814 -82.077814)
			(xy 194.578986 -81.675986) (xy 194.571591 -81.669132) (xy 194.552992 -81.66139) (xy 194.542918 -81.661)
			(xy 189.79769 -81.661) (xy 189.7889 -81.66137) (xy 189.772357 -81.667322) (xy 189.758803 -81.678519)
			(xy 189.754002 -81.685892) (xy 189.702694 -81.77276) (xy 189.702186 -81.799684) (xy 189.70879 -81.811368)
			(xy 189.733897 -81.858253) (xy 189.777109 -81.955444) (xy 189.812038 -82.055908) (xy 189.838441 -82.158942)
			(xy 189.856132 -82.263824) (xy 189.864988 -82.369818) (xy 189.865508 -82.423) (xy 189.865033 -82.47314)
			(xy 189.857151 -82.573111) (xy 189.841412 -82.672149) (xy 189.817914 -82.769637) (xy 189.786803 -82.86497)
			(xy 189.767972 -82.911442) (xy 189.764481 -82.920914) (xy 189.764481 -82.941086) (xy 189.767972 -82.950558)
			(xy 189.786769 -82.996988) (xy 189.817855 -83.092221) (xy 189.841345 -83.189606) (xy 189.857091 -83.288538)
			(xy 189.864997 -83.388403) (xy 189.865508 -83.438492) (xy 189.865508 -83.439) (xy 189.865048 -83.487824)
			(xy 189.85755 -83.585185) (xy 189.8426 -83.681683) (xy 189.820285 -83.776747) (xy 189.790737 -83.869818)
			(xy 189.75413 -83.960346) (xy 189.71068 -84.047796) (xy 189.660645 -84.131651) (xy 189.632844 -84.17179)
			(xy 189.627271 -84.180602) (xy 189.623055 -84.201) (xy 189.627271 -84.221398) (xy 189.632844 -84.23021)
			(xy 189.660634 -84.270357) (xy 189.710673 -84.354209) (xy 189.754125 -84.441656) (xy 189.790733 -84.532183)
			(xy 189.820281 -84.625253) (xy 189.842594 -84.720318) (xy 189.85754 -84.816815) (xy 189.865032 -84.914176)
			(xy 189.865508 -84.963) (xy 189.864991 -85.014572) (xy 189.856631 -85.117377) (xy 189.839964 -85.219166)
			(xy 189.815102 -85.319269) (xy 189.782208 -85.417028) (xy 189.741498 -85.511798) (xy 189.693239 -85.602957)
			(xy 189.637751 -85.689904) (xy 189.575397 -85.772067) (xy 189.506589 -85.848906) (xy 189.469522 -85.884766)
			(xy 189.462938 -85.89154) (xy 189.454879 -85.908611) (xy 189.45354 -85.927441) (xy 189.459105 -85.94548)
			(xy 189.464696 -85.953092) (xy 189.497208 -85.995111) (xy 189.555908 -86.083676) (xy 189.607006 -86.176834)
			(xy 189.650146 -86.273934) (xy 189.685024 -86.374298) (xy 189.711399 -86.477224) (xy 189.729085 -86.581994)
			(xy 189.737959 -86.687874) (xy 189.738508 -86.741) (xy 189.738508 -86.741254) (xy 189.737993 -86.792104)
			(xy 189.729839 -86.893476) (xy 189.713611 -86.993873) (xy 189.689414 -87.092653) (xy 189.657401 -87.189183)
			(xy 189.617778 -87.282847) (xy 189.570798 -87.373045) (xy 189.544198 -87.416386) (xy 189.538847 -87.425885)
			(xy 189.535939 -87.447471) (xy 189.542211 -87.468329) (xy 189.549024 -87.476838) (xy 189.582274 -87.515405)
			(xy 189.643193 -87.597011) (xy 189.697383 -87.683234) (xy 189.744495 -87.773518) (xy 189.784226 -87.867286)
			(xy 189.816321 -87.963933) (xy 189.840575 -88.06284) (xy 189.856831 -88.163371) (xy 189.864985 -88.264881)
			(xy 189.865508 -88.3158) (xy 189.865018 -88.36635) (xy 189.856981 -88.46713) (xy 189.840959 -88.566952)
			(xy 189.817052 -88.665185) (xy 189.785412 -88.761206) (xy 189.74624 -88.854409) (xy 189.699782 -88.944203)
			(xy 189.673484 -88.987376) (xy 189.668791 -88.995638) (xy 189.665284 -89.0143) (xy 189.668791 -89.032962)
			(xy 189.673484 -89.041224) (xy 189.699788 -89.084394) (xy 189.746238 -89.174191) (xy 189.785406 -89.267395)
			(xy 189.817044 -89.363417) (xy 189.840951 -89.461649) (xy 189.856976 -89.561471) (xy 189.865018 -89.66225)
			(xy 189.865508 -89.7128) (xy 189.865018 -89.762699) (xy 189.862948 -89.789) (xy 191.133982 -89.789)
			(xy 191.138053 -89.733378) (xy 191.150179 -89.678941) (xy 191.170102 -89.62685) (xy 191.197398 -89.578215)
			(xy 191.231484 -89.534072) (xy 191.271633 -89.495363) (xy 191.316991 -89.462912) (xy 191.366591 -89.437411)
			(xy 191.419375 -89.419404) (xy 191.474218 -89.409274) (xy 191.529952 -89.407237) (xy 191.585389 -89.413337)
			(xy 191.639346 -89.427443) (xy 191.690675 -89.449255) (xy 191.738281 -89.478309) (xy 191.781149 -89.513984)
			(xy 191.818366 -89.555521) (xy 191.849139 -89.602034) (xy 191.872811 -89.652531) (xy 191.888879 -89.705938)
			(xy 191.896999 -89.761114) (xy 191.897508 -89.789) (xy 191.896999 -89.816886) (xy 191.888879 -89.872062)
			(xy 191.872811 -89.925469) (xy 191.849139 -89.975966) (xy 191.818366 -90.022479) (xy 191.781149 -90.064016)
			(xy 191.738281 -90.099691) (xy 191.690675 -90.128745) (xy 191.639346 -90.150557) (xy 191.585389 -90.164663)
			(xy 191.529952 -90.170763) (xy 191.474218 -90.168726) (xy 191.419375 -90.158596) (xy 191.366591 -90.140589)
			(xy 191.316991 -90.115088) (xy 191.271633 -90.082637) (xy 191.231484 -90.043928) (xy 191.197398 -89.999785)
			(xy 191.170102 -89.95115) (xy 191.150179 -89.899059) (xy 191.138053 -89.844622) (xy 191.133982 -89.789)
			(xy 189.862948 -89.789) (xy 189.857188 -89.86219) (xy 189.841576 -89.960759) (xy 189.818279 -90.0578)
			(xy 189.787439 -90.152714) (xy 189.749248 -90.244916) (xy 189.703941 -90.333837) (xy 189.651796 -90.418929)
			(xy 189.593136 -90.499667) (xy 189.528322 -90.575554) (xy 189.457754 -90.646122) (xy 189.433218 -90.667078)
			(xy 191.133982 -90.667078) (xy 191.138053 -90.611456) (xy 191.150179 -90.557019) (xy 191.170102 -90.504928)
			(xy 191.197398 -90.456293) (xy 191.231484 -90.41215) (xy 191.271633 -90.373441) (xy 191.316991 -90.34099)
			(xy 191.366591 -90.315489) (xy 191.419375 -90.297482) (xy 191.474218 -90.287352) (xy 191.529952 -90.285315)
			(xy 191.585389 -90.291415) (xy 191.639346 -90.305521) (xy 191.690675 -90.327333) (xy 191.738281 -90.356387)
			(xy 191.781149 -90.392062) (xy 191.818366 -90.433599) (xy 191.849139 -90.480112) (xy 191.872811 -90.530609)
			(xy 191.888879 -90.584016) (xy 191.896999 -90.639192) (xy 191.897508 -90.667078) (xy 191.896999 -90.694964)
			(xy 191.888879 -90.75014) (xy 191.872811 -90.803547) (xy 191.849139 -90.854044) (xy 191.818366 -90.900557)
			(xy 191.781149 -90.942094) (xy 191.738281 -90.977769) (xy 191.690675 -91.006823) (xy 191.639346 -91.028635)
			(xy 191.585389 -91.042741) (xy 191.529952 -91.048841) (xy 191.474218 -91.046804) (xy 191.419375 -91.036674)
			(xy 191.366591 -91.018667) (xy 191.316991 -90.993166) (xy 191.271633 -90.960715) (xy 191.231484 -90.922006)
			(xy 191.197398 -90.877863) (xy 191.170102 -90.829228) (xy 191.150179 -90.777137) (xy 191.138053 -90.7227)
			(xy 191.133982 -90.667078) (xy 189.433218 -90.667078) (xy 189.381867 -90.710936) (xy 189.301129 -90.769596)
			(xy 189.216037 -90.821741) (xy 189.127116 -90.867048) (xy 189.034914 -90.905239) (xy 188.94 -90.936079)
			(xy 188.842959 -90.959376) (xy 188.74439 -90.974988) (xy 188.644899 -90.982818) (xy 188.545101 -90.982818)
			(xy 188.44561 -90.974988) (xy 188.347041 -90.959376) (xy 188.25 -90.936079) (xy 188.155086 -90.905239)
			(xy 188.062884 -90.867048) (xy 187.973963 -90.821741) (xy 187.888871 -90.769596) (xy 187.808133 -90.710936)
			(xy 187.732246 -90.646122) (xy 187.661678 -90.575554) (xy 187.596864 -90.499667) (xy 187.538204 -90.418929)
			(xy 187.486059 -90.333837) (xy 187.440752 -90.244916) (xy 187.402561 -90.152714) (xy 187.371721 -90.0578)
			(xy 187.348424 -89.960759) (xy 187.332812 -89.86219) (xy 187.324982 -89.762699) (xy 187.324492 -89.7128)
			(xy 187.324982 -89.66225) (xy 187.333019 -89.56147) (xy 187.349041 -89.461648) (xy 187.372948 -89.363415)
			(xy 187.404588 -89.267394) (xy 187.44376 -89.174191) (xy 187.490218 -89.084397) (xy 187.516516 -89.041224)
			(xy 187.521209 -89.032962) (xy 187.524716 -89.0143) (xy 187.521209 -88.995638) (xy 187.516516 -88.987376)
			(xy 187.490212 -88.944206) (xy 187.443762 -88.854409) (xy 187.404594 -88.761205) (xy 187.372956 -88.665183)
			(xy 187.349049 -88.566951) (xy 187.333024 -88.467129) (xy 187.324982 -88.36635) (xy 187.324492 -88.3158)
			(xy 187.324492 -88.315546) (xy 187.325007 -88.264696) (xy 187.333161 -88.163324) (xy 187.349389 -88.062927)
			(xy 187.373586 -87.964147) (xy 187.405599 -87.867617) (xy 187.445222 -87.773953) (xy 187.492202 -87.683755)
			(xy 187.518802 -87.640414) (xy 187.524153 -87.630915) (xy 187.527061 -87.609329) (xy 187.520789 -87.588471)
			(xy 187.513976 -87.579962) (xy 187.480726 -87.541395) (xy 187.419807 -87.459789) (xy 187.365617 -87.373566)
			(xy 187.318505 -87.283282) (xy 187.278774 -87.189514) (xy 187.246679 -87.092867) (xy 187.222425 -86.99396)
			(xy 187.206169 -86.893429) (xy 187.198015 -86.791919) (xy 187.197492 -86.741) (xy 187.198009 -86.689428)
			(xy 187.206369 -86.586623) (xy 187.223036 -86.484834) (xy 187.247898 -86.384731) (xy 187.280792 -86.286972)
			(xy 187.321502 -86.192202) (xy 187.369761 -86.101043) (xy 187.425249 -86.014096) (xy 187.487603 -85.931933)
			(xy 187.556411 -85.855094) (xy 187.593478 -85.819234) (xy 187.600062 -85.81246) (xy 187.608121 -85.795389)
			(xy 187.60946 -85.776559) (xy 187.603895 -85.75852) (xy 187.598304 -85.750908) (xy 187.565792 -85.708889)
			(xy 187.507092 -85.620324) (xy 187.455994 -85.527166) (xy 187.412854 -85.430066) (xy 187.377976 -85.329702)
			(xy 187.351601 -85.226776) (xy 187.333915 -85.122006) (xy 187.325041 -85.016126) (xy 187.324492 -84.963)
			(xy 187.324952 -84.914176) (xy 187.33245 -84.816815) (xy 187.3474 -84.720317) (xy 187.369715 -84.625253)
			(xy 187.399263 -84.532182) (xy 187.43587 -84.441654) (xy 187.47932 -84.354204) (xy 187.529355 -84.270349)
			(xy 187.557156 -84.23021) (xy 187.562729 -84.221398) (xy 187.566945 -84.201) (xy 187.562729 -84.180602)
			(xy 187.557156 -84.17179) (xy 187.529366 -84.131643) (xy 187.479327 -84.047791) (xy 187.435875 -83.960344)
			(xy 187.399267 -83.869817) (xy 187.369719 -83.776747) (xy 187.347406 -83.681682) (xy 187.33246 -83.585185)
			(xy 187.324968 -83.487824) (xy 187.324492 -83.439) (xy 187.324492 -83.438492) (xy 187.324985 -83.388403)
			(xy 187.332891 -83.288536) (xy 187.348638 -83.189602) (xy 187.372128 -83.092216) (xy 187.403214 -82.996982)
			(xy 187.422028 -82.950558) (xy 187.425519 -82.941086) (xy 187.425519 -82.920914) (xy 187.422028 -82.911442)
			(xy 187.403213 -82.864964) (xy 187.372103 -82.769632) (xy 187.348606 -82.672145) (xy 187.332867 -82.573109)
			(xy 187.324985 -82.47314) (xy 187.324492 -82.423) (xy 187.325038 -82.369819) (xy 187.333908 -82.263829)
			(xy 187.351603 -82.15895) (xy 187.377999 -82.055916) (xy 187.412912 -81.955448) (xy 187.456096 -81.858248)
			(xy 187.48121 -81.811368) (xy 187.487814 -81.799684) (xy 187.487306 -81.77276) (xy 187.435998 -81.685892)
			(xy 187.431198 -81.678518) (xy 187.417644 -81.667321) (xy 187.401101 -81.661369) (xy 187.39231 -81.661)
			(xy 50.654966 -81.661) (xy 50.644899 -81.660571) (xy 50.626303 -81.652847) (xy 50.618898 -81.646014)
			(xy 48.805846 -79.832962) (xy 48.799001 -79.825564) (xy 48.791273 -79.806965) (xy 48.79086 -79.796894)
			(xy 48.79086 -74.900536) (xy 48.791296 -74.890472) (xy 48.799034 -74.87189) (xy 48.805846 -74.864468)
			(xy 50.986436 -72.683878) (xy 50.993286 -72.676481) (xy 51.001022 -72.657883) (xy 51.001422 -72.64781)
			(xy 51.001422 -71.05777) (xy 51.000756 -71.046013) (xy 50.990214 -71.024984) (xy 50.971458 -71.010788)
			(xy 50.96002 -71.007986) (xy 50.843688 -70.986142) (xy 50.811684 -71.004176) (xy 50.80508 -71.021194)
			(xy 50.783008 -71.076628) (xy 50.732083 -71.184545) (xy 50.67367 -71.2886) (xy 50.608062 -71.388274)
			(xy 50.535585 -71.483071) (xy 50.4566 -71.572518) (xy 50.371501 -71.656169) (xy 50.280712 -71.733608)
			(xy 50.184685 -71.804448) (xy 50.0839 -71.868337) (xy 49.978859 -71.924955) (xy 49.870084 -71.974021)
			(xy 49.758119 -72.015291) (xy 49.643521 -72.048558) (xy 49.526861 -72.073656) (xy 49.408721 -72.090462)
			(xy 49.28969 -72.09889) (xy 49.230026 -72.099424) (xy 49.172324 -72.098932) (xy 49.05719 -72.091056)
			(xy 48.942861 -72.075342) (xy 48.829872 -72.051862) (xy 48.718748 -72.020726) (xy 48.610008 -71.98208)
			(xy 48.504159 -71.936103) (xy 48.401694 -71.883009) (xy 48.303091 -71.823048) (xy 48.20881 -71.756497)
			(xy 48.11929 -71.683667) (xy 48.03495 -71.604898) (xy 47.956181 -71.520557) (xy 47.883351 -71.431037)
			(xy 47.8168 -71.336756) (xy 47.756839 -71.238153) (xy 47.703746 -71.135688) (xy 47.657769 -71.029838)
			(xy 47.619123 -70.921098) (xy 47.587987 -70.809974) (xy 47.564508 -70.696985) (xy 47.548794 -70.582656)
			(xy 47.540918 -70.467522) (xy 47.540918 -70.352118) (xy 47.548794 -70.236984) (xy 47.564508 -70.122655)
			(xy 47.587987 -70.009666) (xy 47.619123 -69.898542) (xy 47.657769 -69.789802) (xy 47.703746 -69.683952)
			(xy 47.756839 -69.581487) (xy 47.8168 -69.482884) (xy 47.883351 -69.388603) (xy 47.956181 -69.299083)
			(xy 48.03495 -69.214742) (xy 48.11929 -69.135973) (xy 48.20881 -69.063143) (xy 48.303091 -68.996592)
			(xy 48.401694 -68.936631) (xy 48.504159 -68.883537) (xy 48.610008 -68.83756) (xy 48.718748 -68.798914)
			(xy 48.829872 -68.767778) (xy 48.942861 -68.744298) (xy 49.05719 -68.728584) (xy 49.172324 -68.720708)
			(xy 49.230026 -68.720208) (xy 49.292946 -68.720787) (xy 49.418438 -68.730152) (xy 49.542883 -68.748834)
			(xy 49.665593 -68.776731) (xy 49.785884 -68.813687) (xy 49.844706 -68.836032) (xy 49.86147 -68.842636)
			(xy 49.89576 -68.831714) (xy 49.970436 -68.71716) (xy 49.967134 -68.68541) (xy 49.96688 -68.68033)
			(xy 49.96688 -67.29349) (xy 49.967304 -67.28342) (xy 49.975019 -67.264816) (xy 49.981866 -67.257422)
			(xy 51.648614 -65.590674) (xy 51.655466 -65.583278) (xy 51.663204 -65.564679) (xy 51.6636 -65.554606)
			(xy 51.6636 -58.3946) (xy 51.459384 -58.190384) (xy 48.614584 -58.190384) (xy 48.14316 -57.71896)
			(xy 48.14316 -56.5658) (xy 47.226728 -55.649368) (xy 47.219616 -55.642002) (xy 47.20082 -55.634382)
			(xy 45.932598 -55.634382) (xy 45.922528 -55.634805) (xy 45.903922 -55.642518) (xy 45.89653 -55.649368)
			(xy 45.861986 -55.683912) (xy 45.85462 -55.691024) (xy 45.847 -55.70982) (xy 45.847 -64.3382) (xy 44.9072 -65.278)
			(xy 40.074088 -65.278) (xy 39.439088 -64.643) (xy 32.893 -64.643) (xy 32.746696 -64.789304) (xy 32.746696 -68.941696)
			(xy 34.214816 -70.409816) (xy 43.729915 -70.409816) (xy 43.733942 -70.293213) (xy 43.746004 -70.177166)
			(xy 43.766043 -70.062228) (xy 43.793965 -69.948946) (xy 43.829635 -69.83786) (xy 43.872884 -69.7295)
			(xy 43.923507 -69.624382) (xy 43.98126 -69.523007) (xy 44.045871 -69.425858) (xy 44.117029 -69.333398)
			(xy 44.194397 -69.246067) (xy 44.277606 -69.164283) (xy 44.366259 -69.088434) (xy 44.459933 -69.018882)
			(xy 44.558183 -68.955958) (xy 44.66054 -68.899962) (xy 44.766516 -68.851162) (xy 44.875607 -68.80979)
			(xy 44.987291 -68.776042) (xy 45.101038 -68.75008) (xy 45.216306 -68.732027) (xy 45.332544 -68.72197)
			(xy 45.449198 -68.719956) (xy 45.565714 -68.725995) (xy 45.681536 -68.740059) (xy 45.796111 -68.762079)
			(xy 45.908894 -68.791952) (xy 46.019348 -68.829534) (xy 46.126945 -68.874648) (xy 46.231174 -68.927077)
			(xy 46.331537 -68.986572) (xy 46.427556 -69.052849) (xy 46.518774 -69.125593) (xy 46.604756 -69.204457)
			(xy 46.685093 -69.289065) (xy 46.7594 -69.379014) (xy 46.827325 -69.473875) (xy 46.888544 -69.573196)
			(xy 46.942764 -69.676504) (xy 46.989728 -69.783307) (xy 47.029211 -69.893095) (xy 47.061026 -70.005346)
			(xy 47.085021 -70.119524) (xy 47.101081 -70.235086) (xy 47.10913 -70.35148) (xy 47.109634 -70.409816)
			(xy 47.10913 -70.468152) (xy 47.101081 -70.584546) (xy 47.085021 -70.700108) (xy 47.061026 -70.814286)
			(xy 47.029211 -70.926537) (xy 46.989728 -71.036325) (xy 46.942764 -71.143128) (xy 46.888544 -71.246436)
			(xy 46.827325 -71.345757) (xy 46.7594 -71.440618) (xy 46.685093 -71.530567) (xy 46.604756 -71.615175)
			(xy 46.518774 -71.694039) (xy 46.427556 -71.766783) (xy 46.331537 -71.83306) (xy 46.231174 -71.892555)
			(xy 46.126945 -71.944984) (xy 46.019348 -71.990098) (xy 45.908894 -72.02768) (xy 45.796111 -72.057553)
			(xy 45.681536 -72.079573) (xy 45.565714 -72.093637) (xy 45.449198 -72.099676) (xy 45.332544 -72.097662)
			(xy 45.216306 -72.087605) (xy 45.101038 -72.069552) (xy 44.987291 -72.04359) (xy 44.875607 -72.009842)
			(xy 44.766516 -71.96847) (xy 44.66054 -71.91967) (xy 44.558183 -71.863674) (xy 44.459933 -71.80075)
			(xy 44.366259 -71.731198) (xy 44.277606 -71.655349) (xy 44.194397 -71.573565) (xy 44.117029 -71.486234)
			(xy 44.045871 -71.393774) (xy 43.98126 -71.296625) (xy 43.923507 -71.19525) (xy 43.872884 -71.090132)
			(xy 43.829635 -70.981772) (xy 43.793965 -70.870686) (xy 43.766043 -70.757404) (xy 43.746004 -70.642466)
			(xy 43.733942 -70.526419) (xy 43.729915 -70.409816) (xy 34.214816 -70.409816) (xy 34.905696 -71.100696)
			(xy 34.905696 -82.0928) (xy 39.72459 -82.0928) (xy 39.728607 -81.991818) (xy 39.740636 -81.891474)
			(xy 39.760598 -81.792404) (xy 39.788369 -81.695232) (xy 39.823772 -81.600574) (xy 39.866583 -81.509028)
			(xy 39.916533 -81.421173) (xy 39.973305 -81.337564) (xy 40.03654 -81.25873) (xy 40.105839 -81.185169)
			(xy 40.180763 -81.117347) (xy 40.260839 -81.055692) (xy 40.34556 -81.000593) (xy 40.434391 -80.9524)
			(xy 40.52677 -80.911417) (xy 40.622113 -80.877903) (xy 40.719818 -80.85207) (xy 40.819266 -80.834081)
			(xy 40.919829 -80.82405) (xy 41.02087 -80.822041) (xy 41.121753 -80.828066) (xy 41.221837 -80.842086)
			(xy 41.320491 -80.864015) (xy 41.417092 -80.893712) (xy 41.511027 -80.93099) (xy 41.601704 -80.975613)
			(xy 41.688548 -81.0273) (xy 41.771012 -81.085723) (xy 41.848573 -81.150513) (xy 41.920742 -81.221261)
			(xy 41.987061 -81.297518) (xy 42.047112 -81.378804) (xy 42.100515 -81.464604) (xy 42.146933 -81.554376)
			(xy 42.186071 -81.647551) (xy 42.217683 -81.743542) (xy 42.241568 -81.841741) (xy 42.257576 -81.941527)
			(xy 42.265606 -82.042269) (xy 42.266108 -82.0928) (xy 42.265606 -82.143331) (xy 42.257576 -82.244073)
			(xy 42.241568 -82.343859) (xy 42.217683 -82.442058) (xy 42.186071 -82.538049) (xy 42.146933 -82.631224)
			(xy 42.100515 -82.720996) (xy 42.047112 -82.806796) (xy 42.029046 -82.831251) (xy 185.546978 -82.831251)
			(xy 185.546978 -82.776749) (xy 185.554734 -82.722801) (xy 185.570089 -82.670506) (xy 185.592731 -82.620929)
			(xy 185.622197 -82.575079) (xy 185.657888 -82.533888) (xy 185.699079 -82.498197) (xy 185.744929 -82.468731)
			(xy 185.794506 -82.446089) (xy 185.846801 -82.430734) (xy 185.900749 -82.422978) (xy 185.928 -82.422492)
			(xy 185.953665 -82.422884) (xy 186.004533 -82.42976) (xy 186.054017 -82.443401) (xy 186.101223 -82.46356)
			(xy 186.145296 -82.489873) (xy 186.185439 -82.521864) (xy 186.220924 -82.558952) (xy 186.236356 -82.579464)
			(xy 186.244795 -82.59024) (xy 186.266234 -82.607239) (xy 186.29141 -82.61795) (xy 186.318525 -82.621607)
			(xy 186.34564 -82.61795) (xy 186.370816 -82.607239) (xy 186.392255 -82.59024) (xy 186.400694 -82.579464)
			(xy 186.418801 -82.555609) (xy 186.461172 -82.513291) (xy 186.509637 -82.478114) (xy 186.563003 -82.450944)
			(xy 186.61996 -82.432449) (xy 186.679108 -82.423082) (xy 186.70905 -82.422492) (xy 186.736305 -82.422952)
			(xy 186.790262 -82.430703) (xy 186.842565 -82.446055) (xy 186.892152 -82.468694) (xy 186.938011 -82.498161)
			(xy 186.97921 -82.533855) (xy 187.014909 -82.575049) (xy 187.044382 -82.620904) (xy 187.067028 -82.670488)
			(xy 187.082386 -82.72279) (xy 187.090145 -82.776745) (xy 187.090145 -82.831255) (xy 187.082386 -82.88521)
			(xy 187.067028 -82.937512) (xy 187.044382 -82.987096) (xy 187.014909 -83.032951) (xy 186.97921 -83.074145)
			(xy 186.938011 -83.109839) (xy 186.892152 -83.139306) (xy 186.842565 -83.161945) (xy 186.790262 -83.177297)
			(xy 186.736305 -83.185048) (xy 186.70905 -83.185508) (xy 186.683386 -83.185079) (xy 186.63252 -83.178209)
			(xy 186.583037 -83.164574) (xy 186.535831 -83.144421) (xy 186.491758 -83.118114) (xy 186.451614 -83.086129)
			(xy 186.416127 -83.049045) (xy 186.400694 -83.028536) (xy 186.392282 -83.017716) (xy 186.370864 -83.000635)
			(xy 186.345673 -82.989867) (xy 186.318525 -82.98619) (xy 186.291377 -82.989867) (xy 186.266186 -83.000635)
			(xy 186.244768 -83.017716) (xy 186.236356 -83.028536) (xy 186.220934 -83.049053) (xy 186.185436 -83.086126)
			(xy 186.145287 -83.118104) (xy 186.101213 -83.144408) (xy 186.054008 -83.164564) (xy 186.004527 -83.178206)
			(xy 185.953664 -83.18509) (xy 185.928 -83.185508) (xy 185.900749 -83.185022) (xy 185.846801 -83.177266)
			(xy 185.794506 -83.161911) (xy 185.744929 -83.139269) (xy 185.699079 -83.109803) (xy 185.657888 -83.074112)
			(xy 185.622197 -83.032921) (xy 185.592731 -82.987071) (xy 185.570089 -82.937494) (xy 185.554734 -82.885199)
			(xy 185.546978 -82.831251) (xy 42.029046 -82.831251) (xy 41.987061 -82.888082) (xy 41.920742 -82.964339)
			(xy 41.848573 -83.035087) (xy 41.771012 -83.099877) (xy 41.688548 -83.1583) (xy 41.601704 -83.209987)
			(xy 41.511027 -83.25461) (xy 41.417092 -83.291888) (xy 41.320491 -83.321585) (xy 41.221837 -83.343514)
			(xy 41.121753 -83.357534) (xy 41.02087 -83.363559) (xy 40.919829 -83.36155) (xy 40.819266 -83.351519)
			(xy 40.719818 -83.33353) (xy 40.622113 -83.307697) (xy 40.52677 -83.274183) (xy 40.434391 -83.2332)
			(xy 40.34556 -83.185007) (xy 40.260839 -83.129908) (xy 40.180763 -83.068253) (xy 40.105839 -83.000431)
			(xy 40.03654 -82.92687) (xy 39.973305 -82.848036) (xy 39.916533 -82.764427) (xy 39.866583 -82.676572)
			(xy 39.823772 -82.585026) (xy 39.788369 -82.490368) (xy 39.760598 -82.393196) (xy 39.740636 -82.294126)
			(xy 39.728607 -82.193782) (xy 39.72459 -82.0928) (xy 34.905696 -82.0928) (xy 34.905696 -85.371249)
			(xy 185.527978 -85.371249) (xy 185.527978 -85.316751) (xy 185.535733 -85.262808) (xy 185.551085 -85.210517)
			(xy 185.573723 -85.160943) (xy 185.603185 -85.115095) (xy 185.638871 -85.073906) (xy 185.680055 -85.038215)
			(xy 185.725899 -85.008747) (xy 185.77547 -84.986103) (xy 185.827759 -84.970743) (xy 185.881701 -84.962981)
			(xy 185.90895 -84.962492) (xy 185.935553 -84.962982) (xy 185.988244 -84.970357) (xy 186.039398 -84.984984)
			(xy 186.088023 -85.00658) (xy 186.133174 -85.034725) (xy 186.173974 -85.068873) (xy 186.209632 -85.108361)
			(xy 186.224926 -85.130132) (xy 186.23326 -85.141612) (xy 186.255004 -85.159816) (xy 186.280917 -85.171334)
			(xy 186.309 -85.175274) (xy 186.337083 -85.171334) (xy 186.362996 -85.159816) (xy 186.38474 -85.141612)
			(xy 186.393074 -85.130132) (xy 186.408371 -85.108363) (xy 186.444037 -85.068884) (xy 186.48484 -85.034741)
			(xy 186.52999 -85.006596) (xy 186.578611 -84.984993) (xy 186.629761 -84.970352) (xy 186.682448 -84.962956)
			(xy 186.70905 -84.962492) (xy 186.736305 -84.962952) (xy 186.790262 -84.970703) (xy 186.842565 -84.986055)
			(xy 186.892152 -85.008694) (xy 186.938011 -85.038161) (xy 186.97921 -85.073855) (xy 187.014909 -85.115049)
			(xy 187.044382 -85.160904) (xy 187.067028 -85.210488) (xy 187.082386 -85.26279) (xy 187.090145 -85.316745)
			(xy 187.090145 -85.371255) (xy 187.082386 -85.42521) (xy 187.067028 -85.477512) (xy 187.044382 -85.527096)
			(xy 187.014909 -85.572951) (xy 186.97921 -85.614145) (xy 186.938011 -85.649839) (xy 186.892152 -85.679306)
			(xy 186.842565 -85.701945) (xy 186.790262 -85.717297) (xy 186.736305 -85.725048) (xy 186.70905 -85.725508)
			(xy 186.682447 -85.725018) (xy 186.629756 -85.717643) (xy 186.578602 -85.703016) (xy 186.529977 -85.68142)
			(xy 186.484826 -85.653275) (xy 186.444026 -85.619127) (xy 186.408368 -85.579639) (xy 186.393074 -85.557868)
			(xy 186.38474 -85.546388) (xy 186.362996 -85.528184) (xy 186.337083 -85.516666) (xy 186.309 -85.512726)
			(xy 186.280917 -85.516666) (xy 186.255004 -85.528184) (xy 186.23326 -85.546388) (xy 186.224926 -85.557868)
			(xy 186.209629 -85.579637) (xy 186.173963 -85.619116) (xy 186.13316 -85.653259) (xy 186.08801 -85.681404)
			(xy 186.039389 -85.703007) (xy 185.988239 -85.717648) (xy 185.935552 -85.725044) (xy 185.90895 -85.725508)
			(xy 185.881701 -85.725019) (xy 185.827759 -85.717257) (xy 185.77547 -85.701897) (xy 185.725899 -85.679253)
			(xy 185.680055 -85.649785) (xy 185.638871 -85.614094) (xy 185.603185 -85.572905) (xy 185.573723 -85.527057)
			(xy 185.551085 -85.477483) (xy 185.535733 -85.425192) (xy 185.527978 -85.371249) (xy 34.905696 -85.371249)
			(xy 34.905696 -89.535) (xy 176.885092 -89.535) (xy 176.885578 -89.507749) (xy 176.893334 -89.453801)
			(xy 176.908689 -89.401506) (xy 176.931331 -89.351929) (xy 176.960797 -89.306079) (xy 176.996488 -89.264888)
			(xy 177.037679 -89.229197) (xy 177.083529 -89.199731) (xy 177.133106 -89.177089) (xy 177.185401 -89.161734)
			(xy 177.239349 -89.153978) (xy 177.2666 -89.153492) (xy 177.296213 -89.154012) (xy 177.354724 -89.163185)
			(xy 177.411118 -89.181279) (xy 177.464044 -89.20786) (xy 177.512232 -89.242293) (xy 177.554528 -89.28375)
			(xy 177.57267 -89.307162) (xy 177.578512 -89.315036) (xy 177.594006 -89.324942) (xy 177.679858 -89.34196)
			(xy 177.698146 -89.338658) (xy 177.706274 -89.333832) (xy 177.748524 -89.309101) (xy 177.836155 -89.265436)
			(xy 177.926886 -89.228646) (xy 178.02018 -89.198948) (xy 178.115483 -89.17652) (xy 178.21223 -89.161493)
			(xy 178.309847 -89.153957) (xy 178.3588 -89.153492) (xy 178.408699 -89.153982) (xy 178.50819 -89.161812)
			(xy 178.606759 -89.177424) (xy 178.7038 -89.200721) (xy 178.798714 -89.231561) (xy 178.890916 -89.269752)
			(xy 178.979837 -89.315059) (xy 179.064929 -89.367204) (xy 179.145667 -89.425864) (xy 179.221554 -89.490678)
			(xy 179.292122 -89.561246) (xy 179.356936 -89.637133) (xy 179.415596 -89.717871) (xy 179.467741 -89.802963)
			(xy 179.513048 -89.891884) (xy 179.551239 -89.984086) (xy 179.582079 -90.079) (xy 179.605376 -90.176041)
			(xy 179.620988 -90.27461) (xy 179.628818 -90.374101) (xy 179.629308 -90.424) (xy 179.628802 -90.474834)
			(xy 179.620667 -90.576175) (xy 179.613052 -90.626438) (xy 179.611274 -90.638376) (xy 179.618132 -90.660728)
			(xy 179.690776 -90.736928) (xy 179.713128 -90.744802) (xy 179.725066 -90.743532) (xy 179.735886 -90.742354)
			(xy 179.757616 -90.741084) (xy 179.7685 -90.740992) (xy 179.795751 -90.741478) (xy 179.849699 -90.749234)
			(xy 179.901994 -90.764589) (xy 179.951571 -90.787231) (xy 179.997421 -90.816697) (xy 180.038612 -90.852388)
			(xy 180.074303 -90.893579) (xy 180.103769 -90.939429) (xy 180.126411 -90.989006) (xy 180.141766 -91.041301)
			(xy 180.149522 -91.095249) (xy 180.149522 -91.149751) (xy 180.141766 -91.203699) (xy 180.126411 -91.255994)
			(xy 180.103769 -91.305571) (xy 180.074303 -91.351421) (xy 180.038612 -91.392612) (xy 179.997421 -91.428303)
			(xy 179.951571 -91.457769) (xy 179.901994 -91.480411) (xy 179.849699 -91.495766) (xy 179.795751 -91.503522)
			(xy 179.7685 -91.504008) (xy 179.740302 -91.503513) (xy 179.68452 -91.495223) (xy 179.630566 -91.478811)
			(xy 179.579617 -91.454632) (xy 179.532784 -91.423215) (xy 179.491087 -91.385244) (xy 179.455436 -91.341547)
			(xy 179.440586 -91.317572) (xy 179.43449 -91.307158) (xy 179.414424 -91.294204) (xy 179.31003 -91.28252)
			(xy 179.287932 -91.290648) (xy 179.27955 -91.299284) (xy 179.243704 -91.336271) (xy 179.166916 -91.404934)
			(xy 179.084822 -91.467157) (xy 178.99796 -91.522529) (xy 178.906901 -91.570688) (xy 178.812242 -91.611317)
			(xy 178.714605 -91.64415) (xy 178.61463 -91.668972) (xy 178.512975 -91.685619) (xy 178.410305 -91.693982)
			(xy 178.3588 -91.694508) (xy 178.308901 -91.694018) (xy 178.20941 -91.686188) (xy 178.110841 -91.670576)
			(xy 178.0138 -91.647279) (xy 177.918886 -91.616439) (xy 177.826684 -91.578248) (xy 177.737763 -91.532941)
			(xy 177.652671 -91.480796) (xy 177.571933 -91.422136) (xy 177.496046 -91.357322) (xy 177.425478 -91.286754)
			(xy 177.360664 -91.210867) (xy 177.302004 -91.130129) (xy 177.249859 -91.045037) (xy 177.204552 -90.956116)
			(xy 177.166361 -90.863914) (xy 177.135521 -90.769) (xy 177.112224 -90.671959) (xy 177.096612 -90.57339)
			(xy 177.088782 -90.473899) (xy 177.088292 -90.424) (xy 177.088873 -90.370807) (xy 177.097779 -90.264794)
			(xy 177.115513 -90.159896) (xy 177.14195 -90.056846) (xy 177.158904 -90.006424) (xy 177.161952 -89.99728)
			(xy 177.161444 -89.978738) (xy 177.127408 -89.89822) (xy 177.114454 -89.885012) (xy 177.105818 -89.880948)
			(xy 177.081463 -89.869073) (xy 177.036047 -89.839524) (xy 176.99527 -89.803846) (xy 176.959953 -89.762755)
			(xy 176.930806 -89.71708) (xy 176.908416 -89.66774) (xy 176.893235 -89.615728) (xy 176.885567 -89.562091)
			(xy 176.885092 -89.535) (xy 34.905696 -89.535) (xy 34.905696 -93.091) (xy 188.74004 -93.091) (xy 188.744057 -92.990018)
			(xy 188.756086 -92.889674) (xy 188.776048 -92.790604) (xy 188.803819 -92.693432) (xy 188.839222 -92.598774)
			(xy 188.882033 -92.507228) (xy 188.931983 -92.419373) (xy 188.988755 -92.335764) (xy 189.05199 -92.25693)
			(xy 189.121289 -92.183369) (xy 189.196213 -92.115547) (xy 189.276289 -92.053892) (xy 189.36101 -91.998793)
			(xy 189.449841 -91.9506) (xy 189.54222 -91.909617) (xy 189.637563 -91.876103) (xy 189.735268 -91.85027)
			(xy 189.834716 -91.832281) (xy 189.935279 -91.82225) (xy 190.03632 -91.820241) (xy 190.137203 -91.826266)
			(xy 190.237287 -91.840286) (xy 190.335941 -91.862215) (xy 190.432542 -91.891912) (xy 190.526477 -91.92919)
			(xy 190.617154 -91.973813) (xy 190.703998 -92.0255) (xy 190.786462 -92.083923) (xy 190.864023 -92.148713)
			(xy 190.936192 -92.219461) (xy 191.002511 -92.295718) (xy 191.062562 -92.377004) (xy 191.115965 -92.462804)
			(xy 191.162383 -92.552576) (xy 191.201521 -92.645751) (xy 191.233133 -92.741742) (xy 191.257018 -92.839941)
			(xy 191.273026 -92.939727) (xy 191.281056 -93.040469) (xy 191.281558 -93.091) (xy 191.281056 -93.141531)
			(xy 191.273026 -93.242273) (xy 191.257018 -93.342059) (xy 191.233133 -93.440258) (xy 191.201521 -93.536249)
			(xy 191.162383 -93.629424) (xy 191.115965 -93.719196) (xy 191.062562 -93.804996) (xy 191.002511 -93.886282)
			(xy 190.936192 -93.962539) (xy 190.864023 -94.033287) (xy 190.786462 -94.098077) (xy 190.703998 -94.1565)
			(xy 190.617154 -94.208187) (xy 190.526477 -94.25281) (xy 190.432542 -94.290088) (xy 190.335941 -94.319785)
			(xy 190.237287 -94.341714) (xy 190.137203 -94.355734) (xy 190.03632 -94.361759) (xy 189.935279 -94.35975)
			(xy 189.834716 -94.349719) (xy 189.735268 -94.33173) (xy 189.637563 -94.305897) (xy 189.54222 -94.272383)
			(xy 189.449841 -94.2314) (xy 189.36101 -94.183207) (xy 189.276289 -94.128108) (xy 189.196213 -94.066453)
			(xy 189.121289 -93.998631) (xy 189.05199 -93.92507) (xy 188.988755 -93.846236) (xy 188.931983 -93.762627)
			(xy 188.882033 -93.674772) (xy 188.839222 -93.583226) (xy 188.803819 -93.488568) (xy 188.776048 -93.391396)
			(xy 188.756086 -93.292326) (xy 188.744057 -93.191982) (xy 188.74004 -93.091) (xy 34.905696 -93.091)
			(xy 34.905696 -93.88856) (xy 53.350375 -112.333239) (xy 140.588984 -112.333239) (xy 140.588984 -112.202761)
			(xy 140.596862 -112.072522) (xy 140.61259 -111.942997) (xy 140.636109 -111.814657) (xy 140.667334 -111.687971)
			(xy 140.706151 -111.563402) (xy 140.752419 -111.441403) (xy 140.805969 -111.322421) (xy 140.866605 -111.20689)
			(xy 140.934105 -111.09523) (xy 141.008225 -110.987849) (xy 141.088692 -110.88514) (xy 141.175215 -110.787476)
			(xy 141.267476 -110.695215) (xy 141.36514 -110.608692) (xy 141.467849 -110.528225) (xy 141.57523 -110.454105)
			(xy 141.68689 -110.386605) (xy 141.802421 -110.325969) (xy 141.921403 -110.272419) (xy 142.043402 -110.226151)
			(xy 142.167971 -110.187334) (xy 142.294657 -110.156109) (xy 142.422997 -110.13259) (xy 142.552522 -110.116862)
			(xy 142.682761 -110.108984) (xy 142.748 -110.108492) (xy 142.748508 -110.108492) (xy 142.826191 -110.109198)
			(xy 142.981155 -110.120384) (xy 143.058134 -110.130844) (xy 143.061802 -110.131314) (xy 143.069198 -110.131314)
			(xy 143.072866 -110.130844) (xy 143.149844 -110.120377) (xy 143.304808 -110.109193) (xy 143.382492 -110.108492)
			(xy 143.383 -110.108492) (xy 143.448239 -110.108984) (xy 143.578478 -110.116862) (xy 143.708003 -110.13259)
			(xy 143.836343 -110.156109) (xy 143.963029 -110.187334) (xy 144.087598 -110.226151) (xy 144.209597 -110.272419)
			(xy 144.328579 -110.325969) (xy 144.44411 -110.386605) (xy 144.55577 -110.454105) (xy 144.663151 -110.528225)
			(xy 144.76586 -110.608692) (xy 144.863524 -110.695215) (xy 144.955785 -110.787476) (xy 145.042308 -110.88514)
			(xy 145.122775 -110.987849) (xy 145.196895 -111.09523) (xy 145.264395 -111.20689) (xy 145.325031 -111.322421)
			(xy 145.378581 -111.441403) (xy 145.424849 -111.563402) (xy 145.463666 -111.687971) (xy 145.494891 -111.814657)
			(xy 145.51841 -111.942997) (xy 145.534138 -112.072522) (xy 145.542016 -112.202761) (xy 145.542016 -112.333239)
			(xy 145.534138 -112.463478) (xy 145.51841 -112.593003) (xy 145.494891 -112.721343) (xy 145.463666 -112.848029)
			(xy 145.424849 -112.972598) (xy 145.378581 -113.094597) (xy 145.325031 -113.213579) (xy 145.264395 -113.32911)
			(xy 145.196895 -113.44077) (xy 145.122775 -113.548151) (xy 145.042308 -113.65086) (xy 144.955785 -113.748524)
			(xy 144.863524 -113.840785) (xy 144.76586 -113.927308) (xy 144.663151 -114.007775) (xy 144.55577 -114.081895)
			(xy 144.44411 -114.149395) (xy 144.328579 -114.210031) (xy 144.209597 -114.263581) (xy 144.087598 -114.309849)
			(xy 143.963029 -114.348666) (xy 143.836343 -114.379891) (xy 143.708003 -114.40341) (xy 143.578478 -114.419138)
			(xy 143.448239 -114.427016) (xy 143.383 -114.427508) (xy 143.382492 -114.427508) (xy 143.304809 -114.426802)
			(xy 143.149845 -114.415616) (xy 143.072866 -114.405156) (xy 143.069198 -114.404686) (xy 143.061802 -114.404686)
			(xy 143.058134 -114.405156) (xy 142.981156 -114.415623) (xy 142.826192 -114.426807) (xy 142.748508 -114.427508)
			(xy 142.748 -114.427508) (xy 142.682761 -114.427016) (xy 142.552522 -114.419138) (xy 142.422997 -114.40341)
			(xy 142.294657 -114.379891) (xy 142.167971 -114.348666) (xy 142.043402 -114.309849) (xy 141.921403 -114.263581)
			(xy 141.802421 -114.210031) (xy 141.68689 -114.149395) (xy 141.57523 -114.081895) (xy 141.467849 -114.007775)
			(xy 141.36514 -113.927308) (xy 141.267476 -113.840785) (xy 141.175215 -113.748524) (xy 141.088692 -113.65086)
			(xy 141.008225 -113.548151) (xy 140.934105 -113.44077) (xy 140.866605 -113.32911) (xy 140.805969 -113.213579)
			(xy 140.752419 -113.094597) (xy 140.706151 -112.972598) (xy 140.667334 -112.848029) (xy 140.636109 -112.721343)
			(xy 140.61259 -112.593003) (xy 140.596862 -112.463478) (xy 140.588984 -112.333239) (xy 53.350375 -112.333239)
			(xy 56.270906 -115.25377) (xy 56.278303 -115.260619) (xy 56.296902 -115.268356) (xy 56.306974 -115.268756)
		)
		(stroke
			(width 0)
			(type solid)
		)
		(fill yes)
		(layer "F.Cu")
		(net "GND")
	)
	(gr_poly
		(pts
			(xy 221.766892 -145.000726) (xy 221.776963 -145.000305) (xy 221.795572 -144.992596) (xy 221.80296 -144.98574)
			(xy 222.65132 -144.13738) (xy 222.657715 -144.130445) (xy 222.665316 -144.113194) (xy 222.666168 -144.094361)
			(xy 222.663512 -144.08531) (xy 222.630238 -143.985234) (xy 222.60814 -143.966946) (xy 222.593662 -143.964914)
			(xy 222.529208 -143.955267) (xy 222.401545 -143.92899) (xy 222.27576 -143.894833) (xy 222.152341 -143.852927)
			(xy 222.031764 -143.803434) (xy 221.914494 -143.746545) (xy 221.800986 -143.68248) (xy 221.691677 -143.611487)
			(xy 221.58699 -143.53384) (xy 221.48733 -143.449838) (xy 221.393081 -143.359807) (xy 221.304607 -143.264095)
			(xy 221.222251 -143.16307) (xy 221.146331 -143.057125) (xy 221.077139 -142.946666) (xy 221.014944 -142.832123)
			(xy 220.959986 -142.713936) (xy 220.912477 -142.592564) (xy 220.8726 -142.468474) (xy 220.84051 -142.342146)
			(xy 220.81633 -142.214069) (xy 220.800154 -142.084737) (xy 220.792045 -141.95465) (xy 220.791532 -141.88948)
			(xy 220.792031 -141.824554) (xy 220.800071 -141.694952) (xy 220.816118 -141.566095) (xy 220.840112 -141.438479)
			(xy 220.87196 -141.312594) (xy 220.911539 -141.188921) (xy 220.958699 -141.067936) (xy 221.013258 -140.950102)
			(xy 221.075007 -140.835872) (xy 221.143709 -140.725683) (xy 221.2191 -140.619959) (xy 221.300892 -140.519105)
			(xy 221.38877 -140.423507) (xy 221.482398 -140.333533) (xy 221.581416 -140.249528) (xy 221.685444 -140.171813)
			(xy 221.794084 -140.100688) (xy 221.906919 -140.036424) (xy 222.023515 -139.979269) (xy 222.143426 -139.929441)
			(xy 222.266192 -139.887132) (xy 222.391341 -139.852504) (xy 222.518394 -139.825689) (xy 222.646864 -139.806792)
			(xy 222.711518 -139.800838) (xy 222.720903 -139.799638) (xy 222.737867 -139.791285) (xy 222.750655 -139.777358)
			(xy 222.757533 -139.759745) (xy 222.758 -139.750292) (xy 222.758 -117.724682) (xy 222.757573 -117.714613)
			(xy 222.749854 -117.696014) (xy 222.743014 -117.688614) (xy 222.228664 -117.174264) (xy 38.092634 -117.174264)
			(xy 38.082571 -117.174701) (xy 38.06399 -117.182439) (xy 38.056566 -117.18925) (xy 37.546788 -117.698774)
			(xy 37.539944 -117.706172) (xy 37.532222 -117.724772) (xy 37.531802 -117.734842) (xy 37.531802 -121.209816)
			(xy 46.142915 -121.209816) (xy 46.146941 -121.052186) (xy 46.159012 -120.894968) (xy 46.179094 -120.738571)
			(xy 46.207136 -120.583403) (xy 46.243064 -120.42987) (xy 46.286785 -120.278371) (xy 46.338184 -120.129302)
			(xy 46.397128 -119.983053) (xy 46.463463 -119.840003) (xy 46.537015 -119.700528) (xy 46.617593 -119.56499)
			(xy 46.704987 -119.433743) (xy 46.798968 -119.30713) (xy 46.899291 -119.185481) (xy 47.005696 -119.069113)
			(xy 47.117903 -118.958329) (xy 47.23562 -118.85342) (xy 47.358541 -118.754658) (xy 47.486344 -118.662302)
			(xy 47.618696 -118.576591) (xy 47.755252 -118.497751) (xy 47.895655 -118.425986) (xy 48.03954 -118.361483)
			(xy 48.18653 -118.304412) (xy 48.336243 -118.25492) (xy 48.488288 -118.213138) (xy 48.642267 -118.179173)
			(xy 48.797781 -118.153115) (xy 48.954421 -118.135032) (xy 49.111781 -118.12497) (xy 49.26945 -118.122956)
			(xy 49.427015 -118.128996) (xy 49.584067 -118.143073) (xy 49.740194 -118.165151) (xy 49.894991 -118.195172)
			(xy 50.048053 -118.233058) (xy 50.198981 -118.27871) (xy 50.347381 -118.332009) (xy 50.492866 -118.392816)
			(xy 50.635057 -118.460972) (xy 50.773582 -118.536299) (xy 50.90808 -118.618601) (xy 51.0382 -118.707664)
			(xy 51.163602 -118.803254) (xy 51.283961 -118.905123) (xy 51.39896 -119.013004) (xy 51.508302 -119.126617)
			(xy 51.611699 -119.245665) (xy 51.708883 -119.369836) (xy 51.7996 -119.498808) (xy 51.883613 -119.632244)
			(xy 51.960704 -119.769796) (xy 52.03067 -119.911104) (xy 52.093329 -120.055801) (xy 52.148519 -120.203508)
			(xy 52.196095 -120.353841) (xy 52.235932 -120.506407) (xy 52.267928 -120.660808) (xy 52.291998 -120.816641)
			(xy 52.308079 -120.9735) (xy 52.316131 -121.130975) (xy 52.316634 -121.209816) (xy 53.763418 -121.209816)
			(xy 53.763913 -121.131611) (xy 53.771835 -120.975403) (xy 53.787659 -120.819796) (xy 53.811344 -120.66519)
			(xy 53.842829 -120.511982) (xy 53.882033 -120.360566) (xy 53.928856 -120.211329) (xy 53.983178 -120.064656)
			(xy 54.044859 -119.920923) (xy 54.113741 -119.780497) (xy 54.189647 -119.643741) (xy 54.272382 -119.511005)
			(xy 54.361733 -119.38263) (xy 54.457472 -119.258946) (xy 54.559353 -119.140269) (xy 54.667114 -119.026904)
			(xy 54.780479 -118.919143) (xy 54.899156 -118.817262) (xy 55.02284 -118.721523) (xy 55.151215 -118.632172)
			(xy 55.283951 -118.549437) (xy 55.420707 -118.473531) (xy 55.561133 -118.404649) (xy 55.704866 -118.342968)
			(xy 55.851539 -118.288646) (xy 56.000776 -118.241823) (xy 56.152192 -118.202619) (xy 56.3054 -118.171134)
			(xy 56.460006 -118.147449) (xy 56.615613 -118.131625) (xy 56.771821 -118.123703) (xy 56.928231 -118.123703)
			(xy 57.084439 -118.131625) (xy 57.240046 -118.147449) (xy 57.394652 -118.171134) (xy 57.54786 -118.202619)
			(xy 57.699276 -118.241823) (xy 57.848513 -118.288646) (xy 57.995186 -118.342968) (xy 58.138919 -118.404649)
			(xy 58.279345 -118.473531) (xy 58.416101 -118.549437) (xy 58.548837 -118.632172) (xy 58.677212 -118.721523)
			(xy 58.800896 -118.817262) (xy 58.919573 -118.919143) (xy 59.032938 -119.026904) (xy 59.140699 -119.140269)
			(xy 59.24258 -119.258946) (xy 59.338319 -119.38263) (xy 59.42767 -119.511005) (xy 59.510405 -119.643741)
			(xy 59.586311 -119.780497) (xy 59.655193 -119.920923) (xy 59.716874 -120.064656) (xy 59.771196 -120.211329)
			(xy 59.818019 -120.360566) (xy 59.857223 -120.511982) (xy 59.888708 -120.66519) (xy 59.912393 -120.819796)
			(xy 59.928217 -120.975403) (xy 59.936139 -121.131611) (xy 59.936634 -121.209816) (xy 59.936122 -121.289927)
			(xy 59.927799 -121.449933) (xy 59.911187 -121.609291) (xy 59.886331 -121.767573) (xy 59.853297 -121.924353)
			(xy 59.812175 -122.079208) (xy 59.763075 -122.231721) (xy 59.70613 -122.381481) (xy 59.701746 -122.391424)
			(xy 63.161672 -122.391424) (xy 63.161672 -120.028716) (xy 63.162248 -120.012024) (xy 63.170873 -119.979775)
			(xy 63.187542 -119.950851) (xy 63.21112 -119.927219) (xy 63.240006 -119.910485) (xy 63.272236 -119.901786)
			(xy 63.288926 -119.901208) (xy 65.651126 -119.901208) (xy 65.667785 -119.901764) (xy 65.699969 -119.910381)
			(xy 65.728833 -119.927021) (xy 65.752416 -119.950555) (xy 65.769117 -119.979385) (xy 65.777801 -120.011551)
			(xy 65.77838 -120.028208) (xy 65.77838 -121.209816) (xy 86.142835 -121.209816) (xy 86.146861 -121.052186)
			(xy 86.158932 -120.894968) (xy 86.179014 -120.738571) (xy 86.207056 -120.583403) (xy 86.242984 -120.42987)
			(xy 86.286705 -120.278371) (xy 86.338104 -120.129302) (xy 86.397048 -119.983053) (xy 86.463383 -119.840003)
			(xy 86.536935 -119.700528) (xy 86.617513 -119.56499) (xy 86.704907 -119.433743) (xy 86.798888 -119.30713)
			(xy 86.899211 -119.185481) (xy 87.005616 -119.069113) (xy 87.117823 -118.958329) (xy 87.23554 -118.85342)
			(xy 87.358461 -118.754658) (xy 87.486264 -118.662302) (xy 87.618616 -118.576591) (xy 87.755172 -118.497751)
			(xy 87.895575 -118.425986) (xy 88.03946 -118.361483) (xy 88.18645 -118.304412) (xy 88.336163 -118.25492)
			(xy 88.488208 -118.213138) (xy 88.642187 -118.179173) (xy 88.797701 -118.153115) (xy 88.954341 -118.135032)
			(xy 89.111701 -118.12497) (xy 89.26937 -118.122956) (xy 89.426935 -118.128996) (xy 89.583987 -118.143073)
			(xy 89.740114 -118.165151) (xy 89.894911 -118.195172) (xy 90.047973 -118.233058) (xy 90.198901 -118.27871)
			(xy 90.347301 -118.332009) (xy 90.492786 -118.392816) (xy 90.634977 -118.460972) (xy 90.773502 -118.536299)
			(xy 90.908 -118.618601) (xy 91.03812 -118.707664) (xy 91.163522 -118.803254) (xy 91.283881 -118.905123)
			(xy 91.39888 -119.013004) (xy 91.508222 -119.126617) (xy 91.611619 -119.245665) (xy 91.708803 -119.369836)
			(xy 91.79952 -119.498808) (xy 91.883533 -119.632244) (xy 91.960624 -119.769796) (xy 92.03059 -119.911104)
			(xy 92.093249 -120.055801) (xy 92.148439 -120.203508) (xy 92.196015 -120.353841) (xy 92.235852 -120.506407)
			(xy 92.267848 -120.660808) (xy 92.291918 -120.816641) (xy 92.307999 -120.9735) (xy 92.316051 -121.130975)
			(xy 92.316554 -121.209816) (xy 93.763338 -121.209816) (xy 93.763833 -121.131611) (xy 93.771755 -120.975403)
			(xy 93.787579 -120.819796) (xy 93.811264 -120.66519) (xy 93.842749 -120.511982) (xy 93.881953 -120.360566)
			(xy 93.928776 -120.211329) (xy 93.983098 -120.064656) (xy 94.044779 -119.920923) (xy 94.113661 -119.780497)
			(xy 94.189567 -119.643741) (xy 94.272302 -119.511005) (xy 94.361653 -119.38263) (xy 94.457392 -119.258946)
			(xy 94.559273 -119.140269) (xy 94.667034 -119.026904) (xy 94.780399 -118.919143) (xy 94.899076 -118.817262)
			(xy 95.02276 -118.721523) (xy 95.151135 -118.632172) (xy 95.283871 -118.549437) (xy 95.420627 -118.473531)
			(xy 95.561053 -118.404649) (xy 95.704786 -118.342968) (xy 95.851459 -118.288646) (xy 96.000696 -118.241823)
			(xy 96.152112 -118.202619) (xy 96.30532 -118.171134) (xy 96.459926 -118.147449) (xy 96.615533 -118.131625)
			(xy 96.771741 -118.123703) (xy 96.928151 -118.123703) (xy 97.084359 -118.131625) (xy 97.239966 -118.147449)
			(xy 97.394572 -118.171134) (xy 97.54778 -118.202619) (xy 97.699196 -118.241823) (xy 97.848433 -118.288646)
			(xy 97.995106 -118.342968) (xy 98.138839 -118.404649) (xy 98.279265 -118.473531) (xy 98.416021 -118.549437)
			(xy 98.548757 -118.632172) (xy 98.677132 -118.721523) (xy 98.800816 -118.817262) (xy 98.919493 -118.919143)
			(xy 99.032858 -119.026904) (xy 99.140619 -119.140269) (xy 99.2425 -119.258946) (xy 99.338239 -119.38263)
			(xy 99.42759 -119.511005) (xy 99.510325 -119.643741) (xy 99.586231 -119.780497) (xy 99.655113 -119.920923)
			(xy 99.716794 -120.064656) (xy 99.771116 -120.211329) (xy 99.817939 -120.360566) (xy 99.857143 -120.511982)
			(xy 99.888628 -120.66519) (xy 99.912313 -120.819796) (xy 99.928137 -120.975403) (xy 99.936059 -121.131611)
			(xy 99.936554 -121.209816) (xy 99.936096 -121.289928) (xy 99.927773 -121.449935) (xy 99.911161 -121.609295)
			(xy 99.886304 -121.767579) (xy 99.853269 -121.924361) (xy 99.812146 -122.079217) (xy 99.763044 -122.231732)
			(xy 99.706097 -122.381494) (xy 99.701719 -122.391424) (xy 103.161592 -122.391424) (xy 103.161592 -120.028716)
			(xy 103.162148 -120.012023) (xy 103.170775 -119.97977) (xy 103.187447 -119.950845) (xy 103.21103 -119.927212)
			(xy 103.23992 -119.910479) (xy 103.272154 -119.901784) (xy 103.288846 -119.901208) (xy 105.651046 -119.901208)
			(xy 105.667705 -119.901747) (xy 105.69989 -119.910368) (xy 105.728754 -119.927012) (xy 105.752337 -119.95055)
			(xy 105.769037 -119.979382) (xy 105.777721 -120.01155) (xy 105.7783 -120.028208) (xy 105.7783 -121.209816)
			(xy 126.143009 -121.209816) (xy 126.147035 -121.052186) (xy 126.159106 -120.894968) (xy 126.179188 -120.738571)
			(xy 126.20723 -120.583403) (xy 126.243158 -120.42987) (xy 126.286879 -120.278371) (xy 126.338278 -120.129302)
			(xy 126.397222 -119.983053) (xy 126.463557 -119.840003) (xy 126.537109 -119.700528) (xy 126.617687 -119.56499)
			(xy 126.705081 -119.433743) (xy 126.799062 -119.30713) (xy 126.899385 -119.185481) (xy 127.00579 -119.069113)
			(xy 127.117997 -118.958329) (xy 127.235714 -118.85342) (xy 127.358635 -118.754658) (xy 127.486438 -118.662302)
			(xy 127.61879 -118.576591) (xy 127.755346 -118.497751) (xy 127.895749 -118.425986) (xy 128.039634 -118.361483)
			(xy 128.186624 -118.304412) (xy 128.336337 -118.25492) (xy 128.488382 -118.213138) (xy 128.642361 -118.179173)
			(xy 128.797875 -118.153115) (xy 128.954515 -118.135032) (xy 129.111875 -118.12497) (xy 129.269544 -118.122956)
			(xy 129.427109 -118.128996) (xy 129.584161 -118.143073) (xy 129.740288 -118.165151) (xy 129.895085 -118.195172)
			(xy 130.048147 -118.233058) (xy 130.199075 -118.27871) (xy 130.347475 -118.332009) (xy 130.49296 -118.392816)
			(xy 130.635151 -118.460972) (xy 130.773676 -118.536299) (xy 130.908174 -118.618601) (xy 131.038294 -118.707664)
			(xy 131.163696 -118.803254) (xy 131.284055 -118.905123) (xy 131.399054 -119.013004) (xy 131.508396 -119.126617)
			(xy 131.611793 -119.245665) (xy 131.708977 -119.369836) (xy 131.799694 -119.498808) (xy 131.883707 -119.632244)
			(xy 131.960798 -119.769796) (xy 132.030764 -119.911104) (xy 132.093423 -120.055801) (xy 132.148613 -120.203508)
			(xy 132.196189 -120.353841) (xy 132.236026 -120.506407) (xy 132.268022 -120.660808) (xy 132.292092 -120.816641)
			(xy 132.308173 -120.9735) (xy 132.316225 -121.130975) (xy 132.316728 -121.209816) (xy 133.763512 -121.209816)
			(xy 133.764007 -121.131611) (xy 133.771929 -120.975403) (xy 133.787753 -120.819796) (xy 133.811438 -120.66519)
			(xy 133.842923 -120.511982) (xy 133.882127 -120.360566) (xy 133.92895 -120.211329) (xy 133.983272 -120.064656)
			(xy 134.044953 -119.920923) (xy 134.113835 -119.780497) (xy 134.189741 -119.643741) (xy 134.272476 -119.511005)
			(xy 134.361827 -119.38263) (xy 134.457566 -119.258946) (xy 134.559447 -119.140269) (xy 134.667208 -119.026904)
			(xy 134.780573 -118.919143) (xy 134.89925 -118.817262) (xy 135.022934 -118.721523) (xy 135.151309 -118.632172)
			(xy 135.284045 -118.549437) (xy 135.420801 -118.473531) (xy 135.561227 -118.404649) (xy 135.70496 -118.342968)
			(xy 135.851633 -118.288646) (xy 136.00087 -118.241823) (xy 136.152286 -118.202619) (xy 136.305494 -118.171134)
			(xy 136.4601 -118.147449) (xy 136.615707 -118.131625) (xy 136.771915 -118.123703) (xy 136.928325 -118.123703)
			(xy 137.084533 -118.131625) (xy 137.24014 -118.147449) (xy 137.394746 -118.171134) (xy 137.547954 -118.202619)
			(xy 137.69937 -118.241823) (xy 137.848607 -118.288646) (xy 137.99528 -118.342968) (xy 138.139013 -118.404649)
			(xy 138.279439 -118.473531) (xy 138.416195 -118.549437) (xy 138.548931 -118.632172) (xy 138.677306 -118.721523)
			(xy 138.80099 -118.817262) (xy 138.919667 -118.919143) (xy 139.033032 -119.026904) (xy 139.140793 -119.140269)
			(xy 139.242674 -119.258946) (xy 139.338413 -119.38263) (xy 139.427764 -119.511005) (xy 139.510499 -119.643741)
			(xy 139.586405 -119.780497) (xy 139.655287 -119.920923) (xy 139.716968 -120.064656) (xy 139.77129 -120.211329)
			(xy 139.818113 -120.360566) (xy 139.857317 -120.511982) (xy 139.888802 -120.66519) (xy 139.912487 -120.819796)
			(xy 139.928311 -120.975403) (xy 139.936233 -121.131611) (xy 139.936728 -121.209816) (xy 139.93622 -121.289927)
			(xy 139.927897 -121.449933) (xy 139.911285 -121.609291) (xy 139.886429 -121.767574) (xy 139.853395 -121.924353)
			(xy 139.812273 -122.079208) (xy 139.763173 -122.231721) (xy 139.706227 -122.381482) (xy 139.702068 -122.390916)
			(xy 143.161512 -122.390916) (xy 143.161512 -120.028716) (xy 143.162003 -120.011994) (xy 143.170656 -119.979688)
			(xy 143.187378 -119.950724) (xy 143.211027 -119.927075) (xy 143.239992 -119.910355) (xy 143.272298 -119.901702)
			(xy 143.28902 -119.901208) (xy 145.65122 -119.901208) (xy 145.667937 -119.90172) (xy 145.700231 -119.910379)
			(xy 145.729184 -119.9271) (xy 145.752822 -119.950745) (xy 145.769535 -119.979702) (xy 145.778184 -120.011999)
			(xy 145.778728 -120.028716) (xy 145.778728 -121.209816) (xy 166.143183 -121.209816) (xy 166.147209 -121.052186)
			(xy 166.15928 -120.894968) (xy 166.179362 -120.738571) (xy 166.207404 -120.583403) (xy 166.243332 -120.42987)
			(xy 166.287053 -120.278371) (xy 166.338452 -120.129302) (xy 166.397396 -119.983053) (xy 166.463731 -119.840003)
			(xy 166.537283 -119.700528) (xy 166.617861 -119.56499) (xy 166.705255 -119.433743) (xy 166.799236 -119.30713)
			(xy 166.899559 -119.185481) (xy 167.005964 -119.069113) (xy 167.118171 -118.958329) (xy 167.235888 -118.85342)
			(xy 167.358809 -118.754658) (xy 167.486612 -118.662302) (xy 167.618964 -118.576591) (xy 167.75552 -118.497751)
			(xy 167.895923 -118.425986) (xy 168.039808 -118.361483) (xy 168.186798 -118.304412) (xy 168.336511 -118.25492)
			(xy 168.488556 -118.213138) (xy 168.642535 -118.179173) (xy 168.798049 -118.153115) (xy 168.954689 -118.135032)
			(xy 169.112049 -118.12497) (xy 169.269718 -118.122956) (xy 169.427283 -118.128996) (xy 169.584335 -118.143073)
			(xy 169.740462 -118.165151) (xy 169.895259 -118.195172) (xy 170.048321 -118.233058) (xy 170.199249 -118.27871)
			(xy 170.347649 -118.332009) (xy 170.493134 -118.392816) (xy 170.635325 -118.460972) (xy 170.77385 -118.536299)
			(xy 170.908348 -118.618601) (xy 171.038468 -118.707664) (xy 171.16387 -118.803254) (xy 171.284229 -118.905123)
			(xy 171.399228 -119.013004) (xy 171.50857 -119.126617) (xy 171.611967 -119.245665) (xy 171.709151 -119.369836)
			(xy 171.799868 -119.498808) (xy 171.883881 -119.632244) (xy 171.960972 -119.769796) (xy 172.030938 -119.911104)
			(xy 172.093597 -120.055801) (xy 172.148787 -120.203508) (xy 172.196363 -120.353841) (xy 172.2362 -120.506407)
			(xy 172.268196 -120.660808) (xy 172.292266 -120.816641) (xy 172.308347 -120.9735) (xy 172.316399 -121.130975)
			(xy 172.316902 -121.209816) (xy 173.763686 -121.209816) (xy 173.764181 -121.131611) (xy 173.772103 -120.975403)
			(xy 173.787927 -120.819796) (xy 173.811612 -120.66519) (xy 173.843097 -120.511982) (xy 173.882301 -120.360566)
			(xy 173.929124 -120.211329) (xy 173.983446 -120.064656) (xy 174.045127 -119.920923) (xy 174.114009 -119.780497)
			(xy 174.189915 -119.643741) (xy 174.27265 -119.511005) (xy 174.362001 -119.38263) (xy 174.45774 -119.258946)
			(xy 174.559621 -119.140269) (xy 174.667382 -119.026904) (xy 174.780747 -118.919143) (xy 174.899424 -118.817262)
			(xy 175.023108 -118.721523) (xy 175.151483 -118.632172) (xy 175.284219 -118.549437) (xy 175.420975 -118.473531)
			(xy 175.561401 -118.404649) (xy 175.705134 -118.342968) (xy 175.851807 -118.288646) (xy 176.001044 -118.241823)
			(xy 176.15246 -118.202619) (xy 176.305668 -118.171134) (xy 176.460274 -118.147449) (xy 176.615881 -118.131625)
			(xy 176.772089 -118.123703) (xy 176.928499 -118.123703) (xy 177.084707 -118.131625) (xy 177.240314 -118.147449)
			(xy 177.39492 -118.171134) (xy 177.548128 -118.202619) (xy 177.699544 -118.241823) (xy 177.848781 -118.288646)
			(xy 177.995454 -118.342968) (xy 178.139187 -118.404649) (xy 178.279613 -118.473531) (xy 178.416369 -118.549437)
			(xy 178.549105 -118.632172) (xy 178.67748 -118.721523) (xy 178.801164 -118.817262) (xy 178.919841 -118.919143)
			(xy 179.033206 -119.026904) (xy 179.140967 -119.140269) (xy 179.242848 -119.258946) (xy 179.338587 -119.38263)
			(xy 179.427938 -119.511005) (xy 179.510673 -119.643741) (xy 179.586579 -119.780497) (xy 179.655461 -119.920923)
			(xy 179.717142 -120.064656) (xy 179.771464 -120.211329) (xy 179.818287 -120.360566) (xy 179.857491 -120.511982)
			(xy 179.888976 -120.66519) (xy 179.912661 -120.819796) (xy 179.928485 -120.975403) (xy 179.936407 -121.131611)
			(xy 179.936902 -121.209816) (xy 179.936411 -121.289927) (xy 179.928088 -121.449934) (xy 179.911476 -121.609293)
			(xy 179.88662 -121.767576) (xy 179.853586 -121.924356) (xy 179.812463 -122.079211) (xy 179.763363 -122.231725)
			(xy 179.706417 -122.381486) (xy 179.702035 -122.391424) (xy 183.16194 -122.391424) (xy 183.16194 -120.028716)
			(xy 183.162449 -120.012019) (xy 183.17108 -119.979759) (xy 183.187759 -119.950829) (xy 183.211352 -119.927195)
			(xy 183.240253 -119.910465) (xy 183.272498 -119.901778) (xy 183.289194 -119.901208) (xy 185.651394 -119.901208)
			(xy 185.668051 -119.901792) (xy 185.700234 -119.910401) (xy 185.729098 -119.927035) (xy 185.752683 -119.950564)
			(xy 185.769384 -119.97939) (xy 185.778069 -120.011552) (xy 185.778648 -120.028208) (xy 185.778648 -122.390916)
			(xy 185.77808 -122.407607) (xy 185.769449 -122.439855) (xy 185.752777 -122.468777) (xy 185.729198 -122.492407)
			(xy 185.700313 -122.509142) (xy 185.668084 -122.517843) (xy 185.651394 -122.518424) (xy 183.289194 -122.518424)
			(xy 183.272531 -122.517917) (xy 183.240337 -122.5093) (xy 183.211466 -122.492653) (xy 183.187881 -122.469107)
			(xy 183.171184 -122.440265) (xy 183.162511 -122.408086) (xy 183.16194 -122.391424) (xy 179.702035 -122.391424)
			(xy 179.641778 -122.528092) (xy 179.569622 -122.671147) (xy 179.490141 -122.810266) (xy 179.403551 -122.945075)
			(xy 179.310084 -123.07521) (xy 179.209992 -123.200321) (xy 179.103544 -123.320072) (xy 178.991028 -123.43414)
			(xy 178.872746 -123.542217) (xy 178.749016 -123.644012) (xy 178.620173 -123.739252) (xy 178.486562 -123.82768)
			(xy 178.348544 -123.909057) (xy 178.20649 -123.983166) (xy 178.060783 -124.049805) (xy 177.911816 -124.108796)
			(xy 177.836068 -124.13488) (xy 177.818288 -124.140722) (xy 177.799238 -124.172726) (xy 177.818288 -124.28982)
			(xy 177.820119 -124.298598) (xy 177.828945 -124.314194) (xy 177.842577 -124.325825) (xy 177.859369 -124.332084)
			(xy 177.868326 -124.332492) (xy 179.83327 -124.332492) (xy 179.843341 -124.332909) (xy 179.86194 -124.340633)
			(xy 179.869338 -124.347478) (xy 181.082442 -125.560836) (xy 181.089296 -125.568225) (xy 181.097006 -125.586833)
			(xy 181.097428 -125.596904) (xy 181.097428 -132.594096) (xy 181.097019 -132.604168) (xy 181.089289 -132.622766)
			(xy 181.082442 -132.630164) (xy 180.838145 -132.874512) (xy 188.214 -132.874512) (xy 188.214 -125.316488)
			(xy 189.051438 -124.47905) (xy 189.057542 -124.475397) (xy 189.067597 -124.465342) (xy 189.07125 -124.459238)
			(xy 189.18301 -124.347478) (xy 189.19041 -124.340638) (xy 189.209009 -124.332919) (xy 189.219078 -124.332492)
			(xy 192.02527 -124.332492) (xy 192.035341 -124.332909) (xy 192.05394 -124.340633) (xy 192.061338 -124.347478)
			(xy 193.274696 -125.560836) (xy 193.281365 -125.568255) (xy 193.288946 -125.586686) (xy 193.289428 -125.59665)
			(xy 193.289428 -132.59435) (xy 193.288945 -132.604316) (xy 193.281375 -132.622753) (xy 193.274696 -132.630164)
			(xy 192.061338 -133.843522) (xy 192.053922 -133.850341) (xy 192.035335 -133.858073) (xy 192.02527 -133.858508)
			(xy 189.219078 -133.858508) (xy 189.209004 -133.858118) (xy 189.190405 -133.850375) (xy 189.18301 -133.843522)
			(xy 188.214 -132.874512) (xy 180.838145 -132.874512) (xy 179.869338 -133.843522) (xy 179.861922 -133.850341)
			(xy 179.843335 -133.858073) (xy 179.83327 -133.858508) (xy 177.027078 -133.858508) (xy 177.017004 -133.858118)
			(xy 176.998405 -133.850375) (xy 176.99101 -133.843522) (xy 176.022 -132.874258) (xy 176.022 -125.316742)
			(xy 176.86909 -124.469398) (xy 176.875808 -124.462026) (xy 176.883457 -124.443624) (xy 176.883559 -124.423696)
			(xy 176.880266 -124.41428) (xy 176.84496 -124.327666) (xy 176.840892 -124.31867) (xy 176.827166 -124.304504)
			(xy 176.80909 -124.296607) (xy 176.79924 -124.295916) (xy 176.798732 -124.295916) (xy 176.721376 -124.294212)
			(xy 176.566975 -124.283881) (xy 176.413285 -124.265826) (xy 176.260693 -124.240091) (xy 176.109582 -124.206742)
			(xy 175.960332 -124.165862) (xy 175.813319 -124.117555) (xy 175.668911 -124.06194) (xy 175.527472 -123.999159)
			(xy 175.389356 -123.929369) (xy 175.254911 -123.852745) (xy 175.124475 -123.769481) (xy 174.998376 -123.679784)
			(xy 174.87693 -123.58388) (xy 174.760442 -123.482012) (xy 174.649206 -123.374433) (xy 174.543501 -123.261416)
			(xy 174.443592 -123.143243) (xy 174.34973 -123.020212) (xy 174.262152 -122.892632) (xy 174.181078 -122.760824)
			(xy 174.10671 -122.625118) (xy 174.039237 -122.485856) (xy 173.978827 -122.343387) (xy 173.925632 -122.198071)
			(xy 173.879787 -122.050271) (xy 173.841406 -121.900359) (xy 173.810585 -121.748713) (xy 173.787403 -121.595712)
			(xy 173.771917 -121.441742) (xy 173.764166 -121.287189) (xy 173.763686 -121.209816) (xy 172.316902 -121.209816)
			(xy 172.316399 -121.288657) (xy 172.308347 -121.446132) (xy 172.292266 -121.602991) (xy 172.268196 -121.758824)
			(xy 172.2362 -121.913225) (xy 172.196363 -122.065791) (xy 172.148787 -122.216124) (xy 172.093597 -122.363831)
			(xy 172.030938 -122.508528) (xy 171.960972 -122.649836) (xy 171.883881 -122.787388) (xy 171.799868 -122.920824)
			(xy 171.709151 -123.049796) (xy 171.611967 -123.173967) (xy 171.50857 -123.293015) (xy 171.399228 -123.406628)
			(xy 171.284229 -123.514509) (xy 171.16387 -123.616378) (xy 171.038468 -123.711968) (xy 170.908348 -123.801031)
			(xy 170.77385 -123.883333) (xy 170.635325 -123.95866) (xy 170.493134 -124.026816) (xy 170.347649 -124.087623)
			(xy 170.199249 -124.140922) (xy 170.048321 -124.186574) (xy 169.895259 -124.22446) (xy 169.740462 -124.254481)
			(xy 169.584335 -124.276559) (xy 169.427283 -124.290636) (xy 169.269718 -124.296676) (xy 169.112049 -124.294662)
			(xy 168.954689 -124.2846) (xy 168.798049 -124.266517) (xy 168.642535 -124.240459) (xy 168.488556 -124.206494)
			(xy 168.336511 -124.164712) (xy 168.186798 -124.11522) (xy 168.039808 -124.058149) (xy 167.895923 -123.993646)
			(xy 167.75552 -123.921881) (xy 167.618964 -123.843041) (xy 167.486612 -123.75733) (xy 167.358809 -123.664974)
			(xy 167.235888 -123.566212) (xy 167.118171 -123.461303) (xy 167.005964 -123.350519) (xy 166.899559 -123.234151)
			(xy 166.799236 -123.112502) (xy 166.705255 -122.985889) (xy 166.617861 -122.854642) (xy 166.537283 -122.719104)
			(xy 166.463731 -122.579629) (xy 166.397396 -122.436579) (xy 166.338452 -122.29033) (xy 166.287053 -122.141261)
			(xy 166.243332 -121.989762) (xy 166.207404 -121.836229) (xy 166.179362 -121.681061) (xy 166.15928 -121.524664)
			(xy 166.147209 -121.367446) (xy 166.143183 -121.209816) (xy 145.778728 -121.209816) (xy 145.778728 -122.390916)
			(xy 145.778177 -122.40763) (xy 145.769522 -122.439918) (xy 145.752807 -122.468867) (xy 145.72917 -122.492505)
			(xy 145.700222 -122.509221) (xy 145.667934 -122.517876) (xy 145.65122 -122.518424) (xy 143.28902 -122.518424)
			(xy 143.272301 -122.517894) (xy 143.240001 -122.509245) (xy 143.21104 -122.49253) (xy 143.187392 -122.468889)
			(xy 143.170669 -122.439933) (xy 143.16201 -122.407635) (xy 143.161512 -122.390916) (xy 139.702068 -122.390916)
			(xy 139.641589 -122.528087) (xy 139.569433 -122.671142) (xy 139.489954 -122.810261) (xy 139.403364 -122.94507)
			(xy 139.309898 -123.075205) (xy 139.209807 -123.200316) (xy 139.10336 -123.320067) (xy 138.990845 -123.434135)
			(xy 138.872564 -123.542212) (xy 138.748835 -123.644008) (xy 138.619993 -123.739248) (xy 138.486383 -123.827676)
			(xy 138.348366 -123.909054) (xy 138.206314 -123.983164) (xy 138.060608 -124.049804) (xy 137.911641 -124.108796)
			(xy 137.835894 -124.13488) (xy 137.818114 -124.140722) (xy 137.799064 -124.172726) (xy 137.818114 -124.28982)
			(xy 137.819921 -124.298605) (xy 137.828753 -124.314204) (xy 137.842393 -124.325834) (xy 137.859192 -124.332088)
			(xy 137.868152 -124.332492) (xy 139.833096 -124.332492) (xy 139.843168 -124.332895) (xy 139.861767 -124.340629)
			(xy 139.869164 -124.347478) (xy 141.082522 -125.560836) (xy 141.089374 -125.568227) (xy 141.097086 -125.586833)
			(xy 141.097508 -125.596904) (xy 141.097508 -132.594096) (xy 141.097105 -132.604168) (xy 141.089371 -132.622767)
			(xy 141.082522 -132.630164) (xy 140.843 -132.869686) (xy 148.209 -132.869686) (xy 148.209 -125.321314)
			(xy 149.182836 -124.347478) (xy 149.190227 -124.340626) (xy 149.208833 -124.332914) (xy 149.218904 -124.332492)
			(xy 152.025096 -124.332492) (xy 152.035168 -124.332895) (xy 152.053767 -124.340629) (xy 152.061164 -124.347478)
			(xy 153.274522 -125.560836) (xy 153.281374 -125.568227) (xy 153.289086 -125.586833) (xy 153.289508 -125.596904)
			(xy 153.289508 -132.594096) (xy 153.289105 -132.604168) (xy 153.281371 -132.622767) (xy 153.274522 -132.630164)
			(xy 153.030428 -132.874258) (xy 163.83 -132.874258) (xy 163.83 -125.316742) (xy 164.79901 -124.347478)
			(xy 164.80641 -124.340638) (xy 164.825009 -124.332919) (xy 164.835078 -124.332492) (xy 167.64127 -124.332492)
			(xy 167.651341 -124.332909) (xy 167.66994 -124.340633) (xy 167.677338 -124.347478) (xy 168.890442 -125.560836)
			(xy 168.897296 -125.568225) (xy 168.905006 -125.586833) (xy 168.905428 -125.596904) (xy 168.905428 -132.594096)
			(xy 168.905019 -132.604168) (xy 168.897289 -132.622766) (xy 168.890442 -132.630164) (xy 167.677338 -133.843522)
			(xy 167.669922 -133.850341) (xy 167.651335 -133.858073) (xy 167.64127 -133.858508) (xy 164.835078 -133.858508)
			(xy 164.825004 -133.858118) (xy 164.806405 -133.850375) (xy 164.79901 -133.843522) (xy 163.83 -132.874258)
			(xy 153.030428 -132.874258) (xy 152.061164 -133.843522) (xy 152.053773 -133.850374) (xy 152.035167 -133.858086)
			(xy 152.025096 -133.858508) (xy 149.218904 -133.858508) (xy 149.208832 -133.858105) (xy 149.190233 -133.850371)
			(xy 149.182836 -133.843522) (xy 148.209 -132.869686) (xy 140.843 -132.869686) (xy 139.869164 -133.843522)
			(xy 139.861773 -133.850374) (xy 139.843167 -133.858086) (xy 139.833096 -133.858508) (xy 137.026904 -133.858508)
			(xy 137.016832 -133.858105) (xy 136.998233 -133.850371) (xy 136.990836 -133.843522) (xy 136.017 -132.869686)
			(xy 136.017 -125.321314) (xy 136.868916 -124.469398) (xy 136.875635 -124.462028) (xy 136.883281 -124.443625)
			(xy 136.883384 -124.423697) (xy 136.880092 -124.41428) (xy 136.844786 -124.327666) (xy 136.8407 -124.31868)
			(xy 136.826981 -124.304514) (xy 136.808913 -124.296611) (xy 136.799066 -124.295916) (xy 136.798558 -124.295916)
			(xy 136.721203 -124.294187) (xy 136.566802 -124.283858) (xy 136.413112 -124.265804) (xy 136.26052 -124.24007)
			(xy 136.10941 -124.206722) (xy 135.96016 -124.165844) (xy 135.813147 -124.117537) (xy 135.668739 -124.061924)
			(xy 135.5273 -123.999144) (xy 135.389184 -123.929355) (xy 135.254739 -123.852732) (xy 135.124303 -123.769468)
			(xy 134.998204 -123.679772) (xy 134.876758 -123.58387) (xy 134.76027 -123.482002) (xy 134.649034 -123.374424)
			(xy 134.543328 -123.261408) (xy 134.443419 -123.143236) (xy 134.349558 -123.020205) (xy 134.261979 -122.892626)
			(xy 134.180904 -122.760818) (xy 134.106537 -122.625113) (xy 134.039063 -122.485851) (xy 133.978653 -122.343384)
			(xy 133.925459 -122.198067) (xy 133.879613 -122.050268) (xy 133.841232 -121.900357) (xy 133.810411 -121.748711)
			(xy 133.787229 -121.595711) (xy 133.771743 -121.441741) (xy 133.763992 -121.287189) (xy 133.763512 -121.209816)
			(xy 132.316728 -121.209816) (xy 132.316225 -121.288657) (xy 132.308173 -121.446132) (xy 132.292092 -121.602991)
			(xy 132.268022 -121.758824) (xy 132.236026 -121.913225) (xy 132.196189 -122.065791) (xy 132.148613 -122.216124)
			(xy 132.093423 -122.363831) (xy 132.030764 -122.508528) (xy 131.960798 -122.649836) (xy 131.883707 -122.787388)
			(xy 131.799694 -122.920824) (xy 131.708977 -123.049796) (xy 131.611793 -123.173967) (xy 131.508396 -123.293015)
			(xy 131.399054 -123.406628) (xy 131.284055 -123.514509) (xy 131.163696 -123.616378) (xy 131.038294 -123.711968)
			(xy 130.908174 -123.801031) (xy 130.773676 -123.883333) (xy 130.635151 -123.95866) (xy 130.49296 -124.026816)
			(xy 130.347475 -124.087623) (xy 130.199075 -124.140922) (xy 130.048147 -124.186574) (xy 129.895085 -124.22446)
			(xy 129.740288 -124.254481) (xy 129.584161 -124.276559) (xy 129.427109 -124.290636) (xy 129.269544 -124.296676)
			(xy 129.111875 -124.294662) (xy 128.954515 -124.2846) (xy 128.797875 -124.266517) (xy 128.642361 -124.240459)
			(xy 128.488382 -124.206494) (xy 128.336337 -124.164712) (xy 128.186624 -124.11522) (xy 128.039634 -124.058149)
			(xy 127.895749 -123.993646) (xy 127.755346 -123.921881) (xy 127.61879 -123.843041) (xy 127.486438 -123.75733)
			(xy 127.358635 -123.664974) (xy 127.235714 -123.566212) (xy 127.117997 -123.461303) (xy 127.00579 -123.350519)
			(xy 126.899385 -123.234151) (xy 126.799062 -123.112502) (xy 126.705081 -122.985889) (xy 126.617687 -122.854642)
			(xy 126.537109 -122.719104) (xy 126.463557 -122.579629) (xy 126.397222 -122.436579) (xy 126.338278 -122.29033)
			(xy 126.286879 -122.141261) (xy 126.243158 -121.989762) (xy 126.20723 -121.836229) (xy 126.179188 -121.681061)
			(xy 126.159106 -121.524664) (xy 126.147035 -121.367446) (xy 126.143009 -121.209816) (xy 105.7783 -121.209816)
			(xy 105.7783 -122.390916) (xy 105.777779 -122.407611) (xy 105.769144 -122.439866) (xy 105.752465 -122.468792)
			(xy 105.728876 -122.492424) (xy 105.699979 -122.509156) (xy 105.66774 -122.517849) (xy 105.651046 -122.518424)
			(xy 103.288846 -122.518424) (xy 103.272185 -122.517872) (xy 103.239993 -122.509267) (xy 103.211122 -122.49263)
			(xy 103.187535 -122.469093) (xy 103.170837 -122.440257) (xy 103.162163 -122.408084) (xy 103.161592 -122.391424)
			(xy 99.701719 -122.391424) (xy 99.641457 -122.5281) (xy 99.5693 -122.671155) (xy 99.489818 -122.810275)
			(xy 99.403226 -122.945084) (xy 99.309757 -123.07522) (xy 99.209663 -123.200331) (xy 99.103214 -123.320082)
			(xy 98.990696 -123.434149) (xy 98.872412 -123.542225) (xy 98.748681 -123.64402) (xy 98.619835 -123.739259)
			(xy 98.486223 -123.827686) (xy 98.348203 -123.909063) (xy 98.206147 -123.98317) (xy 98.060438 -124.049808)
			(xy 97.911469 -124.108797) (xy 97.83572 -124.13488) (xy 97.81794 -124.140722) (xy 97.79889 -124.172726)
			(xy 97.81794 -124.28982) (xy 97.819724 -124.298612) (xy 97.828561 -124.314213) (xy 97.842209 -124.325843)
			(xy 97.859015 -124.332092) (xy 97.867978 -124.332492) (xy 99.832922 -124.332492) (xy 99.842996 -124.332882)
			(xy 99.861595 -124.340625) (xy 99.86899 -124.347478) (xy 101.082094 -125.560836) (xy 101.088942 -125.56823)
			(xy 101.096657 -125.586834) (xy 101.09708 -125.596904) (xy 101.09708 -132.594096) (xy 101.096658 -132.604166)
			(xy 101.088935 -132.622764) (xy 101.082094 -132.630164) (xy 100.847701 -132.864606) (xy 108.204 -132.864606)
			(xy 108.204 -125.326394) (xy 109.182662 -124.347478) (xy 109.190078 -124.340659) (xy 109.208665 -124.332927)
			(xy 109.21873 -124.332492) (xy 112.024922 -124.332492) (xy 112.034996 -124.332882) (xy 112.053595 -124.340625)
			(xy 112.06099 -124.347478) (xy 113.274094 -125.560836) (xy 113.280942 -125.56823) (xy 113.288657 -125.586834)
			(xy 113.28908 -125.596904) (xy 113.28908 -132.594096) (xy 113.288658 -132.604166) (xy 113.280935 -132.622764)
			(xy 113.274094 -132.630164) (xy 113.034622 -132.869686) (xy 123.825 -132.869686) (xy 123.825 -125.321314)
			(xy 124.798836 -124.347478) (xy 124.806227 -124.340626) (xy 124.824833 -124.332914) (xy 124.834904 -124.332492)
			(xy 127.641096 -124.332492) (xy 127.651168 -124.332895) (xy 127.669767 -124.340629) (xy 127.677164 -124.347478)
			(xy 128.890522 -125.560836) (xy 128.897374 -125.568227) (xy 128.905086 -125.586833) (xy 128.905508 -125.596904)
			(xy 128.905508 -132.594096) (xy 128.905105 -132.604168) (xy 128.897371 -132.622767) (xy 128.890522 -132.630164)
			(xy 127.677164 -133.843522) (xy 127.669773 -133.850374) (xy 127.651167 -133.858086) (xy 127.641096 -133.858508)
			(xy 124.834904 -133.858508) (xy 124.824832 -133.858105) (xy 124.806233 -133.850371) (xy 124.798836 -133.843522)
			(xy 123.825 -132.869686) (xy 113.034622 -132.869686) (xy 112.06099 -133.843522) (xy 112.05359 -133.850362)
			(xy 112.034991 -133.858081) (xy 112.024922 -133.858508) (xy 109.21873 -133.858508) (xy 109.208659 -133.858091)
			(xy 109.19006 -133.850367) (xy 109.182662 -133.843522) (xy 108.204 -132.864606) (xy 100.847701 -132.864606)
			(xy 99.86899 -133.843522) (xy 99.86159 -133.850362) (xy 99.842991 -133.858081) (xy 99.832922 -133.858508)
			(xy 97.02673 -133.858508) (xy 97.016659 -133.858091) (xy 96.99806 -133.850367) (xy 96.990662 -133.843522)
			(xy 96.012 -132.864606) (xy 96.012 -125.326394) (xy 96.868742 -124.469398) (xy 96.875463 -124.46203)
			(xy 96.883106 -124.443625) (xy 96.883209 -124.423697) (xy 96.879918 -124.41428) (xy 96.844612 -124.327666)
			(xy 96.840507 -124.318691) (xy 96.826796 -124.304523) (xy 96.808736 -124.296616) (xy 96.798892 -124.295916)
			(xy 96.798384 -124.295916) (xy 96.72103 -124.294163) (xy 96.566629 -124.283834) (xy 96.412939 -124.265781)
			(xy 96.260348 -124.240049) (xy 96.109238 -124.206702) (xy 95.959988 -124.165825) (xy 95.812975 -124.11752)
			(xy 95.668567 -124.061908) (xy 95.527128 -123.999129) (xy 95.389012 -123.929341) (xy 95.254568 -123.852719)
			(xy 95.124132 -123.769456) (xy 94.998032 -123.679761) (xy 94.876586 -123.583859) (xy 94.760098 -123.481992)
			(xy 94.648861 -123.374415) (xy 94.543156 -123.261399) (xy 94.443247 -123.143228) (xy 94.349385 -123.020199)
			(xy 94.261806 -122.89262) (xy 94.180731 -122.760813) (xy 94.106364 -122.625108) (xy 94.03889 -122.485847)
			(xy 93.97848 -122.34338) (xy 93.925285 -122.198064) (xy 93.879439 -122.050266) (xy 93.841058 -121.900355)
			(xy 93.810237 -121.748709) (xy 93.787055 -121.59571) (xy 93.771569 -121.441741) (xy 93.763818 -121.287189)
			(xy 93.763338 -121.209816) (xy 92.316554 -121.209816) (xy 92.316051 -121.288657) (xy 92.307999 -121.446132)
			(xy 92.291918 -121.602991) (xy 92.267848 -121.758824) (xy 92.235852 -121.913225) (xy 92.196015 -122.065791)
			(xy 92.148439 -122.216124) (xy 92.093249 -122.363831) (xy 92.03059 -122.508528) (xy 91.960624 -122.649836)
			(xy 91.883533 -122.787388) (xy 91.79952 -122.920824) (xy 91.708803 -123.049796) (xy 91.611619 -123.173967)
			(xy 91.508222 -123.293015) (xy 91.39888 -123.406628) (xy 91.283881 -123.514509) (xy 91.163522 -123.616378)
			(xy 91.03812 -123.711968) (xy 90.908 -123.801031) (xy 90.773502 -123.883333) (xy 90.634977 -123.95866)
			(xy 90.492786 -124.026816) (xy 90.347301 -124.087623) (xy 90.198901 -124.140922) (xy 90.047973 -124.186574)
			(xy 89.894911 -124.22446) (xy 89.740114 -124.254481) (xy 89.583987 -124.276559) (xy 89.426935 -124.290636)
			(xy 89.26937 -124.296676) (xy 89.111701 -124.294662) (xy 88.954341 -124.2846) (xy 88.797701 -124.266517)
			(xy 88.642187 -124.240459) (xy 88.488208 -124.206494) (xy 88.336163 -124.164712) (xy 88.18645 -124.11522)
			(xy 88.03946 -124.058149) (xy 87.895575 -123.993646) (xy 87.755172 -123.921881) (xy 87.618616 -123.843041)
			(xy 87.486264 -123.75733) (xy 87.358461 -123.664974) (xy 87.23554 -123.566212) (xy 87.117823 -123.461303)
			(xy 87.005616 -123.350519) (xy 86.899211 -123.234151) (xy 86.798888 -123.112502) (xy 86.704907 -122.985889)
			(xy 86.617513 -122.854642) (xy 86.536935 -122.719104) (xy 86.463383 -122.579629) (xy 86.397048 -122.436579)
			(xy 86.338104 -122.29033) (xy 86.286705 -122.141261) (xy 86.242984 -121.989762) (xy 86.207056 -121.836229)
			(xy 86.179014 -121.681061) (xy 86.158932 -121.524664) (xy 86.146861 -121.367446) (xy 86.142835 -121.209816)
			(xy 65.77838 -121.209816) (xy 65.77838 -122.390916) (xy 65.777879 -122.407613) (xy 65.769242 -122.439871)
			(xy 65.75256 -122.468799) (xy 65.728966 -122.492432) (xy 65.700065 -122.509161) (xy 65.667822 -122.517851)
			(xy 65.651126 -122.518424) (xy 63.288926 -122.518424) (xy 63.272264 -122.51789) (xy 63.240072 -122.50928)
			(xy 63.211201 -122.492639) (xy 63.187614 -122.469099) (xy 63.170916 -122.44026) (xy 63.162243 -122.408085)
			(xy 63.161672 -122.391424) (xy 59.701746 -122.391424) (xy 59.641492 -122.528086) (xy 59.569336 -122.671141)
			(xy 59.489857 -122.81026) (xy 59.403267 -122.945068) (xy 59.309801 -123.075204) (xy 59.20971 -123.200315)
			(xy 59.103264 -123.320066) (xy 58.990749 -123.434133) (xy 58.872468 -123.542211) (xy 58.74874 -123.644007)
			(xy 58.619898 -123.739247) (xy 58.486288 -123.827675) (xy 58.348272 -123.909054) (xy 58.206219 -123.983163)
			(xy 58.060514 -124.049803) (xy 57.911547 -124.108796) (xy 57.8358 -124.13488) (xy 57.81802 -124.140722)
			(xy 57.79897 -124.172726) (xy 57.81802 -124.28982) (xy 57.819822 -124.298606) (xy 57.828655 -124.314206)
			(xy 57.842297 -124.325836) (xy 57.859097 -124.332089) (xy 57.868058 -124.332492) (xy 59.833002 -124.332492)
			(xy 59.843075 -124.332892) (xy 59.861674 -124.340628) (xy 59.86907 -124.347478) (xy 61.082174 -125.560836)
			(xy 61.089019 -125.568233) (xy 61.096736 -125.586834) (xy 61.09716 -125.596904) (xy 61.09716 -132.594096)
			(xy 61.096743 -132.604166) (xy 61.089018 -132.622765) (xy 61.082174 -132.630164) (xy 60.85286 -132.859526)
			(xy 68.199 -132.859526) (xy 68.199 -125.331474) (xy 69.182742 -124.347478) (xy 69.190131 -124.340624)
			(xy 69.208739 -124.332913) (xy 69.21881 -124.332492) (xy 72.025002 -124.332492) (xy 72.035075 -124.332892)
			(xy 72.053674 -124.340628) (xy 72.06107 -124.347478) (xy 73.274174 -125.560836) (xy 73.281019 -125.568233)
			(xy 73.288736 -125.586834) (xy 73.28916 -125.596904) (xy 73.28916 -132.594096) (xy 73.288743 -132.604166)
			(xy 73.281018 -132.622765) (xy 73.274174 -132.630164) (xy 73.039781 -132.864606) (xy 83.82 -132.864606)
			(xy 83.82 -125.326394) (xy 84.798662 -124.347478) (xy 84.806078 -124.340659) (xy 84.824665 -124.332927)
			(xy 84.83473 -124.332492) (xy 87.640922 -124.332492) (xy 87.650996 -124.332882) (xy 87.669595 -124.340625)
			(xy 87.67699 -124.347478) (xy 88.890094 -125.560836) (xy 88.896942 -125.56823) (xy 88.904657 -125.586834)
			(xy 88.90508 -125.596904) (xy 88.90508 -132.594096) (xy 88.904658 -132.604166) (xy 88.896935 -132.622764)
			(xy 88.890094 -132.630164) (xy 87.67699 -133.843522) (xy 87.66959 -133.850362) (xy 87.650991 -133.858081)
			(xy 87.640922 -133.858508) (xy 84.83473 -133.858508) (xy 84.824659 -133.858091) (xy 84.80606 -133.850367)
			(xy 84.798662 -133.843522) (xy 83.82 -132.864606) (xy 73.039781 -132.864606) (xy 72.06107 -133.843522)
			(xy 72.053677 -133.850371) (xy 72.035072 -133.858085) (xy 72.025002 -133.858508) (xy 69.21881 -133.858508)
			(xy 69.208738 -133.858102) (xy 69.190139 -133.85037) (xy 69.182742 -133.843522) (xy 68.199 -132.859526)
			(xy 60.85286 -132.859526) (xy 59.86907 -133.843522) (xy 59.861677 -133.850371) (xy 59.843072 -133.858085)
			(xy 59.833002 -133.858508) (xy 57.02681 -133.858508) (xy 57.016738 -133.858102) (xy 56.998139 -133.85037)
			(xy 56.990742 -133.843522) (xy 56.007 -132.859526) (xy 56.007 -125.331474) (xy 56.868822 -124.469398)
			(xy 56.875542 -124.462028) (xy 56.883187 -124.443625) (xy 56.883289 -124.423697) (xy 56.879998 -124.41428)
			(xy 56.844692 -124.327666) (xy 56.840601 -124.318683) (xy 56.826885 -124.304516) (xy 56.808818 -124.296613)
			(xy 56.798972 -124.295916) (xy 56.798464 -124.295916) (xy 56.72111 -124.294142) (xy 56.56671 -124.283813)
			(xy 56.413022 -124.26576) (xy 56.260431 -124.240028) (xy 56.109322 -124.206681) (xy 55.960073 -124.165804)
			(xy 55.813061 -124.117499) (xy 55.668654 -124.061887) (xy 55.527215 -123.999108) (xy 55.3891 -123.929321)
			(xy 55.254656 -123.852699) (xy 55.12422 -123.769437) (xy 54.998121 -123.679743) (xy 54.876675 -123.583842)
			(xy 54.760188 -123.481976) (xy 54.648951 -123.3744) (xy 54.543246 -123.261385) (xy 54.443337 -123.143214)
			(xy 54.349475 -123.020186) (xy 54.261896 -122.892608) (xy 54.180821 -122.760802) (xy 54.106453 -122.625099)
			(xy 54.038979 -122.485839) (xy 53.978568 -122.343373) (xy 53.925372 -122.198058) (xy 53.879526 -122.05026)
			(xy 53.841144 -121.900351) (xy 53.810322 -121.748706) (xy 53.787138 -121.595708) (xy 53.771651 -121.441739)
			(xy 53.763899 -121.287189) (xy 53.763418 -121.209816) (xy 52.316634 -121.209816) (xy 52.316131 -121.288657)
			(xy 52.308079 -121.446132) (xy 52.291998 -121.602991) (xy 52.267928 -121.758824) (xy 52.235932 -121.913225)
			(xy 52.196095 -122.065791) (xy 52.148519 -122.216124) (xy 52.093329 -122.363831) (xy 52.03067 -122.508528)
			(xy 51.960704 -122.649836) (xy 51.883613 -122.787388) (xy 51.7996 -122.920824) (xy 51.708883 -123.049796)
			(xy 51.611699 -123.173967) (xy 51.508302 -123.293015) (xy 51.39896 -123.406628) (xy 51.283961 -123.514509)
			(xy 51.163602 -123.616378) (xy 51.0382 -123.711968) (xy 50.90808 -123.801031) (xy 50.773582 -123.883333)
			(xy 50.635057 -123.95866) (xy 50.492866 -124.026816) (xy 50.347381 -124.087623) (xy 50.198981 -124.140922)
			(xy 50.048053 -124.186574) (xy 49.894991 -124.22446) (xy 49.740194 -124.254481) (xy 49.584067 -124.276559)
			(xy 49.427015 -124.290636) (xy 49.26945 -124.296676) (xy 49.111781 -124.294662) (xy 48.954421 -124.2846)
			(xy 48.797781 -124.266517) (xy 48.642267 -124.240459) (xy 48.488288 -124.206494) (xy 48.336243 -124.164712)
			(xy 48.18653 -124.11522) (xy 48.03954 -124.058149) (xy 47.895655 -123.993646) (xy 47.755252 -123.921881)
			(xy 47.618696 -123.843041) (xy 47.486344 -123.75733) (xy 47.358541 -123.664974) (xy 47.23562 -123.566212)
			(xy 47.117903 -123.461303) (xy 47.005696 -123.350519) (xy 46.899291 -123.234151) (xy 46.798968 -123.112502)
			(xy 46.704987 -122.985889) (xy 46.617593 -122.854642) (xy 46.537015 -122.719104) (xy 46.463463 -122.579629)
			(xy 46.397128 -122.436579) (xy 46.338184 -122.29033) (xy 46.286785 -122.141261) (xy 46.243064 -121.989762)
			(xy 46.207136 -121.836229) (xy 46.179094 -121.681061) (xy 46.159012 -121.524664) (xy 46.146941 -121.367446)
			(xy 46.142915 -121.209816) (xy 37.531802 -121.209816) (xy 37.531802 -132.859526) (xy 43.815 -132.859526)
			(xy 43.815 -125.331474) (xy 44.798742 -124.347478) (xy 44.806131 -124.340624) (xy 44.824739 -124.332913)
			(xy 44.83481 -124.332492) (xy 47.641002 -124.332492) (xy 47.651075 -124.332892) (xy 47.669674 -124.340628)
			(xy 47.67707 -124.347478) (xy 48.890174 -125.560836) (xy 48.897019 -125.568233) (xy 48.904736 -125.586834)
			(xy 48.90516 -125.596904) (xy 48.90516 -132.594096) (xy 48.904743 -132.604166) (xy 48.897018 -132.622765)
			(xy 48.890174 -132.630164) (xy 47.67707 -133.843522) (xy 47.669677 -133.850371) (xy 47.651072 -133.858085)
			(xy 47.641002 -133.858508) (xy 44.83481 -133.858508) (xy 44.824738 -133.858102) (xy 44.806139 -133.85037)
			(xy 44.798742 -133.843522) (xy 43.815 -132.859526) (xy 37.531802 -132.859526) (xy 37.531802 -137.693908)
			(xy 41.132252 -137.693908) (xy 41.132252 -136.1186) (xy 41.132834 -136.101909) (xy 41.141461 -136.069662)
			(xy 41.15813 -136.040741) (xy 41.181706 -136.017109) (xy 41.21059 -136.000374) (xy 41.242817 -135.991673)
			(xy 41.259506 -135.991092) (xy 42.834306 -135.991092) (xy 42.850971 -135.991583) (xy 42.883166 -136.000201)
			(xy 42.912039 -136.016851) (xy 42.935625 -136.0404) (xy 42.952321 -136.069246) (xy 42.960991 -136.101428)
			(xy 42.96156 -136.118092) (xy 42.96156 -136.906) (xy 44.353486 -136.906) (xy 44.357505 -136.758915)
			(xy 44.36955 -136.612269) (xy 44.389585 -136.466499) (xy 44.417551 -136.322042) (xy 44.453364 -136.179327)
			(xy 44.496918 -136.03878) (xy 44.548081 -135.900822) (xy 44.606702 -135.765863) (xy 44.672605 -135.634308)
			(xy 44.745594 -135.506547) (xy 44.825451 -135.382963) (xy 44.911938 -135.263924) (xy 45.004796 -135.149786)
			(xy 45.103748 -135.040889) (xy 45.2085 -134.937559) (xy 45.318738 -134.840103) (xy 45.434134 -134.748812)
			(xy 45.554343 -134.663959) (xy 45.679006 -134.585798) (xy 45.807752 -134.514561) (xy 45.940196 -134.45046)
			(xy 46.075942 -134.393689) (xy 46.214586 -134.344414) (xy 46.355715 -134.302785) (xy 46.498905 -134.268925)
			(xy 46.643732 -134.242934) (xy 46.789761 -134.224892) (xy 46.936558 -134.21485) (xy 47.083684 -134.212841)
			(xy 47.230701 -134.218868) (xy 47.377169 -134.232916) (xy 47.522651 -134.25494) (xy 47.666713 -134.284877)
			(xy 47.808926 -134.322636) (xy 47.948864 -134.368105) (xy 48.086111 -134.421147) (xy 48.220256 -134.481606)
			(xy 48.350899 -134.5493) (xy 48.477651 -134.624027) (xy 48.600133 -134.705565) (xy 48.717979 -134.793669)
			(xy 48.830838 -134.888078) (xy 48.938373 -134.988509) (xy 49.040264 -135.094662) (xy 49.136205 -135.206221)
			(xy 49.225911 -135.322853) (xy 49.309114 -135.44421) (xy 49.385565 -135.569929) (xy 49.455037 -135.699635)
			(xy 49.517323 -135.832942) (xy 49.572235 -135.969452) (xy 49.619611 -136.108756) (xy 49.659309 -136.250439)
			(xy 49.69121 -136.39408) (xy 49.71522 -136.539247) (xy 49.731266 -136.68551) (xy 49.739302 -136.83243)
			(xy 49.739804 -136.906) (xy 49.739302 -136.97957) (xy 49.731266 -137.12649) (xy 49.71522 -137.272753)
			(xy 49.69121 -137.41792) (xy 49.659309 -137.561561) (xy 49.622227 -137.693908) (xy 53.324252 -137.693908)
			(xy 53.324252 -136.1186) (xy 53.324834 -136.101909) (xy 53.333461 -136.069662) (xy 53.35013 -136.040741)
			(xy 53.373706 -136.017109) (xy 53.40259 -136.000374) (xy 53.434817 -135.991673) (xy 53.451506 -135.991092)
			(xy 55.026306 -135.991092) (xy 55.042971 -135.991583) (xy 55.075166 -136.000201) (xy 55.104039 -136.016851)
			(xy 55.127625 -136.0404) (xy 55.144321 -136.069246) (xy 55.152991 -136.101428) (xy 55.15356 -136.118092)
			(xy 55.15356 -136.906) (xy 56.545486 -136.906) (xy 56.549505 -136.758915) (xy 56.56155 -136.612269)
			(xy 56.581585 -136.466499) (xy 56.609551 -136.322042) (xy 56.645364 -136.179327) (xy 56.688918 -136.03878)
			(xy 56.740081 -135.900822) (xy 56.798702 -135.765863) (xy 56.864605 -135.634308) (xy 56.937594 -135.506547)
			(xy 57.017451 -135.382963) (xy 57.103938 -135.263924) (xy 57.196796 -135.149786) (xy 57.295748 -135.040889)
			(xy 57.4005 -134.937559) (xy 57.510738 -134.840103) (xy 57.626134 -134.748812) (xy 57.746343 -134.663959)
			(xy 57.871006 -134.585798) (xy 57.999752 -134.514561) (xy 58.132196 -134.45046) (xy 58.267942 -134.393689)
			(xy 58.406586 -134.344414) (xy 58.547715 -134.302785) (xy 58.690905 -134.268925) (xy 58.835732 -134.242934)
			(xy 58.981761 -134.224892) (xy 59.128558 -134.21485) (xy 59.275684 -134.212841) (xy 59.422701 -134.218868)
			(xy 59.569169 -134.232916) (xy 59.714651 -134.25494) (xy 59.858713 -134.284877) (xy 60.000926 -134.322636)
			(xy 60.140864 -134.368105) (xy 60.278111 -134.421147) (xy 60.412256 -134.481606) (xy 60.542899 -134.5493)
			(xy 60.669651 -134.624027) (xy 60.792133 -134.705565) (xy 60.909979 -134.793669) (xy 61.022838 -134.888078)
			(xy 61.130373 -134.988509) (xy 61.232264 -135.094662) (xy 61.328205 -135.206221) (xy 61.417911 -135.322853)
			(xy 61.501114 -135.44421) (xy 61.577565 -135.569929) (xy 61.647037 -135.699635) (xy 61.709323 -135.832942)
			(xy 61.764235 -135.969452) (xy 61.811611 -136.108756) (xy 61.851309 -136.250439) (xy 61.88321 -136.39408)
			(xy 61.90722 -136.539247) (xy 61.923266 -136.68551) (xy 61.931302 -136.83243) (xy 61.931804 -136.906)
			(xy 61.931302 -136.97957) (xy 61.923266 -137.12649) (xy 61.90722 -137.272753) (xy 61.88321 -137.41792)
			(xy 61.851309 -137.561561) (xy 61.814227 -137.693908) (xy 65.516252 -137.693908) (xy 65.516252 -136.1186)
			(xy 65.516834 -136.101909) (xy 65.525461 -136.069662) (xy 65.54213 -136.040741) (xy 65.565706 -136.017109)
			(xy 65.59459 -136.000374) (xy 65.626817 -135.991673) (xy 65.643506 -135.991092) (xy 67.218306 -135.991092)
			(xy 67.234971 -135.991583) (xy 67.267166 -136.000201) (xy 67.296039 -136.016851) (xy 67.319625 -136.0404)
			(xy 67.336321 -136.069246) (xy 67.344991 -136.101428) (xy 67.34556 -136.118092) (xy 67.34556 -136.906)
			(xy 68.737486 -136.906) (xy 68.741505 -136.758915) (xy 68.75355 -136.612269) (xy 68.773585 -136.466499)
			(xy 68.801551 -136.322042) (xy 68.837364 -136.179327) (xy 68.880918 -136.03878) (xy 68.932081 -135.900822)
			(xy 68.990702 -135.765863) (xy 69.056605 -135.634308) (xy 69.129594 -135.506547) (xy 69.209451 -135.382963)
			(xy 69.295938 -135.263924) (xy 69.388796 -135.149786) (xy 69.487748 -135.040889) (xy 69.5925 -134.937559)
			(xy 69.702738 -134.840103) (xy 69.818134 -134.748812) (xy 69.938343 -134.663959) (xy 70.063006 -134.585798)
			(xy 70.191752 -134.514561) (xy 70.324196 -134.45046) (xy 70.459942 -134.393689) (xy 70.598586 -134.344414)
			(xy 70.739715 -134.302785) (xy 70.882905 -134.268925) (xy 71.027732 -134.242934) (xy 71.173761 -134.224892)
			(xy 71.320558 -134.21485) (xy 71.467684 -134.212841) (xy 71.614701 -134.218868) (xy 71.761169 -134.232916)
			(xy 71.906651 -134.25494) (xy 72.050713 -134.284877) (xy 72.192926 -134.322636) (xy 72.332864 -134.368105)
			(xy 72.470111 -134.421147) (xy 72.604256 -134.481606) (xy 72.734899 -134.5493) (xy 72.861651 -134.624027)
			(xy 72.984133 -134.705565) (xy 73.101979 -134.793669) (xy 73.214838 -134.888078) (xy 73.322373 -134.988509)
			(xy 73.424264 -135.094662) (xy 73.520205 -135.206221) (xy 73.609911 -135.322853) (xy 73.693114 -135.44421)
			(xy 73.769565 -135.569929) (xy 73.839037 -135.699635) (xy 73.901323 -135.832942) (xy 73.956235 -135.969452)
			(xy 74.003611 -136.108756) (xy 74.043309 -136.250439) (xy 74.07521 -136.39408) (xy 74.09922 -136.539247)
			(xy 74.115266 -136.68551) (xy 74.123302 -136.83243) (xy 74.123804 -136.906) (xy 74.123302 -136.97957)
			(xy 74.115266 -137.12649) (xy 74.09922 -137.272753) (xy 74.07521 -137.41792) (xy 74.043309 -137.561561)
			(xy 74.006227 -137.693908) (xy 81.132172 -137.693908) (xy 81.132172 -136.1186) (xy 81.132734 -136.101908)
			(xy 81.141363 -136.069658) (xy 81.158035 -136.040734) (xy 81.181616 -136.017102) (xy 81.210504 -136.000369)
			(xy 81.242735 -135.99167) (xy 81.259426 -135.991092) (xy 82.834226 -135.991092) (xy 82.850892 -135.991565)
			(xy 82.883088 -136.000189) (xy 82.91196 -136.016843) (xy 82.935546 -136.040395) (xy 82.952241 -136.069243)
			(xy 82.960911 -136.101427) (xy 82.96148 -136.118092) (xy 82.96148 -136.906) (xy 84.353406 -136.906)
			(xy 84.357425 -136.758915) (xy 84.36947 -136.612269) (xy 84.389505 -136.466499) (xy 84.417471 -136.322042)
			(xy 84.453284 -136.179327) (xy 84.496838 -136.03878) (xy 84.548001 -135.900822) (xy 84.606622 -135.765863)
			(xy 84.672525 -135.634308) (xy 84.745514 -135.506547) (xy 84.825371 -135.382963) (xy 84.911858 -135.263924)
			(xy 85.004716 -135.149786) (xy 85.103668 -135.040889) (xy 85.20842 -134.937559) (xy 85.318658 -134.840103)
			(xy 85.434054 -134.748812) (xy 85.554263 -134.663959) (xy 85.678926 -134.585798) (xy 85.807672 -134.514561)
			(xy 85.940116 -134.45046) (xy 86.075862 -134.393689) (xy 86.214506 -134.344414) (xy 86.355635 -134.302785)
			(xy 86.498825 -134.268925) (xy 86.643652 -134.242934) (xy 86.789681 -134.224892) (xy 86.936478 -134.21485)
			(xy 87.083604 -134.212841) (xy 87.230621 -134.218868) (xy 87.377089 -134.232916) (xy 87.522571 -134.25494)
			(xy 87.666633 -134.284877) (xy 87.808846 -134.322636) (xy 87.948784 -134.368105) (xy 88.086031 -134.421147)
			(xy 88.220176 -134.481606) (xy 88.350819 -134.5493) (xy 88.477571 -134.624027) (xy 88.600053 -134.705565)
			(xy 88.717899 -134.793669) (xy 88.830758 -134.888078) (xy 88.938293 -134.988509) (xy 89.040184 -135.094662)
			(xy 89.136125 -135.206221) (xy 89.225831 -135.322853) (xy 89.309034 -135.44421) (xy 89.385485 -135.569929)
			(xy 89.454957 -135.699635) (xy 89.517243 -135.832942) (xy 89.572155 -135.969452) (xy 89.619531 -136.108756)
			(xy 89.659229 -136.250439) (xy 89.69113 -136.39408) (xy 89.71514 -136.539247) (xy 89.731186 -136.68551)
			(xy 89.739222 -136.83243) (xy 89.739724 -136.906) (xy 89.739222 -136.97957) (xy 89.731186 -137.12649)
			(xy 89.71514 -137.272753) (xy 89.69113 -137.41792) (xy 89.659229 -137.561561) (xy 89.622147 -137.693908)
			(xy 93.324172 -137.693908) (xy 93.324172 -136.1186) (xy 93.324734 -136.101908) (xy 93.333363 -136.069658)
			(xy 93.350035 -136.040734) (xy 93.373616 -136.017102) (xy 93.402504 -136.000369) (xy 93.434735 -135.99167)
			(xy 93.451426 -135.991092) (xy 95.026226 -135.991092) (xy 95.042892 -135.991565) (xy 95.075088 -136.000189)
			(xy 95.10396 -136.016843) (xy 95.127546 -136.040395) (xy 95.144241 -136.069243) (xy 95.152911 -136.101427)
			(xy 95.15348 -136.118092) (xy 95.15348 -136.906) (xy 96.545406 -136.906) (xy 96.549425 -136.758915)
			(xy 96.56147 -136.612269) (xy 96.581505 -136.466499) (xy 96.609471 -136.322042) (xy 96.645284 -136.179327)
			(xy 96.688838 -136.03878) (xy 96.740001 -135.900822) (xy 96.798622 -135.765863) (xy 96.864525 -135.634308)
			(xy 96.937514 -135.506547) (xy 97.017371 -135.382963) (xy 97.103858 -135.263924) (xy 97.196716 -135.149786)
			(xy 97.295668 -135.040889) (xy 97.40042 -134.937559) (xy 97.510658 -134.840103) (xy 97.626054 -134.748812)
			(xy 97.746263 -134.663959) (xy 97.870926 -134.585798) (xy 97.999672 -134.514561) (xy 98.132116 -134.45046)
			(xy 98.267862 -134.393689) (xy 98.406506 -134.344414) (xy 98.547635 -134.302785) (xy 98.690825 -134.268925)
			(xy 98.835652 -134.242934) (xy 98.981681 -134.224892) (xy 99.128478 -134.21485) (xy 99.275604 -134.212841)
			(xy 99.422621 -134.218868) (xy 99.569089 -134.232916) (xy 99.714571 -134.25494) (xy 99.858633 -134.284877)
			(xy 100.000846 -134.322636) (xy 100.140784 -134.368105) (xy 100.278031 -134.421147) (xy 100.412176 -134.481606)
			(xy 100.542819 -134.5493) (xy 100.669571 -134.624027) (xy 100.792053 -134.705565) (xy 100.909899 -134.793669)
			(xy 101.022758 -134.888078) (xy 101.130293 -134.988509) (xy 101.232184 -135.094662) (xy 101.328125 -135.206221)
			(xy 101.417831 -135.322853) (xy 101.501034 -135.44421) (xy 101.577485 -135.569929) (xy 101.646957 -135.699635)
			(xy 101.709243 -135.832942) (xy 101.764155 -135.969452) (xy 101.811531 -136.108756) (xy 101.851229 -136.250439)
			(xy 101.88313 -136.39408) (xy 101.90714 -136.539247) (xy 101.923186 -136.68551) (xy 101.931222 -136.83243)
			(xy 101.931724 -136.906) (xy 101.931222 -136.97957) (xy 101.923186 -137.12649) (xy 101.90714 -137.272753)
			(xy 101.88313 -137.41792) (xy 101.851229 -137.561561) (xy 101.814147 -137.693908) (xy 105.516172 -137.693908)
			(xy 105.516172 -136.1186) (xy 105.516734 -136.101908) (xy 105.525363 -136.069658) (xy 105.542035 -136.040734)
			(xy 105.565616 -136.017102) (xy 105.594504 -136.000369) (xy 105.626735 -135.99167) (xy 105.643426 -135.991092)
			(xy 107.218226 -135.991092) (xy 107.234892 -135.991565) (xy 107.267088 -136.000189) (xy 107.29596 -136.016843)
			(xy 107.319546 -136.040395) (xy 107.336241 -136.069243) (xy 107.344911 -136.101427) (xy 107.34548 -136.118092)
			(xy 107.34548 -136.906) (xy 108.737406 -136.906) (xy 108.741425 -136.758915) (xy 108.75347 -136.612269)
			(xy 108.773505 -136.466499) (xy 108.801471 -136.322042) (xy 108.837284 -136.179327) (xy 108.880838 -136.03878)
			(xy 108.932001 -135.900822) (xy 108.990622 -135.765863) (xy 109.056525 -135.634308) (xy 109.129514 -135.506547)
			(xy 109.209371 -135.382963) (xy 109.295858 -135.263924) (xy 109.388716 -135.149786) (xy 109.487668 -135.040889)
			(xy 109.59242 -134.937559) (xy 109.702658 -134.840103) (xy 109.818054 -134.748812) (xy 109.938263 -134.663959)
			(xy 110.062926 -134.585798) (xy 110.191672 -134.514561) (xy 110.324116 -134.45046) (xy 110.459862 -134.393689)
			(xy 110.598506 -134.344414) (xy 110.739635 -134.302785) (xy 110.882825 -134.268925) (xy 111.027652 -134.242934)
			(xy 111.173681 -134.224892) (xy 111.320478 -134.21485) (xy 111.467604 -134.212841) (xy 111.614621 -134.218868)
			(xy 111.761089 -134.232916) (xy 111.906571 -134.25494) (xy 112.050633 -134.284877) (xy 112.192846 -134.322636)
			(xy 112.332784 -134.368105) (xy 112.470031 -134.421147) (xy 112.604176 -134.481606) (xy 112.734819 -134.5493)
			(xy 112.861571 -134.624027) (xy 112.984053 -134.705565) (xy 113.101899 -134.793669) (xy 113.214758 -134.888078)
			(xy 113.322293 -134.988509) (xy 113.424184 -135.094662) (xy 113.520125 -135.206221) (xy 113.609831 -135.322853)
			(xy 113.693034 -135.44421) (xy 113.769485 -135.569929) (xy 113.838957 -135.699635) (xy 113.901243 -135.832942)
			(xy 113.956155 -135.969452) (xy 114.003531 -136.108756) (xy 114.043229 -136.250439) (xy 114.07513 -136.39408)
			(xy 114.09914 -136.539247) (xy 114.115186 -136.68551) (xy 114.123222 -136.83243) (xy 114.123724 -136.906)
			(xy 114.123222 -136.97957) (xy 114.115186 -137.12649) (xy 114.09914 -137.272753) (xy 114.07513 -137.41792)
			(xy 114.043229 -137.561561) (xy 114.006289 -137.6934) (xy 121.132092 -137.6934) (xy 121.132092 -136.1186)
			(xy 121.132638 -136.101885) (xy 121.14129 -136.069594) (xy 121.158005 -136.040643) (xy 121.181643 -136.017005)
			(xy 121.210594 -136.00029) (xy 121.242885 -135.991638) (xy 121.2596 -135.991092) (xy 122.8344 -135.991092)
			(xy 122.851115 -135.991638) (xy 122.883406 -136.00029) (xy 122.912357 -136.017005) (xy 122.935995 -136.040643)
			(xy 122.95271 -136.069594) (xy 122.961362 -136.101885) (xy 122.961908 -136.1186) (xy 122.961908 -136.906)
			(xy 124.35358 -136.906) (xy 124.357599 -136.758915) (xy 124.369644 -136.612269) (xy 124.389679 -136.466499)
			(xy 124.417645 -136.322042) (xy 124.453458 -136.179327) (xy 124.497012 -136.03878) (xy 124.548175 -135.900822)
			(xy 124.606796 -135.765863) (xy 124.672699 -135.634308) (xy 124.745688 -135.506547) (xy 124.825545 -135.382963)
			(xy 124.912032 -135.263924) (xy 125.00489 -135.149786) (xy 125.103842 -135.040889) (xy 125.208594 -134.937559)
			(xy 125.318832 -134.840103) (xy 125.434228 -134.748812) (xy 125.554437 -134.663959) (xy 125.6791 -134.585798)
			(xy 125.807846 -134.514561) (xy 125.94029 -134.45046) (xy 126.076036 -134.393689) (xy 126.21468 -134.344414)
			(xy 126.355809 -134.302785) (xy 126.498999 -134.268925) (xy 126.643826 -134.242934) (xy 126.789855 -134.224892)
			(xy 126.936652 -134.21485) (xy 127.083778 -134.212841) (xy 127.230795 -134.218868) (xy 127.377263 -134.232916)
			(xy 127.522745 -134.25494) (xy 127.666807 -134.284877) (xy 127.80902 -134.322636) (xy 127.948958 -134.368105)
			(xy 128.086205 -134.421147) (xy 128.22035 -134.481606) (xy 128.350993 -134.5493) (xy 128.477745 -134.624027)
			(xy 128.600227 -134.705565) (xy 128.718073 -134.793669) (xy 128.830932 -134.888078) (xy 128.938467 -134.988509)
			(xy 129.040358 -135.094662) (xy 129.136299 -135.206221) (xy 129.226005 -135.322853) (xy 129.309208 -135.44421)
			(xy 129.385659 -135.569929) (xy 129.455131 -135.699635) (xy 129.517417 -135.832942) (xy 129.572329 -135.969452)
			(xy 129.619705 -136.108756) (xy 129.659403 -136.250439) (xy 129.691304 -136.39408) (xy 129.715314 -136.539247)
			(xy 129.73136 -136.68551) (xy 129.739396 -136.83243) (xy 129.739898 -136.906) (xy 129.739396 -136.97957)
			(xy 129.73136 -137.12649) (xy 129.715314 -137.272753) (xy 129.691304 -137.41792) (xy 129.659403 -137.561561)
			(xy 129.622463 -137.6934) (xy 133.324092 -137.6934) (xy 133.324092 -136.1186) (xy 133.324638 -136.101885)
			(xy 133.33329 -136.069594) (xy 133.350005 -136.040643) (xy 133.373643 -136.017005) (xy 133.402594 -136.00029)
			(xy 133.434885 -135.991638) (xy 133.4516 -135.991092) (xy 135.0264 -135.991092) (xy 135.043115 -135.991638)
			(xy 135.075406 -136.00029) (xy 135.104357 -136.017005) (xy 135.127995 -136.040643) (xy 135.14471 -136.069594)
			(xy 135.153362 -136.101885) (xy 135.153908 -136.1186) (xy 135.153908 -136.906) (xy 136.54558 -136.906)
			(xy 136.549599 -136.758915) (xy 136.561644 -136.612269) (xy 136.581679 -136.466499) (xy 136.609645 -136.322042)
			(xy 136.645458 -136.179327) (xy 136.689012 -136.03878) (xy 136.740175 -135.900822) (xy 136.798796 -135.765863)
			(xy 136.864699 -135.634308) (xy 136.937688 -135.506547) (xy 137.017545 -135.382963) (xy 137.104032 -135.263924)
			(xy 137.19689 -135.149786) (xy 137.295842 -135.040889) (xy 137.400594 -134.937559) (xy 137.510832 -134.840103)
			(xy 137.626228 -134.748812) (xy 137.746437 -134.663959) (xy 137.8711 -134.585798) (xy 137.999846 -134.514561)
			(xy 138.13229 -134.45046) (xy 138.268036 -134.393689) (xy 138.40668 -134.344414) (xy 138.547809 -134.302785)
			(xy 138.690999 -134.268925) (xy 138.835826 -134.242934) (xy 138.981855 -134.224892) (xy 139.128652 -134.21485)
			(xy 139.275778 -134.212841) (xy 139.422795 -134.218868) (xy 139.569263 -134.232916) (xy 139.714745 -134.25494)
			(xy 139.858807 -134.284877) (xy 140.00102 -134.322636) (xy 140.140958 -134.368105) (xy 140.278205 -134.421147)
			(xy 140.41235 -134.481606) (xy 140.542993 -134.5493) (xy 140.669745 -134.624027) (xy 140.792227 -134.705565)
			(xy 140.910073 -134.793669) (xy 141.022932 -134.888078) (xy 141.130467 -134.988509) (xy 141.232358 -135.094662)
			(xy 141.328299 -135.206221) (xy 141.418005 -135.322853) (xy 141.501208 -135.44421) (xy 141.577659 -135.569929)
			(xy 141.647131 -135.699635) (xy 141.709417 -135.832942) (xy 141.764329 -135.969452) (xy 141.811705 -136.108756)
			(xy 141.851403 -136.250439) (xy 141.883304 -136.39408) (xy 141.907314 -136.539247) (xy 141.92336 -136.68551)
			(xy 141.931396 -136.83243) (xy 141.931898 -136.906) (xy 141.931396 -136.97957) (xy 141.92336 -137.12649)
			(xy 141.907314 -137.272753) (xy 141.883304 -137.41792) (xy 141.851403 -137.561561) (xy 141.814463 -137.6934)
			(xy 145.516092 -137.6934) (xy 145.516092 -136.1186) (xy 145.516638 -136.101885) (xy 145.52529 -136.069594)
			(xy 145.542005 -136.040643) (xy 145.565643 -136.017005) (xy 145.594594 -136.00029) (xy 145.626885 -135.991638)
			(xy 145.6436 -135.991092) (xy 147.2184 -135.991092) (xy 147.235115 -135.991638) (xy 147.267406 -136.00029)
			(xy 147.296357 -136.017005) (xy 147.319995 -136.040643) (xy 147.33671 -136.069594) (xy 147.345362 -136.101885)
			(xy 147.345908 -136.1186) (xy 147.345908 -136.906) (xy 148.73758 -136.906) (xy 148.741599 -136.758915)
			(xy 148.753644 -136.612269) (xy 148.773679 -136.466499) (xy 148.801645 -136.322042) (xy 148.837458 -136.179327)
			(xy 148.881012 -136.03878) (xy 148.932175 -135.900822) (xy 148.990796 -135.765863) (xy 149.056699 -135.634308)
			(xy 149.129688 -135.506547) (xy 149.209545 -135.382963) (xy 149.296032 -135.263924) (xy 149.38889 -135.149786)
			(xy 149.487842 -135.040889) (xy 149.592594 -134.937559) (xy 149.702832 -134.840103) (xy 149.818228 -134.748812)
			(xy 149.938437 -134.663959) (xy 150.0631 -134.585798) (xy 150.191846 -134.514561) (xy 150.32429 -134.45046)
			(xy 150.460036 -134.393689) (xy 150.59868 -134.344414) (xy 150.739809 -134.302785) (xy 150.882999 -134.268925)
			(xy 151.027826 -134.242934) (xy 151.173855 -134.224892) (xy 151.320652 -134.21485) (xy 151.467778 -134.212841)
			(xy 151.614795 -134.218868) (xy 151.761263 -134.232916) (xy 151.906745 -134.25494) (xy 152.050807 -134.284877)
			(xy 152.19302 -134.322636) (xy 152.332958 -134.368105) (xy 152.470205 -134.421147) (xy 152.60435 -134.481606)
			(xy 152.734993 -134.5493) (xy 152.861745 -134.624027) (xy 152.984227 -134.705565) (xy 153.102073 -134.793669)
			(xy 153.214932 -134.888078) (xy 153.322467 -134.988509) (xy 153.424358 -135.094662) (xy 153.520299 -135.206221)
			(xy 153.610005 -135.322853) (xy 153.693208 -135.44421) (xy 153.769659 -135.569929) (xy 153.839131 -135.699635)
			(xy 153.901417 -135.832942) (xy 153.956329 -135.969452) (xy 154.003705 -136.108756) (xy 154.043403 -136.250439)
			(xy 154.075304 -136.39408) (xy 154.099314 -136.539247) (xy 154.11536 -136.68551) (xy 154.123396 -136.83243)
			(xy 154.123898 -136.906) (xy 154.123396 -136.97957) (xy 154.11536 -137.12649) (xy 154.099314 -137.272753)
			(xy 154.075304 -137.41792) (xy 154.043403 -137.561561) (xy 154.006321 -137.693908) (xy 161.13252 -137.693908)
			(xy 161.13252 -136.1186) (xy 161.133035 -136.101904) (xy 161.141668 -136.069647) (xy 161.158347 -136.040718)
			(xy 161.181938 -136.017085) (xy 161.210837 -136.000355) (xy 161.243079 -135.991665) (xy 161.259774 -135.991092)
			(xy 162.834574 -135.991092) (xy 162.851237 -135.991611) (xy 162.883432 -136.000222) (xy 162.912305 -136.016865)
			(xy 162.935892 -136.040409) (xy 162.952588 -136.069251) (xy 162.961259 -136.10143) (xy 162.961828 -136.118092)
			(xy 162.961828 -136.906) (xy 164.353754 -136.906) (xy 164.357773 -136.758915) (xy 164.369818 -136.612269)
			(xy 164.389853 -136.466499) (xy 164.417819 -136.322042) (xy 164.453632 -136.179327) (xy 164.497186 -136.03878)
			(xy 164.548349 -135.900822) (xy 164.60697 -135.765863) (xy 164.672873 -135.634308) (xy 164.745862 -135.506547)
			(xy 164.825719 -135.382963) (xy 164.912206 -135.263924) (xy 165.005064 -135.149786) (xy 165.104016 -135.040889)
			(xy 165.208768 -134.937559) (xy 165.319006 -134.840103) (xy 165.434402 -134.748812) (xy 165.554611 -134.663959)
			(xy 165.679274 -134.585798) (xy 165.80802 -134.514561) (xy 165.940464 -134.45046) (xy 166.07621 -134.393689)
			(xy 166.214854 -134.344414) (xy 166.355983 -134.302785) (xy 166.499173 -134.268925) (xy 166.644 -134.242934)
			(xy 166.790029 -134.224892) (xy 166.936826 -134.21485) (xy 167.083952 -134.212841) (xy 167.230969 -134.218868)
			(xy 167.377437 -134.232916) (xy 167.522919 -134.25494) (xy 167.666981 -134.284877) (xy 167.809194 -134.322636)
			(xy 167.949132 -134.368105) (xy 168.086379 -134.421147) (xy 168.220524 -134.481606) (xy 168.351167 -134.5493)
			(xy 168.477919 -134.624027) (xy 168.600401 -134.705565) (xy 168.718247 -134.793669) (xy 168.831106 -134.888078)
			(xy 168.938641 -134.988509) (xy 169.040532 -135.094662) (xy 169.136473 -135.206221) (xy 169.226179 -135.322853)
			(xy 169.309382 -135.44421) (xy 169.385833 -135.569929) (xy 169.455305 -135.699635) (xy 169.517591 -135.832942)
			(xy 169.572503 -135.969452) (xy 169.619879 -136.108756) (xy 169.659577 -136.250439) (xy 169.691478 -136.39408)
			(xy 169.715488 -136.539247) (xy 169.731534 -136.68551) (xy 169.73957 -136.83243) (xy 169.740072 -136.906)
			(xy 169.73957 -136.97957) (xy 169.731534 -137.12649) (xy 169.715488 -137.272753) (xy 169.691478 -137.41792)
			(xy 169.659577 -137.561561) (xy 169.622495 -137.693908) (xy 173.32452 -137.693908) (xy 173.32452 -136.1186)
			(xy 173.325035 -136.101904) (xy 173.333668 -136.069647) (xy 173.350347 -136.040718) (xy 173.373938 -136.017085)
			(xy 173.402837 -136.000355) (xy 173.435079 -135.991665) (xy 173.451774 -135.991092) (xy 175.026574 -135.991092)
			(xy 175.043237 -135.991611) (xy 175.075432 -136.000222) (xy 175.104305 -136.016865) (xy 175.127892 -136.040409)
			(xy 175.144588 -136.069251) (xy 175.153259 -136.10143) (xy 175.153828 -136.118092) (xy 175.153828 -136.906)
			(xy 176.545754 -136.906) (xy 176.549773 -136.758915) (xy 176.561818 -136.612269) (xy 176.581853 -136.466499)
			(xy 176.609819 -136.322042) (xy 176.645632 -136.179327) (xy 176.689186 -136.03878) (xy 176.740349 -135.900822)
			(xy 176.79897 -135.765863) (xy 176.864873 -135.634308) (xy 176.937862 -135.506547) (xy 177.017719 -135.382963)
			(xy 177.104206 -135.263924) (xy 177.197064 -135.149786) (xy 177.296016 -135.040889) (xy 177.400768 -134.937559)
			(xy 177.511006 -134.840103) (xy 177.626402 -134.748812) (xy 177.746611 -134.663959) (xy 177.871274 -134.585798)
			(xy 178.00002 -134.514561) (xy 178.132464 -134.45046) (xy 178.26821 -134.393689) (xy 178.406854 -134.344414)
			(xy 178.547983 -134.302785) (xy 178.691173 -134.268925) (xy 178.836 -134.242934) (xy 178.982029 -134.224892)
			(xy 179.128826 -134.21485) (xy 179.275952 -134.212841) (xy 179.422969 -134.218868) (xy 179.569437 -134.232916)
			(xy 179.714919 -134.25494) (xy 179.858981 -134.284877) (xy 180.001194 -134.322636) (xy 180.141132 -134.368105)
			(xy 180.278379 -134.421147) (xy 180.412524 -134.481606) (xy 180.543167 -134.5493) (xy 180.669919 -134.624027)
			(xy 180.792401 -134.705565) (xy 180.910247 -134.793669) (xy 181.023106 -134.888078) (xy 181.130641 -134.988509)
			(xy 181.232532 -135.094662) (xy 181.328473 -135.206221) (xy 181.418179 -135.322853) (xy 181.501382 -135.44421)
			(xy 181.577833 -135.569929) (xy 181.647305 -135.699635) (xy 181.709591 -135.832942) (xy 181.764503 -135.969452)
			(xy 181.811879 -136.108756) (xy 181.851577 -136.250439) (xy 181.883478 -136.39408) (xy 181.907488 -136.539247)
			(xy 181.923534 -136.68551) (xy 181.93157 -136.83243) (xy 181.932072 -136.906) (xy 181.93157 -136.97957)
			(xy 181.923534 -137.12649) (xy 181.907488 -137.272753) (xy 181.883478 -137.41792) (xy 181.851577 -137.561561)
			(xy 181.814495 -137.693908) (xy 185.51652 -137.693908) (xy 185.51652 -136.1186) (xy 185.517035 -136.101904)
			(xy 185.525668 -136.069647) (xy 185.542347 -136.040718) (xy 185.565938 -136.017085) (xy 185.594837 -136.000355)
			(xy 185.627079 -135.991665) (xy 185.643774 -135.991092) (xy 187.218574 -135.991092) (xy 187.235237 -135.991611)
			(xy 187.267432 -136.000222) (xy 187.296305 -136.016865) (xy 187.319892 -136.040409) (xy 187.336588 -136.069251)
			(xy 187.345259 -136.10143) (xy 187.345828 -136.118092) (xy 187.345828 -136.906) (xy 188.737754 -136.906)
			(xy 188.741773 -136.758915) (xy 188.753818 -136.612269) (xy 188.773853 -136.466499) (xy 188.801819 -136.322042)
			(xy 188.837632 -136.179327) (xy 188.881186 -136.03878) (xy 188.932349 -135.900822) (xy 188.99097 -135.765863)
			(xy 189.056873 -135.634308) (xy 189.129862 -135.506547) (xy 189.209719 -135.382963) (xy 189.296206 -135.263924)
			(xy 189.389064 -135.149786) (xy 189.488016 -135.040889) (xy 189.592768 -134.937559) (xy 189.703006 -134.840103)
			(xy 189.818402 -134.748812) (xy 189.938611 -134.663959) (xy 190.063274 -134.585798) (xy 190.19202 -134.514561)
			(xy 190.324464 -134.45046) (xy 190.46021 -134.393689) (xy 190.598854 -134.344414) (xy 190.739983 -134.302785)
			(xy 190.883173 -134.268925) (xy 191.028 -134.242934) (xy 191.174029 -134.224892) (xy 191.320826 -134.21485)
			(xy 191.467952 -134.212841) (xy 191.614969 -134.218868) (xy 191.761437 -134.232916) (xy 191.906919 -134.25494)
			(xy 192.050981 -134.284877) (xy 192.193194 -134.322636) (xy 192.333132 -134.368105) (xy 192.470379 -134.421147)
			(xy 192.604524 -134.481606) (xy 192.735167 -134.5493) (xy 192.861919 -134.624027) (xy 192.984401 -134.705565)
			(xy 193.102247 -134.793669) (xy 193.215106 -134.888078) (xy 193.322641 -134.988509) (xy 193.424532 -135.094662)
			(xy 193.520473 -135.206221) (xy 193.610179 -135.322853) (xy 193.693382 -135.44421) (xy 193.769833 -135.569929)
			(xy 193.839305 -135.699635) (xy 193.901591 -135.832942) (xy 193.956503 -135.969452) (xy 194.003879 -136.108756)
			(xy 194.043577 -136.250439) (xy 194.075478 -136.39408) (xy 194.099488 -136.539247) (xy 194.115534 -136.68551)
			(xy 194.12357 -136.83243) (xy 194.124072 -136.906) (xy 194.12357 -136.97957) (xy 194.115534 -137.12649)
			(xy 194.099488 -137.272753) (xy 194.075478 -137.41792) (xy 194.043577 -137.561561) (xy 194.003879 -137.703244)
			(xy 193.956503 -137.842548) (xy 193.901591 -137.979058) (xy 193.839305 -138.112365) (xy 193.769833 -138.242071)
			(xy 193.693382 -138.36779) (xy 193.610179 -138.489147) (xy 193.520473 -138.605779) (xy 193.424532 -138.717338)
			(xy 193.322641 -138.823491) (xy 193.215106 -138.923922) (xy 193.102247 -139.018331) (xy 192.984401 -139.106435)
			(xy 192.861919 -139.187973) (xy 192.735167 -139.2627) (xy 192.604524 -139.330394) (xy 192.470379 -139.390853)
			(xy 192.333132 -139.443895) (xy 192.193194 -139.489364) (xy 192.050981 -139.527123) (xy 191.906919 -139.55706)
			(xy 191.761437 -139.579084) (xy 191.614969 -139.593132) (xy 191.467952 -139.599159) (xy 191.320826 -139.59715)
			(xy 191.174029 -139.587108) (xy 191.028 -139.569066) (xy 190.883173 -139.543075) (xy 190.739983 -139.509215)
			(xy 190.598854 -139.467586) (xy 190.46021 -139.418311) (xy 190.324464 -139.36154) (xy 190.19202 -139.297439)
			(xy 190.063274 -139.226202) (xy 189.938611 -139.148041) (xy 189.818402 -139.063188) (xy 189.703006 -138.971897)
			(xy 189.592768 -138.874441) (xy 189.488016 -138.771111) (xy 189.389064 -138.662214) (xy 189.296206 -138.548076)
			(xy 189.209719 -138.429037) (xy 189.129862 -138.305453) (xy 189.056873 -138.177692) (xy 188.99097 -138.046137)
			(xy 188.932349 -137.911178) (xy 188.881186 -137.77322) (xy 188.837632 -137.632673) (xy 188.801819 -137.489958)
			(xy 188.773853 -137.345501) (xy 188.753818 -137.199731) (xy 188.741773 -137.053085) (xy 188.737754 -136.906)
			(xy 187.345828 -136.906) (xy 187.345828 -137.6934) (xy 187.345266 -137.710092) (xy 187.336637 -137.742342)
			(xy 187.319965 -137.771266) (xy 187.296384 -137.794898) (xy 187.267496 -137.811631) (xy 187.235265 -137.82033)
			(xy 187.218574 -137.820908) (xy 185.643774 -137.820908) (xy 185.627108 -137.820435) (xy 185.594912 -137.811811)
			(xy 185.56604 -137.795157) (xy 185.542454 -137.771605) (xy 185.525759 -137.742757) (xy 185.517089 -137.710573)
			(xy 185.51652 -137.693908) (xy 181.814495 -137.693908) (xy 181.811879 -137.703244) (xy 181.764503 -137.842548)
			(xy 181.709591 -137.979058) (xy 181.647305 -138.112365) (xy 181.577833 -138.242071) (xy 181.501382 -138.36779)
			(xy 181.418179 -138.489147) (xy 181.328473 -138.605779) (xy 181.232532 -138.717338) (xy 181.130641 -138.823491)
			(xy 181.023106 -138.923922) (xy 180.910247 -139.018331) (xy 180.792401 -139.106435) (xy 180.669919 -139.187973)
			(xy 180.543167 -139.2627) (xy 180.412524 -139.330394) (xy 180.278379 -139.390853) (xy 180.141132 -139.443895)
			(xy 180.001194 -139.489364) (xy 179.858981 -139.527123) (xy 179.714919 -139.55706) (xy 179.569437 -139.579084)
			(xy 179.422969 -139.593132) (xy 179.275952 -139.599159) (xy 179.128826 -139.59715) (xy 178.982029 -139.587108)
			(xy 178.836 -139.569066) (xy 178.691173 -139.543075) (xy 178.547983 -139.509215) (xy 178.406854 -139.467586)
			(xy 178.26821 -139.418311) (xy 178.132464 -139.36154) (xy 178.00002 -139.297439) (xy 177.871274 -139.226202)
			(xy 177.746611 -139.148041) (xy 177.626402 -139.063188) (xy 177.511006 -138.971897) (xy 177.400768 -138.874441)
			(xy 177.296016 -138.771111) (xy 177.197064 -138.662214) (xy 177.104206 -138.548076) (xy 177.017719 -138.429037)
			(xy 176.937862 -138.305453) (xy 176.864873 -138.177692) (xy 176.79897 -138.046137) (xy 176.740349 -137.911178)
			(xy 176.689186 -137.77322) (xy 176.645632 -137.632673) (xy 176.609819 -137.489958) (xy 176.581853 -137.345501)
			(xy 176.561818 -137.199731) (xy 176.549773 -137.053085) (xy 176.545754 -136.906) (xy 175.153828 -136.906)
			(xy 175.153828 -137.6934) (xy 175.153266 -137.710092) (xy 175.144637 -137.742342) (xy 175.127965 -137.771266)
			(xy 175.104384 -137.794898) (xy 175.075496 -137.811631) (xy 175.043265 -137.82033) (xy 175.026574 -137.820908)
			(xy 173.451774 -137.820908) (xy 173.435108 -137.820435) (xy 173.402912 -137.811811) (xy 173.37404 -137.795157)
			(xy 173.350454 -137.771605) (xy 173.333759 -137.742757) (xy 173.325089 -137.710573) (xy 173.32452 -137.693908)
			(xy 169.622495 -137.693908) (xy 169.619879 -137.703244) (xy 169.572503 -137.842548) (xy 169.517591 -137.979058)
			(xy 169.455305 -138.112365) (xy 169.385833 -138.242071) (xy 169.309382 -138.36779) (xy 169.226179 -138.489147)
			(xy 169.136473 -138.605779) (xy 169.040532 -138.717338) (xy 168.938641 -138.823491) (xy 168.831106 -138.923922)
			(xy 168.718247 -139.018331) (xy 168.600401 -139.106435) (xy 168.477919 -139.187973) (xy 168.351167 -139.2627)
			(xy 168.220524 -139.330394) (xy 168.086379 -139.390853) (xy 167.949132 -139.443895) (xy 167.809194 -139.489364)
			(xy 167.666981 -139.527123) (xy 167.522919 -139.55706) (xy 167.377437 -139.579084) (xy 167.230969 -139.593132)
			(xy 167.083952 -139.599159) (xy 166.936826 -139.59715) (xy 166.790029 -139.587108) (xy 166.644 -139.569066)
			(xy 166.499173 -139.543075) (xy 166.355983 -139.509215) (xy 166.214854 -139.467586) (xy 166.07621 -139.418311)
			(xy 165.940464 -139.36154) (xy 165.80802 -139.297439) (xy 165.679274 -139.226202) (xy 165.554611 -139.148041)
			(xy 165.434402 -139.063188) (xy 165.319006 -138.971897) (xy 165.208768 -138.874441) (xy 165.104016 -138.771111)
			(xy 165.005064 -138.662214) (xy 164.912206 -138.548076) (xy 164.825719 -138.429037) (xy 164.745862 -138.305453)
			(xy 164.672873 -138.177692) (xy 164.60697 -138.046137) (xy 164.548349 -137.911178) (xy 164.497186 -137.77322)
			(xy 164.453632 -137.632673) (xy 164.417819 -137.489958) (xy 164.389853 -137.345501) (xy 164.369818 -137.199731)
			(xy 164.357773 -137.053085) (xy 164.353754 -136.906) (xy 162.961828 -136.906) (xy 162.961828 -137.6934)
			(xy 162.961266 -137.710092) (xy 162.952637 -137.742342) (xy 162.935965 -137.771266) (xy 162.912384 -137.794898)
			(xy 162.883496 -137.811631) (xy 162.851265 -137.82033) (xy 162.834574 -137.820908) (xy 161.259774 -137.820908)
			(xy 161.243108 -137.820435) (xy 161.210912 -137.811811) (xy 161.18204 -137.795157) (xy 161.158454 -137.771605)
			(xy 161.141759 -137.742757) (xy 161.133089 -137.710573) (xy 161.13252 -137.693908) (xy 154.006321 -137.693908)
			(xy 154.003705 -137.703244) (xy 153.956329 -137.842548) (xy 153.901417 -137.979058) (xy 153.839131 -138.112365)
			(xy 153.769659 -138.242071) (xy 153.693208 -138.36779) (xy 153.610005 -138.489147) (xy 153.520299 -138.605779)
			(xy 153.424358 -138.717338) (xy 153.322467 -138.823491) (xy 153.214932 -138.923922) (xy 153.102073 -139.018331)
			(xy 152.984227 -139.106435) (xy 152.861745 -139.187973) (xy 152.734993 -139.2627) (xy 152.60435 -139.330394)
			(xy 152.470205 -139.390853) (xy 152.332958 -139.443895) (xy 152.19302 -139.489364) (xy 152.050807 -139.527123)
			(xy 151.906745 -139.55706) (xy 151.761263 -139.579084) (xy 151.614795 -139.593132) (xy 151.467778 -139.599159)
			(xy 151.320652 -139.59715) (xy 151.173855 -139.587108) (xy 151.027826 -139.569066) (xy 150.882999 -139.543075)
			(xy 150.739809 -139.509215) (xy 150.59868 -139.467586) (xy 150.460036 -139.418311) (xy 150.32429 -139.36154)
			(xy 150.191846 -139.297439) (xy 150.0631 -139.226202) (xy 149.938437 -139.148041) (xy 149.818228 -139.063188)
			(xy 149.702832 -138.971897) (xy 149.592594 -138.874441) (xy 149.487842 -138.771111) (xy 149.38889 -138.662214)
			(xy 149.296032 -138.548076) (xy 149.209545 -138.429037) (xy 149.129688 -138.305453) (xy 149.056699 -138.177692)
			(xy 148.990796 -138.046137) (xy 148.932175 -137.911178) (xy 148.881012 -137.77322) (xy 148.837458 -137.632673)
			(xy 148.801645 -137.489958) (xy 148.773679 -137.345501) (xy 148.753644 -137.199731) (xy 148.741599 -137.053085)
			(xy 148.73758 -136.906) (xy 147.345908 -136.906) (xy 147.345908 -137.6934) (xy 147.345362 -137.710115)
			(xy 147.33671 -137.742406) (xy 147.319995 -137.771357) (xy 147.296357 -137.794995) (xy 147.267406 -137.81171)
			(xy 147.235115 -137.820362) (xy 147.2184 -137.820908) (xy 145.6436 -137.820908) (xy 145.626885 -137.820362)
			(xy 145.594594 -137.81171) (xy 145.565643 -137.794995) (xy 145.542005 -137.771357) (xy 145.52529 -137.742406)
			(xy 145.516638 -137.710115) (xy 145.516092 -137.6934) (xy 141.814463 -137.6934) (xy 141.811705 -137.703244)
			(xy 141.764329 -137.842548) (xy 141.709417 -137.979058) (xy 141.647131 -138.112365) (xy 141.577659 -138.242071)
			(xy 141.501208 -138.36779) (xy 141.418005 -138.489147) (xy 141.328299 -138.605779) (xy 141.232358 -138.717338)
			(xy 141.130467 -138.823491) (xy 141.022932 -138.923922) (xy 140.910073 -139.018331) (xy 140.792227 -139.106435)
			(xy 140.669745 -139.187973) (xy 140.542993 -139.2627) (xy 140.41235 -139.330394) (xy 140.278205 -139.390853)
			(xy 140.140958 -139.443895) (xy 140.00102 -139.489364) (xy 139.858807 -139.527123) (xy 139.714745 -139.55706)
			(xy 139.569263 -139.579084) (xy 139.422795 -139.593132) (xy 139.275778 -139.599159) (xy 139.128652 -139.59715)
			(xy 138.981855 -139.587108) (xy 138.835826 -139.569066) (xy 138.690999 -139.543075) (xy 138.547809 -139.509215)
			(xy 138.40668 -139.467586) (xy 138.268036 -139.418311) (xy 138.13229 -139.36154) (xy 137.999846 -139.297439)
			(xy 137.8711 -139.226202) (xy 137.746437 -139.148041) (xy 137.626228 -139.063188) (xy 137.510832 -138.971897)
			(xy 137.400594 -138.874441) (xy 137.295842 -138.771111) (xy 137.19689 -138.662214) (xy 137.104032 -138.548076)
			(xy 137.017545 -138.429037) (xy 136.937688 -138.305453) (xy 136.864699 -138.177692) (xy 136.798796 -138.046137)
			(xy 136.740175 -137.911178) (xy 136.689012 -137.77322) (xy 136.645458 -137.632673) (xy 136.609645 -137.489958)
			(xy 136.581679 -137.345501) (xy 136.561644 -137.199731) (xy 136.549599 -137.053085) (xy 136.54558 -136.906)
			(xy 135.153908 -136.906) (xy 135.153908 -137.6934) (xy 135.153362 -137.710115) (xy 135.14471 -137.742406)
			(xy 135.127995 -137.771357) (xy 135.104357 -137.794995) (xy 135.075406 -137.81171) (xy 135.043115 -137.820362)
			(xy 135.0264 -137.820908) (xy 133.4516 -137.820908) (xy 133.434885 -137.820362) (xy 133.402594 -137.81171)
			(xy 133.373643 -137.794995) (xy 133.350005 -137.771357) (xy 133.33329 -137.742406) (xy 133.324638 -137.710115)
			(xy 133.324092 -137.6934) (xy 129.622463 -137.6934) (xy 129.619705 -137.703244) (xy 129.572329 -137.842548)
			(xy 129.517417 -137.979058) (xy 129.455131 -138.112365) (xy 129.385659 -138.242071) (xy 129.309208 -138.36779)
			(xy 129.226005 -138.489147) (xy 129.136299 -138.605779) (xy 129.040358 -138.717338) (xy 128.938467 -138.823491)
			(xy 128.830932 -138.923922) (xy 128.718073 -139.018331) (xy 128.600227 -139.106435) (xy 128.477745 -139.187973)
			(xy 128.350993 -139.2627) (xy 128.22035 -139.330394) (xy 128.086205 -139.390853) (xy 127.948958 -139.443895)
			(xy 127.80902 -139.489364) (xy 127.666807 -139.527123) (xy 127.522745 -139.55706) (xy 127.377263 -139.579084)
			(xy 127.230795 -139.593132) (xy 127.083778 -139.599159) (xy 126.936652 -139.59715) (xy 126.789855 -139.587108)
			(xy 126.643826 -139.569066) (xy 126.498999 -139.543075) (xy 126.355809 -139.509215) (xy 126.21468 -139.467586)
			(xy 126.076036 -139.418311) (xy 125.94029 -139.36154) (xy 125.807846 -139.297439) (xy 125.6791 -139.226202)
			(xy 125.554437 -139.148041) (xy 125.434228 -139.063188) (xy 125.318832 -138.971897) (xy 125.208594 -138.874441)
			(xy 125.103842 -138.771111) (xy 125.00489 -138.662214) (xy 124.912032 -138.548076) (xy 124.825545 -138.429037)
			(xy 124.745688 -138.305453) (xy 124.672699 -138.177692) (xy 124.606796 -138.046137) (xy 124.548175 -137.911178)
			(xy 124.497012 -137.77322) (xy 124.453458 -137.632673) (xy 124.417645 -137.489958) (xy 124.389679 -137.345501)
			(xy 124.369644 -137.199731) (xy 124.357599 -137.053085) (xy 124.35358 -136.906) (xy 122.961908 -136.906)
			(xy 122.961908 -137.6934) (xy 122.961362 -137.710115) (xy 122.95271 -137.742406) (xy 122.935995 -137.771357)
			(xy 122.912357 -137.794995) (xy 122.883406 -137.81171) (xy 122.851115 -137.820362) (xy 122.8344 -137.820908)
			(xy 121.2596 -137.820908) (xy 121.242885 -137.820362) (xy 121.210594 -137.81171) (xy 121.181643 -137.794995)
			(xy 121.158005 -137.771357) (xy 121.14129 -137.742406) (xy 121.132638 -137.710115) (xy 121.132092 -137.6934)
			(xy 114.006289 -137.6934) (xy 114.003531 -137.703244) (xy 113.956155 -137.842548) (xy 113.901243 -137.979058)
			(xy 113.838957 -138.112365) (xy 113.769485 -138.242071) (xy 113.693034 -138.36779) (xy 113.609831 -138.489147)
			(xy 113.520125 -138.605779) (xy 113.424184 -138.717338) (xy 113.322293 -138.823491) (xy 113.214758 -138.923922)
			(xy 113.101899 -139.018331) (xy 112.984053 -139.106435) (xy 112.861571 -139.187973) (xy 112.734819 -139.2627)
			(xy 112.604176 -139.330394) (xy 112.470031 -139.390853) (xy 112.332784 -139.443895) (xy 112.192846 -139.489364)
			(xy 112.050633 -139.527123) (xy 111.906571 -139.55706) (xy 111.761089 -139.579084) (xy 111.614621 -139.593132)
			(xy 111.467604 -139.599159) (xy 111.320478 -139.59715) (xy 111.173681 -139.587108) (xy 111.027652 -139.569066)
			(xy 110.882825 -139.543075) (xy 110.739635 -139.509215) (xy 110.598506 -139.467586) (xy 110.459862 -139.418311)
			(xy 110.324116 -139.36154) (xy 110.191672 -139.297439) (xy 110.062926 -139.226202) (xy 109.938263 -139.148041)
			(xy 109.818054 -139.063188) (xy 109.702658 -138.971897) (xy 109.59242 -138.874441) (xy 109.487668 -138.771111)
			(xy 109.388716 -138.662214) (xy 109.295858 -138.548076) (xy 109.209371 -138.429037) (xy 109.129514 -138.305453)
			(xy 109.056525 -138.177692) (xy 108.990622 -138.046137) (xy 108.932001 -137.911178) (xy 108.880838 -137.77322)
			(xy 108.837284 -137.632673) (xy 108.801471 -137.489958) (xy 108.773505 -137.345501) (xy 108.75347 -137.199731)
			(xy 108.741425 -137.053085) (xy 108.737406 -136.906) (xy 107.34548 -136.906) (xy 107.34548 -137.6934)
			(xy 107.344965 -137.710096) (xy 107.336332 -137.742353) (xy 107.319653 -137.771282) (xy 107.296062 -137.794915)
			(xy 107.267163 -137.811645) (xy 107.234921 -137.820335) (xy 107.218226 -137.820908) (xy 105.643426 -137.820908)
			(xy 105.626763 -137.820389) (xy 105.594568 -137.811778) (xy 105.565695 -137.795135) (xy 105.542108 -137.771591)
			(xy 105.525412 -137.742749) (xy 105.516741 -137.71057) (xy 105.516172 -137.693908) (xy 101.814147 -137.693908)
			(xy 101.811531 -137.703244) (xy 101.764155 -137.842548) (xy 101.709243 -137.979058) (xy 101.646957 -138.112365)
			(xy 101.577485 -138.242071) (xy 101.501034 -138.36779) (xy 101.417831 -138.489147) (xy 101.328125 -138.605779)
			(xy 101.232184 -138.717338) (xy 101.130293 -138.823491) (xy 101.022758 -138.923922) (xy 100.909899 -139.018331)
			(xy 100.792053 -139.106435) (xy 100.669571 -139.187973) (xy 100.542819 -139.2627) (xy 100.412176 -139.330394)
			(xy 100.278031 -139.390853) (xy 100.140784 -139.443895) (xy 100.000846 -139.489364) (xy 99.858633 -139.527123)
			(xy 99.714571 -139.55706) (xy 99.569089 -139.579084) (xy 99.422621 -139.593132) (xy 99.275604 -139.599159)
			(xy 99.128478 -139.59715) (xy 98.981681 -139.587108) (xy 98.835652 -139.569066) (xy 98.690825 -139.543075)
			(xy 98.547635 -139.509215) (xy 98.406506 -139.467586) (xy 98.267862 -139.418311) (xy 98.132116 -139.36154)
			(xy 97.999672 -139.297439) (xy 97.870926 -139.226202) (xy 97.746263 -139.148041) (xy 97.626054 -139.063188)
			(xy 97.510658 -138.971897) (xy 97.40042 -138.874441) (xy 97.295668 -138.771111) (xy 97.196716 -138.662214)
			(xy 97.103858 -138.548076) (xy 97.017371 -138.429037) (xy 96.937514 -138.305453) (xy 96.864525 -138.177692)
			(xy 96.798622 -138.046137) (xy 96.740001 -137.911178) (xy 96.688838 -137.77322) (xy 96.645284 -137.632673)
			(xy 96.609471 -137.489958) (xy 96.581505 -137.345501) (xy 96.56147 -137.199731) (xy 96.549425 -137.053085)
			(xy 96.545406 -136.906) (xy 95.15348 -136.906) (xy 95.15348 -137.6934) (xy 95.152965 -137.710096)
			(xy 95.144332 -137.742353) (xy 95.127653 -137.771282) (xy 95.104062 -137.794915) (xy 95.075163 -137.811645)
			(xy 95.042921 -137.820335) (xy 95.026226 -137.820908) (xy 93.451426 -137.820908) (xy 93.434763 -137.820389)
			(xy 93.402568 -137.811778) (xy 93.373695 -137.795135) (xy 93.350108 -137.771591) (xy 93.333412 -137.742749)
			(xy 93.324741 -137.71057) (xy 93.324172 -137.693908) (xy 89.622147 -137.693908) (xy 89.619531 -137.703244)
			(xy 89.572155 -137.842548) (xy 89.517243 -137.979058) (xy 89.454957 -138.112365) (xy 89.385485 -138.242071)
			(xy 89.309034 -138.36779) (xy 89.225831 -138.489147) (xy 89.136125 -138.605779) (xy 89.040184 -138.717338)
			(xy 88.938293 -138.823491) (xy 88.830758 -138.923922) (xy 88.717899 -139.018331) (xy 88.600053 -139.106435)
			(xy 88.477571 -139.187973) (xy 88.350819 -139.2627) (xy 88.220176 -139.330394) (xy 88.086031 -139.390853)
			(xy 87.948784 -139.443895) (xy 87.808846 -139.489364) (xy 87.666633 -139.527123) (xy 87.522571 -139.55706)
			(xy 87.377089 -139.579084) (xy 87.230621 -139.593132) (xy 87.083604 -139.599159) (xy 86.936478 -139.59715)
			(xy 86.789681 -139.587108) (xy 86.643652 -139.569066) (xy 86.498825 -139.543075) (xy 86.355635 -139.509215)
			(xy 86.214506 -139.467586) (xy 86.075862 -139.418311) (xy 85.940116 -139.36154) (xy 85.807672 -139.297439)
			(xy 85.678926 -139.226202) (xy 85.554263 -139.148041) (xy 85.434054 -139.063188) (xy 85.318658 -138.971897)
			(xy 85.20842 -138.874441) (xy 85.103668 -138.771111) (xy 85.004716 -138.662214) (xy 84.911858 -138.548076)
			(xy 84.825371 -138.429037) (xy 84.745514 -138.305453) (xy 84.672525 -138.177692) (xy 84.606622 -138.046137)
			(xy 84.548001 -137.911178) (xy 84.496838 -137.77322) (xy 84.453284 -137.632673) (xy 84.417471 -137.489958)
			(xy 84.389505 -137.345501) (xy 84.36947 -137.199731) (xy 84.357425 -137.053085) (xy 84.353406 -136.906)
			(xy 82.96148 -136.906) (xy 82.96148 -137.6934) (xy 82.960965 -137.710096) (xy 82.952332 -137.742353)
			(xy 82.935653 -137.771282) (xy 82.912062 -137.794915) (xy 82.883163 -137.811645) (xy 82.850921 -137.820335)
			(xy 82.834226 -137.820908) (xy 81.259426 -137.820908) (xy 81.242763 -137.820389) (xy 81.210568 -137.811778)
			(xy 81.181695 -137.795135) (xy 81.158108 -137.771591) (xy 81.141412 -137.742749) (xy 81.132741 -137.71057)
			(xy 81.132172 -137.693908) (xy 74.006227 -137.693908) (xy 74.003611 -137.703244) (xy 73.956235 -137.842548)
			(xy 73.901323 -137.979058) (xy 73.839037 -138.112365) (xy 73.769565 -138.242071) (xy 73.693114 -138.36779)
			(xy 73.609911 -138.489147) (xy 73.520205 -138.605779) (xy 73.424264 -138.717338) (xy 73.322373 -138.823491)
			(xy 73.214838 -138.923922) (xy 73.101979 -139.018331) (xy 72.984133 -139.106435) (xy 72.861651 -139.187973)
			(xy 72.734899 -139.2627) (xy 72.604256 -139.330394) (xy 72.470111 -139.390853) (xy 72.332864 -139.443895)
			(xy 72.192926 -139.489364) (xy 72.050713 -139.527123) (xy 71.906651 -139.55706) (xy 71.761169 -139.579084)
			(xy 71.614701 -139.593132) (xy 71.467684 -139.599159) (xy 71.320558 -139.59715) (xy 71.173761 -139.587108)
			(xy 71.027732 -139.569066) (xy 70.882905 -139.543075) (xy 70.739715 -139.509215) (xy 70.598586 -139.467586)
			(xy 70.459942 -139.418311) (xy 70.324196 -139.36154) (xy 70.191752 -139.297439) (xy 70.063006 -139.226202)
			(xy 69.938343 -139.148041) (xy 69.818134 -139.063188) (xy 69.702738 -138.971897) (xy 69.5925 -138.874441)
			(xy 69.487748 -138.771111) (xy 69.388796 -138.662214) (xy 69.295938 -138.548076) (xy 69.209451 -138.429037)
			(xy 69.129594 -138.305453) (xy 69.056605 -138.177692) (xy 68.990702 -138.046137) (xy 68.932081 -137.911178)
			(xy 68.880918 -137.77322) (xy 68.837364 -137.632673) (xy 68.801551 -137.489958) (xy 68.773585 -137.345501)
			(xy 68.75355 -137.199731) (xy 68.741505 -137.053085) (xy 68.737486 -136.906) (xy 67.34556 -136.906)
			(xy 67.34556 -137.6934) (xy 67.345065 -137.710098) (xy 67.33643 -137.742358) (xy 67.319748 -137.771288)
			(xy 67.296153 -137.794922) (xy 67.267249 -137.811651) (xy 67.235003 -137.820338) (xy 67.218306 -137.820908)
			(xy 65.643506 -137.820908) (xy 65.626842 -137.820407) (xy 65.594647 -137.811791) (xy 65.565774 -137.795143)
			(xy 65.542187 -137.771597) (xy 65.525491 -137.742752) (xy 65.516821 -137.710571) (xy 65.516252 -137.693908)
			(xy 61.814227 -137.693908) (xy 61.811611 -137.703244) (xy 61.764235 -137.842548) (xy 61.709323 -137.979058)
			(xy 61.647037 -138.112365) (xy 61.577565 -138.242071) (xy 61.501114 -138.36779) (xy 61.417911 -138.489147)
			(xy 61.328205 -138.605779) (xy 61.232264 -138.717338) (xy 61.130373 -138.823491) (xy 61.022838 -138.923922)
			(xy 60.909979 -139.018331) (xy 60.792133 -139.106435) (xy 60.669651 -139.187973) (xy 60.542899 -139.2627)
			(xy 60.412256 -139.330394) (xy 60.278111 -139.390853) (xy 60.140864 -139.443895) (xy 60.000926 -139.489364)
			(xy 59.858713 -139.527123) (xy 59.714651 -139.55706) (xy 59.569169 -139.579084) (xy 59.422701 -139.593132)
			(xy 59.275684 -139.599159) (xy 59.128558 -139.59715) (xy 58.981761 -139.587108) (xy 58.835732 -139.569066)
			(xy 58.690905 -139.543075) (xy 58.547715 -139.509215) (xy 58.406586 -139.467586) (xy 58.267942 -139.418311)
			(xy 58.132196 -139.36154) (xy 57.999752 -139.297439) (xy 57.871006 -139.226202) (xy 57.746343 -139.148041)
			(xy 57.626134 -139.063188) (xy 57.510738 -138.971897) (xy 57.4005 -138.874441) (xy 57.295748 -138.771111)
			(xy 57.196796 -138.662214) (xy 57.103938 -138.548076) (xy 57.017451 -138.429037) (xy 56.937594 -138.305453)
			(xy 56.864605 -138.177692) (xy 56.798702 -138.046137) (xy 56.740081 -137.911178) (xy 56.688918 -137.77322)
			(xy 56.645364 -137.632673) (xy 56.609551 -137.489958) (xy 56.581585 -137.345501) (xy 56.56155 -137.199731)
			(xy 56.549505 -137.053085) (xy 56.545486 -136.906) (xy 55.15356 -136.906) (xy 55.15356 -137.6934)
			(xy 55.153065 -137.710098) (xy 55.14443 -137.742358) (xy 55.127748 -137.771288) (xy 55.104153 -137.794922)
			(xy 55.075249 -137.811651) (xy 55.043003 -137.820338) (xy 55.026306 -137.820908) (xy 53.451506 -137.820908)
			(xy 53.434842 -137.820407) (xy 53.402647 -137.811791) (xy 53.373774 -137.795143) (xy 53.350187 -137.771597)
			(xy 53.333491 -137.742752) (xy 53.324821 -137.710571) (xy 53.324252 -137.693908) (xy 49.622227 -137.693908)
			(xy 49.619611 -137.703244) (xy 49.572235 -137.842548) (xy 49.517323 -137.979058) (xy 49.455037 -138.112365)
			(xy 49.385565 -138.242071) (xy 49.309114 -138.36779) (xy 49.225911 -138.489147) (xy 49.136205 -138.605779)
			(xy 49.040264 -138.717338) (xy 48.938373 -138.823491) (xy 48.830838 -138.923922) (xy 48.717979 -139.018331)
			(xy 48.600133 -139.106435) (xy 48.477651 -139.187973) (xy 48.350899 -139.2627) (xy 48.220256 -139.330394)
			(xy 48.086111 -139.390853) (xy 47.948864 -139.443895) (xy 47.808926 -139.489364) (xy 47.666713 -139.527123)
			(xy 47.522651 -139.55706) (xy 47.377169 -139.579084) (xy 47.230701 -139.593132) (xy 47.083684 -139.599159)
			(xy 46.936558 -139.59715) (xy 46.789761 -139.587108) (xy 46.643732 -139.569066) (xy 46.498905 -139.543075)
			(xy 46.355715 -139.509215) (xy 46.214586 -139.467586) (xy 46.075942 -139.418311) (xy 45.940196 -139.36154)
			(xy 45.807752 -139.297439) (xy 45.679006 -139.226202) (xy 45.554343 -139.148041) (xy 45.434134 -139.063188)
			(xy 45.318738 -138.971897) (xy 45.2085 -138.874441) (xy 45.103748 -138.771111) (xy 45.004796 -138.662214)
			(xy 44.911938 -138.548076) (xy 44.825451 -138.429037) (xy 44.745594 -138.305453) (xy 44.672605 -138.177692)
			(xy 44.606702 -138.046137) (xy 44.548081 -137.911178) (xy 44.496918 -137.77322) (xy 44.453364 -137.632673)
			(xy 44.417551 -137.489958) (xy 44.389585 -137.345501) (xy 44.36955 -137.199731) (xy 44.357505 -137.053085)
			(xy 44.353486 -136.906) (xy 42.96156 -136.906) (xy 42.96156 -137.6934) (xy 42.961065 -137.710098)
			(xy 42.95243 -137.742358) (xy 42.935748 -137.771288) (xy 42.912153 -137.794922) (xy 42.883249 -137.811651)
			(xy 42.851003 -137.820338) (xy 42.834306 -137.820908) (xy 41.259506 -137.820908) (xy 41.242842 -137.820407)
			(xy 41.210647 -137.811791) (xy 41.181774 -137.795143) (xy 41.158187 -137.771597) (xy 41.141491 -137.742752)
			(xy 41.132821 -137.710571) (xy 41.132252 -137.693908) (xy 37.531802 -137.693908) (xy 37.531802 -141.75232)
			(xy 37.539422 -141.771116) (xy 37.546788 -141.778228) (xy 37.546788 -143.537432) (xy 37.547216 -143.5475)
			(xy 37.554938 -143.566097) (xy 37.561774 -143.5735) (xy 38.974014 -144.98574) (xy 38.981411 -144.992591)
			(xy 39.000009 -145.000329) (xy 39.010082 -145.000726)
		)
		(stroke
			(width 0)
			(type solid)
		)
		(fill yes)
		(layer "F.Cu")
		(net "P52V_HS_FILTER")
	)
	(gr_poly
		(pts
			(xy 90.363294 -78.1558) (xy 90.373165 -78.155326) (xy 90.391444 -78.147864) (xy 90.398854 -78.141322)
			(xy 90.403934 -78.136242) (xy 90.452448 -78.074012) (xy 90.457545 -78.066887) (xy 90.463011 -78.050258)
			(xy 90.463116 -78.0415) (xy 90.463116 -78.040992) (xy 90.462862 -78.033626) (xy 90.462354 -78.031086)
			(xy 90.4621 -78.030324) (xy 90.461338 -78.027276) (xy 90.449138 -77.976583) (xy 90.432088 -77.873711)
			(xy 90.423524 -77.769788) (xy 90.422984 -77.71765) (xy 90.422984 -77.699616) (xy 90.424254 -77.668882)
			(xy 90.426712 -77.618093) (xy 90.438734 -77.517113) (xy 90.458787 -77.417417) (xy 90.486744 -77.319643)
			(xy 90.522424 -77.224415) (xy 90.565601 -77.132343) (xy 90.615997 -77.044016) (xy 90.673291 -76.959999)
			(xy 90.737115 -76.88083) (xy 90.807063 -76.807014) (xy 90.882685 -76.739024) (xy 90.963499 -76.677294)
			(xy 91.048988 -76.622221) (xy 91.138604 -76.574155) (xy 91.231775 -76.533405) (xy 91.327905 -76.50023)
			(xy 91.377008 -76.48702) (xy 91.385136 -76.484988) (xy 91.398852 -76.476098) (xy 91.404694 -76.468732)
			(xy 91.405964 -76.467208) (xy 91.413838 -76.459842) (xy 91.41714 -76.457556) (xy 91.423501 -76.453578)
			(xy 91.437837 -76.449183) (xy 91.445334 -76.44892) (xy 91.627452 -76.44892) (xy 91.628722 -76.448666)
			(xy 91.694 -76.447142) (xy 91.759278 -76.448666) (xy 91.760548 -76.44892) (xy 92.783406 -76.44892)
			(xy 92.784676 -76.448666) (xy 92.849954 -76.447142) (xy 92.915232 -76.448666) (xy 92.916502 -76.44892)
			(xy 94.5896 -76.44892) (xy 94.593608 -76.44885) (xy 94.60152 -76.44757) (xy 94.605348 -76.44638)
			(xy 94.627446 -76.439268) (xy 94.636082 -76.433172) (xy 94.636336 -76.433172) (xy 94.676541 -76.405263)
			(xy 94.760532 -76.355003) (xy 94.848141 -76.311356) (xy 94.93885 -76.274581) (xy 95.032121 -76.244897)
			(xy 95.127399 -76.222479) (xy 95.22412 -76.207461) (xy 95.32171 -76.199932) (xy 95.37065 -76.199492)
			(xy 95.376746 -76.199492) (xy 95.425439 -76.200179) (xy 95.522507 -76.208099) (xy 95.618685 -76.223428)
			(xy 95.713406 -76.246078) (xy 95.806114 -76.275914) (xy 95.896265 -76.312762) (xy 95.98333 -76.356405)
			(xy 96.066798 -76.406587) (xy 96.106742 -76.434442) (xy 96.106996 -76.434696) (xy 96.113854 -76.439268)
			(xy 96.143572 -76.44892) (xy 96.7486 -76.44892) (xy 96.752608 -76.44885) (xy 96.76052 -76.44757)
			(xy 96.764348 -76.44638) (xy 96.786446 -76.439268) (xy 96.795082 -76.433172) (xy 96.795336 -76.433172)
			(xy 96.835541 -76.405263) (xy 96.919532 -76.355003) (xy 97.007141 -76.311356) (xy 97.09785 -76.274581)
			(xy 97.191121 -76.244897) (xy 97.286399 -76.222479) (xy 97.38312 -76.207461) (xy 97.48071 -76.199932)
			(xy 97.52965 -76.199492) (xy 97.535746 -76.199492) (xy 97.584439 -76.200179) (xy 97.681507 -76.208099)
			(xy 97.777685 -76.223428) (xy 97.872406 -76.246078) (xy 97.965114 -76.275914) (xy 98.055265 -76.312762)
			(xy 98.14233 -76.356405) (xy 98.225798 -76.406587) (xy 98.265742 -76.434442) (xy 98.265996 -76.434696)
			(xy 98.272854 -76.439268) (xy 98.302572 -76.44892) (xy 99.04095 -76.44892) (xy 99.044958 -76.448854)
			(xy 99.052873 -76.447581) (xy 99.056698 -76.44638) (xy 99.078796 -76.439268) (xy 99.087432 -76.433172)
			(xy 99.087686 -76.433172) (xy 99.127892 -76.405265) (xy 99.211883 -76.355008) (xy 99.299493 -76.311364)
			(xy 99.390202 -76.274593) (xy 99.483473 -76.244913) (xy 99.578751 -76.222499) (xy 99.675471 -76.207484)
			(xy 99.77306 -76.199959) (xy 99.822 -76.199492) (xy 99.828096 -76.199492) (xy 99.877313 -76.200206)
			(xy 99.975418 -76.208299) (xy 100.072604 -76.223957) (xy 100.168287 -76.247086) (xy 100.261895 -76.277547)
			(xy 100.352866 -76.315158) (xy 100.440654 -76.359693) (xy 100.524735 -76.410886) (xy 100.56495 -76.439268)
			(xy 100.57158 -76.443677) (xy 100.586713 -76.448599) (xy 100.594668 -76.44892) (xy 100.784152 -76.44892)
			(xy 100.793804 -76.448412) (xy 100.794058 -76.448412) (xy 100.849938 -76.446634) (xy 100.850192 -76.446634)
			(xy 100.900104 -76.447135) (xy 100.99962 -76.454989) (xy 101.098213 -76.470625) (xy 101.195275 -76.493947)
			(xy 101.290209 -76.524811) (xy 101.382429 -76.563028) (xy 101.471367 -76.60836) (xy 101.556475 -76.66053)
			(xy 101.637228 -76.719216) (xy 101.713129 -76.784055) (xy 101.783709 -76.854649) (xy 101.848534 -76.930562)
			(xy 101.907204 -77.011326) (xy 101.959358 -77.096444) (xy 102.004674 -77.18539) (xy 102.042873 -77.277618)
			(xy 102.073719 -77.372558) (xy 102.097023 -77.469625) (xy 102.11264 -77.56822) (xy 102.120475 -77.667737)
			(xy 102.120954 -77.71765) (xy 102.120369 -77.770184) (xy 102.111612 -77.874887) (xy 102.094244 -77.978511)
			(xy 102.081838 -78.029562) (xy 102.07879 -78.041246) (xy 102.083616 -78.063852) (xy 102.140004 -78.136242)
			(xy 102.147542 -78.145038) (xy 102.168313 -78.15524) (xy 102.179882 -78.1558) (xy 131.519422 -78.1558)
			(xy 131.529299 -78.155339) (xy 131.547596 -78.147895) (xy 131.554982 -78.141322) (xy 131.560062 -78.136242)
			(xy 131.608576 -78.07452) (xy 131.614259 -78.066609) (xy 131.619724 -78.047929) (xy 131.619244 -78.038198)
			(xy 131.618736 -78.033372) (xy 131.61772 -78.029562) (xy 131.605495 -77.978957) (xy 131.588376 -77.876257)
			(xy 131.579716 -77.772501) (xy 131.579112 -77.720444) (xy 131.579366 -77.72019) (xy 131.579874 -77.699362)
			(xy 131.581059 -77.649935) (xy 131.590167 -77.551479) (xy 131.606901 -77.454028) (xy 131.631159 -77.358173)
			(xy 131.662795 -77.264493) (xy 131.701617 -77.173556) (xy 131.747391 -77.085913) (xy 131.799839 -77.002092)
			(xy 131.858643 -76.922602) (xy 131.923449 -76.847923) (xy 131.993864 -76.778508) (xy 132.069461 -76.714777)
			(xy 132.149784 -76.657115) (xy 132.234346 -76.605871) (xy 132.322636 -76.561355) (xy 132.414118 -76.523837)
			(xy 132.50824 -76.493544) (xy 132.604433 -76.470658) (xy 132.702113 -76.45532) (xy 132.80069 -76.44762)
			(xy 132.850128 -76.447142) (xy 132.8674 -76.447142) (xy 134.950962 -76.447142) (xy 134.956466 -76.44702)
			(xy 134.967227 -76.444714) (xy 134.972298 -76.44257) (xy 135.021911 -76.420395) (xy 135.124176 -76.383605)
			(xy 135.229211 -76.355688) (xy 135.336247 -76.336849) (xy 135.444501 -76.327224) (xy 135.49884 -76.326492)
			(xy 135.502904 -76.326492) (xy 135.557375 -76.32708) (xy 135.665914 -76.336427) (xy 135.773255 -76.355034)
			(xy 135.878607 -76.382764) (xy 135.981198 -76.419415) (xy 136.03097 -76.441554) (xy 136.033256 -76.44257)
			(xy 136.037066 -76.444094) (xy 136.041367 -76.445539) (xy 136.050309 -76.447066) (xy 136.054846 -76.447142)
			(xy 137.236962 -76.447142) (xy 137.242466 -76.44702) (xy 137.253227 -76.444714) (xy 137.258298 -76.44257)
			(xy 137.307911 -76.420395) (xy 137.410176 -76.383605) (xy 137.515211 -76.355688) (xy 137.622247 -76.336849)
			(xy 137.730501 -76.327224) (xy 137.78484 -76.326492) (xy 137.788904 -76.326492) (xy 137.843375 -76.32708)
			(xy 137.951914 -76.336427) (xy 138.059255 -76.355034) (xy 138.164607 -76.382764) (xy 138.267198 -76.419415)
			(xy 138.31697 -76.441554) (xy 138.319256 -76.44257) (xy 138.323066 -76.444094) (xy 138.327367 -76.445539)
			(xy 138.336309 -76.447066) (xy 138.340846 -76.447142) (xy 139.520676 -76.447142) (xy 139.526772 -76.446888)
			(xy 139.537694 -76.445364) (xy 139.54506 -76.442062) (xy 139.594947 -76.419844) (xy 139.697771 -76.383033)
			(xy 139.803375 -76.355177) (xy 139.910978 -76.336483) (xy 140.019789 -76.327088) (xy 140.074396 -76.326492)
			(xy 140.07465 -76.326492) (xy 140.129371 -76.32708) (xy 140.238404 -76.33652) (xy 140.346223 -76.355301)
			(xy 140.452027 -76.383283) (xy 140.555033 -76.420259) (xy 140.605002 -76.44257) (xy 140.615162 -76.447142)
			(xy 140.90142 -76.447142) (xy 140.90142 -76.448158) (xy 140.952532 -76.45074) (xy 141.054134 -76.463089)
			(xy 141.154413 -76.483574) (xy 141.252718 -76.512061) (xy 141.348413 -76.548365) (xy 141.440876 -76.592251)
			(xy 141.529508 -76.643435) (xy 141.613735 -76.701584) (xy 141.693009 -76.766322) (xy 141.766818 -76.837228)
			(xy 141.834682 -76.913843) (xy 141.896162 -76.995671) (xy 141.950858 -77.08218) (xy 141.998416 -77.172809)
			(xy 142.038528 -77.266971) (xy 142.070933 -77.364055) (xy 142.095421 -77.463432) (xy 142.111835 -77.564457)
			(xy 142.120066 -77.666475) (xy 142.12062 -77.71765) (xy 142.12062 -77.718666) (xy 142.120073 -77.770412)
			(xy 142.111614 -77.873557) (xy 142.094797 -77.975673) (xy 142.082774 -78.026006) (xy 142.081758 -78.029562)
			(xy 142.080996 -78.037944) (xy 142.080489 -78.047527) (xy 142.085851 -78.065935) (xy 142.09141 -78.073758)
			(xy 142.140178 -78.136242) (xy 142.147721 -78.145025) (xy 142.168492 -78.155197) (xy 142.180056 -78.1558)
			(xy 170.223942 -78.1558) (xy 170.452542 -77.9272) (xy 170.452542 -76.085954) (xy 170.453561 -76.034456)
			(xy 170.462908 -75.931871) (xy 170.480531 -75.83038) (xy 170.506315 -75.730649) (xy 170.54009 -75.633333)
			(xy 170.581634 -75.539072) (xy 170.630675 -75.448485) (xy 170.686891 -75.362166) (xy 170.749911 -75.280683)
			(xy 170.819323 -75.204571) (xy 170.89467 -75.134329) (xy 170.975458 -75.07042) (xy 171.061155 -75.013262)
			(xy 171.1512 -74.963232) (xy 171.245 -74.920657) (xy 171.34194 -74.885818) (xy 171.441382 -74.858943)
			(xy 171.542674 -74.840209) (xy 171.645151 -74.829738) (xy 171.696634 -74.828146) (xy 171.69765 -74.828146)
			(xy 171.72305 -74.827892) (xy 171.74845 -74.828146) (xy 175.105822 -74.828146) (xy 175.133508 -74.805794)
			(xy 175.137318 -74.788014) (xy 175.148545 -74.738532) (xy 175.17787 -74.641387) (xy 175.21485 -74.546891)
			(xy 175.25925 -74.455646) (xy 175.310787 -74.368233) (xy 175.369132 -74.285209) (xy 175.433914 -74.207105)
			(xy 175.504719 -74.134416) (xy 175.581097 -74.067607) (xy 175.662561 -74.007104) (xy 175.748592 -73.953291)
			(xy 175.838641 -73.906512) (xy 175.932134 -73.867066) (xy 176.028476 -73.835202) (xy 176.127053 -73.811125)
			(xy 176.227236 -73.794988) (xy 176.328387 -73.786894) (xy 176.429861 -73.786894) (xy 176.531012 -73.794988)
			(xy 176.631195 -73.811125) (xy 176.729772 -73.835202) (xy 176.826114 -73.867066) (xy 176.919607 -73.906512)
			(xy 177.009656 -73.953291) (xy 177.095687 -74.007104) (xy 177.177151 -74.067607) (xy 177.253529 -74.134416)
			(xy 177.324334 -74.207105) (xy 177.389116 -74.285209) (xy 177.447461 -74.368233) (xy 177.498998 -74.455646)
			(xy 177.543398 -74.546891) (xy 177.580378 -74.641387) (xy 177.609703 -74.738532) (xy 177.62093 -74.788014)
			(xy 177.624141 -74.803) (xy 182.62499 -74.803) (xy 182.629007 -74.702018) (xy 182.641036 -74.601674)
			(xy 182.660998 -74.502604) (xy 182.688769 -74.405432) (xy 182.724172 -74.310774) (xy 182.766983 -74.219228)
			(xy 182.816933 -74.131373) (xy 182.873705 -74.047764) (xy 182.93694 -73.96893) (xy 183.006239 -73.895369)
			(xy 183.081163 -73.827547) (xy 183.161239 -73.765892) (xy 183.24596 -73.710793) (xy 183.334791 -73.6626)
			(xy 183.42717 -73.621617) (xy 183.522513 -73.588103) (xy 183.620218 -73.56227) (xy 183.719666 -73.544281)
			(xy 183.820229 -73.53425) (xy 183.92127 -73.532241) (xy 184.022153 -73.538266) (xy 184.122237 -73.552286)
			(xy 184.220891 -73.574215) (xy 184.317492 -73.603912) (xy 184.411427 -73.64119) (xy 184.502104 -73.685813)
			(xy 184.588948 -73.7375) (xy 184.671412 -73.795923) (xy 184.748973 -73.860713) (xy 184.821142 -73.931461)
			(xy 184.887461 -74.007718) (xy 184.947512 -74.089004) (xy 185.000915 -74.174804) (xy 185.047333 -74.264576)
			(xy 185.086471 -74.357751) (xy 185.118083 -74.453742) (xy 185.141968 -74.551941) (xy 185.157976 -74.651727)
			(xy 185.166006 -74.752469) (xy 185.166508 -74.803) (xy 185.166006 -74.853531) (xy 185.157976 -74.954273)
			(xy 185.141968 -75.054059) (xy 185.118083 -75.152258) (xy 185.086471 -75.248249) (xy 185.047333 -75.341424)
			(xy 185.000915 -75.431196) (xy 184.947512 -75.516996) (xy 184.887461 -75.598282) (xy 184.821142 -75.674539)
			(xy 184.748973 -75.745287) (xy 184.671412 -75.810077) (xy 184.588948 -75.8685) (xy 184.502104 -75.920187)
			(xy 184.411427 -75.96481) (xy 184.317492 -76.002088) (xy 184.220891 -76.031785) (xy 184.122237 -76.053714)
			(xy 184.022153 -76.067734) (xy 183.92127 -76.073759) (xy 183.820229 -76.07175) (xy 183.719666 -76.061719)
			(xy 183.620218 -76.04373) (xy 183.522513 -76.017897) (xy 183.42717 -75.984383) (xy 183.334791 -75.9434)
			(xy 183.24596 -75.895207) (xy 183.161239 -75.840108) (xy 183.081163 -75.778453) (xy 183.006239 -75.710631)
			(xy 182.93694 -75.63707) (xy 182.873705 -75.558236) (xy 182.816933 -75.474627) (xy 182.766983 -75.386772)
			(xy 182.724172 -75.295226) (xy 182.688769 -75.200568) (xy 182.660998 -75.103396) (xy 182.641036 -75.004326)
			(xy 182.629007 -74.903982) (xy 182.62499 -74.803) (xy 177.624141 -74.803) (xy 177.626264 -74.812906)
			(xy 177.635154 -74.820272) (xy 177.64506 -74.840846) (xy 177.64506 -74.949304) (xy 177.645314 -74.951336)
			(xy 177.647354 -74.977704) (xy 177.649512 -75.030553) (xy 177.649632 -75.057) (xy 177.649518 -75.083447)
			(xy 177.647361 -75.136296) (xy 177.645314 -75.162664) (xy 177.64506 -75.164696) (xy 177.64506 -76.0984)
			(xy 177.875438 -76.328778) (xy 177.894147 -76.329944) (xy 177.931491 -76.333247) (xy 177.950114 -76.335382)
			(xy 179.923948 -76.335382) (xy 179.961526 -76.331191) (xy 180.037014 -76.326746) (xy 180.074824 -76.326492)
			(xy 180.121825 -76.326928) (xy 180.215568 -76.333895) (xy 180.30854 -76.347768) (xy 180.400234 -76.36847)
			(xy 180.490148 -76.395888) (xy 180.577791 -76.429873) (xy 180.620416 -76.449682) (xy 180.62575 -76.452222)
			(xy 180.634132 -76.456286) (xy 180.641119 -76.459421) (xy 180.656245 -76.461754) (xy 180.66385 -76.460858)
			(xy 180.71338 -76.454508) (xy 180.713634 -76.454508) (xy 180.716428 -76.454254) (xy 180.749792 -76.450924)
			(xy 180.816757 -76.447368) (xy 180.850286 -76.447142) (xy 180.900185 -76.447619) (xy 180.999676 -76.455448)
			(xy 181.098246 -76.471059) (xy 181.195287 -76.494357) (xy 181.290201 -76.525196) (xy 181.382403 -76.563387)
			(xy 181.471324 -76.608695) (xy 181.556416 -76.660841) (xy 181.637154 -76.719501) (xy 181.713041 -76.784316)
			(xy 181.783608 -76.854885) (xy 181.848421 -76.930774) (xy 181.907079 -77.011514) (xy 181.959222 -77.096607)
			(xy 182.004528 -77.185529) (xy 182.042716 -77.277732) (xy 182.073553 -77.372647) (xy 182.096848 -77.469689)
			(xy 182.112456 -77.56826) (xy 182.120283 -77.667751) (xy 182.120794 -77.71765) (xy 182.12024 -77.770136)
			(xy 182.111557 -77.87475) (xy 182.094279 -77.978292) (xy 182.081932 -78.029308) (xy 182.079138 -78.040738)
			(xy 182.083964 -78.063598) (xy 182.089044 -78.069948) (xy 182.091584 -78.073758) (xy 182.140352 -78.136242)
			(xy 182.147893 -78.14503) (xy 182.168664 -78.155212) (xy 182.18023 -78.1558) (xy 187.9854 -78.1558)
			(xy 188.4172 -77.724) (xy 192.6844 -77.724) (xy 193.1162 -78.1558) (xy 197.286118 -78.1558) (xy 197.296187 -78.155373)
			(xy 197.314786 -78.147654) (xy 197.322186 -78.140814) (xy 198.105014 -77.357986) (xy 198.111868 -77.350591)
			(xy 198.11961 -77.331992) (xy 198.12 -77.321918) (xy 198.12 -67.010026) (xy 198.29526 -66.834766)
			(xy 199.006714 -66.834766) (xy 199.0852 -66.75628) (xy 199.0852 -65.144142) (xy 199.085634 -65.134077)
			(xy 199.093363 -65.115487) (xy 199.100186 -65.108074) (xy 199.650604 -64.557656) (xy 199.658 -64.550804)
			(xy 199.676599 -64.543062) (xy 199.686672 -64.54267) (xy 212.195918 -64.54267) (xy 212.205986 -64.542243)
			(xy 212.224583 -64.534521) (xy 212.231986 -64.527684) (xy 213.223856 -63.535814) (xy 213.223856 -42.28084)
			(xy 212.471762 -41.529) (xy 204.281786 -41.529) (xy 204.271717 -41.528574) (xy 204.253116 -41.520856)
			(xy 204.245718 -41.514014) (xy 202.75169 -40.019986) (xy 202.744836 -40.012591) (xy 202.737092 -39.993992)
			(xy 202.736704 -39.983918) (xy 202.736704 -20.75942) (xy 201.325226 -19.347942) (xy 164.275516 -19.347942)
			(xy 163.449 -18.521426) (xy 163.295838 -18.368264) (xy 163.295838 -9.773158) (xy 163.401502 -9.667494)
			(xy 163.401502 -2.441702) (xy 162.9918 -2.032) (xy 161.392362 -2.032) (xy 161.340597 -2.039967) (xy 161.2362 -2.048486)
			(xy 161.131456 -2.048486) (xy 161.027059 -2.039967) (xy 160.975294 -2.032) (xy 156.16936 -2.032)
			(xy 156.104082 -2.034032) (xy 156.103574 -2.034032) (xy 156.038296 -2.032) (xy 151.08936 -2.032)
			(xy 151.024082 -2.034032) (xy 151.023574 -2.034032) (xy 150.958296 -2.032) (xy 146.00936 -2.032)
			(xy 145.944082 -2.034032) (xy 145.943574 -2.034032) (xy 145.878296 -2.032) (xy 140.92936 -2.032)
			(xy 140.864082 -2.034032) (xy 140.863574 -2.034032) (xy 140.798296 -2.032) (xy 135.84936 -2.032)
			(xy 135.784082 -2.034032) (xy 135.783574 -2.034032) (xy 135.718296 -2.032) (xy 130.76936 -2.032)
			(xy 130.704082 -2.034032) (xy 130.703574 -2.034032) (xy 130.638296 -2.032) (xy 125.68936 -2.032)
			(xy 125.624082 -2.034032) (xy 125.623574 -2.034032) (xy 125.558296 -2.032) (xy 120.60936 -2.032)
			(xy 120.544082 -2.034032) (xy 120.543574 -2.034032) (xy 120.478296 -2.032) (xy 115.52936 -2.032)
			(xy 115.464082 -2.034032) (xy 115.463574 -2.034032) (xy 115.398296 -2.032) (xy 110.44936 -2.032)
			(xy 110.384082 -2.034032) (xy 110.383574 -2.034032) (xy 110.318296 -2.032) (xy 105.36936 -2.032)
			(xy 105.304082 -2.034032) (xy 105.303574 -2.034032) (xy 105.238296 -2.032) (xy 100.28936 -2.032)
			(xy 100.224082 -2.034032) (xy 100.223574 -2.034032) (xy 100.158296 -2.032) (xy 95.20936 -2.032) (xy 95.144082 -2.034032)
			(xy 95.143574 -2.034032) (xy 95.078296 -2.032) (xy 90.12936 -2.032) (xy 90.064082 -2.034032) (xy 90.063574 -2.034032)
			(xy 89.998296 -2.032) (xy 85.04936 -2.032) (xy 84.984082 -2.034032) (xy 84.983574 -2.034032) (xy 84.918296 -2.032)
			(xy 79.96936 -2.032) (xy 79.904082 -2.034032) (xy 79.903574 -2.034032) (xy 79.838296 -2.032) (xy 74.88936 -2.032)
			(xy 74.824082 -2.034032) (xy 74.823574 -2.034032) (xy 74.758296 -2.032) (xy 69.80936 -2.032) (xy 69.744082 -2.034032)
			(xy 69.743574 -2.034032) (xy 69.678296 -2.032) (xy 64.72936 -2.032) (xy 64.664082 -2.034032) (xy 64.663574 -2.034032)
			(xy 64.598296 -2.032) (xy 59.64936 -2.032) (xy 59.584082 -2.034032) (xy 59.583574 -2.034032) (xy 59.518296 -2.032)
			(xy 54.56936 -2.032) (xy 54.504082 -2.034032) (xy 54.503574 -2.034032) (xy 54.438296 -2.032) (xy 49.602136 -2.032)
			(xy 49.591468 -2.034032) (xy 49.583594 -2.035556) (xy 49.570386 -2.042414) (xy 48.236632 -3.376168)
			(xy 48.229793 -3.383569) (xy 48.222078 -3.402167) (xy 48.221646 -3.412236) (xy 48.221646 -5.263777)
			(xy 49.428134 -5.263777) (xy 49.428134 -5.150223) (xy 49.436055 -5.036947) (xy 49.451858 -4.924499)
			(xy 49.475467 -4.813428) (xy 49.506767 -4.704273) (xy 49.545604 -4.597568) (xy 49.59179 -4.493833)
			(xy 49.6451 -4.393571) (xy 49.705274 -4.297273) (xy 49.772019 -4.205407) (xy 49.845009 -4.11842)
			(xy 49.92389 -4.036737) (xy 50.008276 -3.960755) (xy 50.097757 -3.890845) (xy 50.191897 -3.827347)
			(xy 50.290237 -3.77057) (xy 50.392297 -3.720792) (xy 50.497582 -3.678254) (xy 50.605577 -3.643164)
			(xy 50.715757 -3.615693) (xy 50.827585 -3.595975) (xy 50.940516 -3.584105) (xy 51.054 -3.580143)
			(xy 51.167484 -3.584105) (xy 51.280415 -3.595975) (xy 51.392243 -3.615693) (xy 51.502423 -3.643164)
			(xy 51.610418 -3.678254) (xy 51.715703 -3.720792) (xy 51.817763 -3.77057) (xy 51.916103 -3.827347)
			(xy 52.010243 -3.890845) (xy 52.099724 -3.960755) (xy 52.18411 -4.036737) (xy 52.262991 -4.11842)
			(xy 52.335981 -4.205407) (xy 52.402726 -4.297273) (xy 52.4629 -4.393571) (xy 52.51621 -4.493833)
			(xy 52.562396 -4.597568) (xy 52.601233 -4.704273) (xy 52.632533 -4.813428) (xy 52.656142 -4.924499)
			(xy 52.671945 -5.036947) (xy 52.679866 -5.150223) (xy 52.680362 -5.207) (xy 52.679866 -5.263777)
			(xy 52.671945 -5.377053) (xy 52.656142 -5.489501) (xy 52.632533 -5.600572) (xy 52.601233 -5.709727)
			(xy 52.562396 -5.816432) (xy 52.51621 -5.920167) (xy 52.4629 -6.020429) (xy 52.402726 -6.116727)
			(xy 52.335981 -6.208593) (xy 52.262991 -6.29558) (xy 52.18411 -6.377263) (xy 52.099724 -6.453245)
			(xy 52.010243 -6.523155) (xy 51.916103 -6.586653) (xy 51.817763 -6.64343) (xy 51.715703 -6.693208)
			(xy 51.610418 -6.735746) (xy 51.502423 -6.770836) (xy 51.392243 -6.798307) (xy 51.280415 -6.818025)
			(xy 51.167484 -6.829895) (xy 51.054 -6.833858) (xy 50.940516 -6.829895) (xy 50.827585 -6.818025)
			(xy 50.715757 -6.798307) (xy 50.605577 -6.770836) (xy 50.497582 -6.735746) (xy 50.392297 -6.693208)
			(xy 50.290237 -6.64343) (xy 50.191897 -6.586653) (xy 50.097757 -6.523155) (xy 50.008276 -6.453245)
			(xy 49.92389 -6.377263) (xy 49.845009 -6.29558) (xy 49.772019 -6.208593) (xy 49.705274 -6.116727)
			(xy 49.6451 -6.020429) (xy 49.59179 -5.920167) (xy 49.545604 -5.816432) (xy 49.506767 -5.709727)
			(xy 49.475467 -5.600572) (xy 49.451858 -5.489501) (xy 49.436055 -5.377053) (xy 49.428134 -5.263777)
			(xy 48.221646 -5.263777) (xy 48.221646 -12.109944) (xy 101.98201 -12.109944) (xy 101.98201 -11.890016)
			(xy 101.990043 -11.670233) (xy 102.006096 -11.450891) (xy 102.03015 -11.232282) (xy 102.062172 -11.014696)
			(xy 102.102119 -10.798426) (xy 102.149938 -10.583759) (xy 102.205566 -10.370981) (xy 102.268927 -10.160377)
			(xy 102.339938 -9.952227) (xy 102.418503 -9.74681) (xy 102.504518 -9.5444) (xy 102.597869 -9.345265)
			(xy 102.698429 -9.149673) (xy 102.806066 -8.957884) (xy 102.920636 -8.770155) (xy 103.041986 -8.586734)
			(xy 103.169953 -8.407868) (xy 103.304368 -8.233795) (xy 103.445051 -8.064748) (xy 103.591813 -7.900951)
			(xy 103.74446 -7.742623) (xy 103.902788 -7.589976) (xy 104.066585 -7.443213) (xy 104.235632 -7.302531)
			(xy 104.409705 -7.168116) (xy 104.588571 -7.040148) (xy 104.771991 -6.918798) (xy 104.959721 -6.804228)
			(xy 105.15151 -6.696591) (xy 105.347102 -6.59603) (xy 105.546236 -6.50268) (xy 105.748647 -6.416665)
			(xy 105.954064 -6.338099) (xy 106.162213 -6.267088) (xy 106.372817 -6.203727) (xy 106.585595 -6.148099)
			(xy 106.800262 -6.10028) (xy 107.016532 -6.060333) (xy 107.234118 -6.028311) (xy 107.452727 -6.004257)
			(xy 107.672069 -5.988203) (xy 107.891852 -5.98017) (xy 108.001816 -5.979668) (xy 129.998216 -5.979668)
			(xy 130.108181 -5.980172) (xy 130.327963 -5.988204) (xy 130.547305 -6.004258) (xy 130.765915 -6.028312)
			(xy 130.9835 -6.060334) (xy 131.199771 -6.100281) (xy 131.414438 -6.1481) (xy 131.627216 -6.203727)
			(xy 131.83782 -6.267088) (xy 132.04597 -6.338099) (xy 132.251387 -6.416664) (xy 132.453798 -6.502679)
			(xy 132.652932 -6.59603) (xy 132.848524 -6.69659) (xy 133.040313 -6.804227) (xy 133.228043 -6.918797)
			(xy 133.411464 -7.040147) (xy 133.59033 -7.168115) (xy 133.764403 -7.302529) (xy 133.933451 -7.443212)
			(xy 134.097248 -7.589975) (xy 134.255576 -7.742622) (xy 134.408223 -7.900949) (xy 134.554986 -8.064746)
			(xy 134.695668 -8.233794) (xy 134.830083 -8.407867) (xy 134.958051 -8.586733) (xy 135.079401 -8.770153)
			(xy 135.193971 -8.957883) (xy 135.301608 -9.149672) (xy 135.402169 -9.345264) (xy 135.495519 -9.544398)
			(xy 135.581534 -9.746809) (xy 135.6601 -9.952226) (xy 135.731111 -10.160376) (xy 135.794472 -10.37098)
			(xy 135.850099 -10.583758) (xy 135.897919 -10.798425) (xy 135.937866 -11.014696) (xy 135.969888 -11.232281)
			(xy 135.993942 -11.450891) (xy 136.009995 -11.670233) (xy 136.018028 -11.890015) (xy 136.018028 -12.109945)
			(xy 136.009995 -12.329727) (xy 135.993942 -12.549069) (xy 135.969888 -12.767679) (xy 135.937866 -12.985264)
			(xy 135.897919 -13.201535) (xy 135.850099 -13.416202) (xy 135.794472 -13.62898) (xy 135.731111 -13.839584)
			(xy 135.6601 -14.047734) (xy 135.581534 -14.253151) (xy 135.495519 -14.455562) (xy 135.402169 -14.654696)
			(xy 135.301608 -14.850288) (xy 135.193971 -15.042077) (xy 135.079401 -15.229807) (xy 134.958051 -15.413227)
			(xy 134.830083 -15.592093) (xy 134.695668 -15.766166) (xy 134.554986 -15.935214) (xy 134.408223 -16.099011)
			(xy 134.255576 -16.257338) (xy 134.097248 -16.409985) (xy 133.933451 -16.556748) (xy 133.764403 -16.697431)
			(xy 133.59033 -16.831845) (xy 133.411464 -16.959813) (xy 133.228043 -17.081163) (xy 133.040313 -17.195733)
			(xy 132.848524 -17.30337) (xy 132.652932 -17.40393) (xy 132.453798 -17.497281) (xy 132.251387 -17.583296)
			(xy 132.04597 -17.661861) (xy 131.83782 -17.732872) (xy 131.627216 -17.796233) (xy 131.414438 -17.85186)
			(xy 131.199771 -17.899679) (xy 130.9835 -17.939626) (xy 130.765915 -17.971648) (xy 130.547305 -17.995702)
			(xy 130.327963 -18.011756) (xy 130.108181 -18.019788) (xy 129.998216 -18.020284) (xy 108.001816 -18.020284)
			(xy 107.891852 -18.01979) (xy 107.672069 -18.011757) (xy 107.452727 -17.995703) (xy 107.234118 -17.971649)
			(xy 107.016532 -17.939627) (xy 106.800262 -17.89968) (xy 106.585595 -17.851861) (xy 106.372817 -17.796233)
			(xy 106.162213 -17.732872) (xy 105.954064 -17.661861) (xy 105.748647 -17.583295) (xy 105.546236 -17.49728)
			(xy 105.347102 -17.40393) (xy 105.15151 -17.303369) (xy 104.959721 -17.195732) (xy 104.771991 -17.081162)
			(xy 104.588571 -16.959812) (xy 104.409705 -16.831844) (xy 104.235632 -16.697429) (xy 104.066585 -16.556747)
			(xy 103.902788 -16.409984) (xy 103.74446 -16.257337) (xy 103.591813 -16.099009) (xy 103.445051 -15.935212)
			(xy 103.304368 -15.766165) (xy 103.169953 -15.592092) (xy 103.041986 -15.413226) (xy 102.920636 -15.229805)
			(xy 102.806066 -15.042076) (xy 102.698429 -14.850287) (xy 102.597869 -14.654695) (xy 102.504518 -14.45556)
			(xy 102.418503 -14.25315) (xy 102.339938 -14.047733) (xy 102.268927 -13.839583) (xy 102.205566 -13.628979)
			(xy 102.149938 -13.416201) (xy 102.102119 -13.201534) (xy 102.062172 -12.985264) (xy 102.03015 -12.767678)
			(xy 102.006096 -12.549069) (xy 101.990043 -12.329727) (xy 101.98201 -12.109944) (xy 48.221646 -12.109944)
			(xy 48.221646 -29.197554) (xy 44.47921 -32.93999) (xy 59.041799 -32.93999) (xy 59.045806 -32.755097)
			(xy 59.057818 -32.57055) (xy 59.077813 -32.386697) (xy 59.105754 -32.203883) (xy 59.141587 -32.022451)
			(xy 59.185247 -31.842742) (xy 59.23665 -31.665092) (xy 59.295701 -31.489836) (xy 59.362288 -31.317303)
			(xy 59.436286 -31.147816) (xy 59.517557 -30.981693) (xy 59.605948 -30.819247) (xy 59.701293 -30.660783)
			(xy 59.803413 -30.506597) (xy 59.912116 -30.35698) (xy 60.027199 -30.212212) (xy 60.148444 -30.072566)
			(xy 60.275625 -29.938302) (xy 60.408503 -29.809674) (xy 60.546828 -29.686923) (xy 60.690341 -29.570279)
			(xy 60.838771 -29.459962) (xy 60.991842 -29.356177) (xy 61.149264 -29.259121) (xy 61.310743 -29.168976)
			(xy 61.475975 -29.08591) (xy 61.644651 -29.01008) (xy 61.816453 -28.941628) (xy 61.991059 -28.880682)
			(xy 62.168141 -28.827357) (xy 62.347367 -28.781754) (xy 62.5284 -28.743956) (xy 62.710901 -28.714037)
			(xy 62.894526 -28.692051) (xy 63.078932 -28.678041) (xy 63.263771 -28.672031) (xy 63.448697 -28.674035)
			(xy 63.633363 -28.684047) (xy 63.817421 -28.702049) (xy 64.000527 -28.728008) (xy 64.182337 -28.761874)
			(xy 64.362509 -28.803585) (xy 64.540705 -28.85306) (xy 64.71659 -28.910209) (xy 64.889835 -28.974923)
			(xy 65.060114 -29.047081) (xy 65.227107 -29.126548) (xy 65.390501 -29.213174) (xy 65.549989 -29.306797)
			(xy 65.705272 -29.40724) (xy 65.856058 -29.514316) (xy 66.002064 -29.627824) (xy 66.143015 -29.747549)
			(xy 66.278649 -29.873268) (xy 66.408708 -30.004745) (xy 66.532951 -30.141732) (xy 66.651143 -30.283973)
			(xy 66.763062 -30.4312) (xy 66.868498 -30.583137) (xy 66.967254 -30.739498) (xy 67.059143 -30.899991)
			(xy 67.143994 -31.064314) (xy 67.221647 -31.232158) (xy 67.291956 -31.403209) (xy 67.35479 -31.577144)
			(xy 67.41003 -31.753639) (xy 67.457572 -31.93236) (xy 67.497328 -32.112973) (xy 67.529223 -32.295139)
			(xy 67.553197 -32.478515) (xy 67.569204 -32.662758) (xy 67.577215 -32.847522) (xy 67.577716 -32.93999)
			(xy 67.577215 -33.032458) (xy 67.569204 -33.217222) (xy 67.553197 -33.401465) (xy 67.529223 -33.584841)
			(xy 67.497328 -33.767007) (xy 67.457572 -33.94762) (xy 67.41003 -34.126341) (xy 67.35479 -34.302836)
			(xy 67.291956 -34.476771) (xy 67.221647 -34.647822) (xy 67.143994 -34.815666) (xy 67.059143 -34.979989)
			(xy 66.967254 -35.140482) (xy 66.868498 -35.296843) (xy 66.763062 -35.44878) (xy 66.739335 -35.479993)
			(xy 73.59425 -35.479993) (xy 73.598088 -35.363144) (xy 73.609583 -35.2468) (xy 73.628687 -35.13146)
			(xy 73.655316 -35.017621) (xy 73.689357 -34.905776) (xy 73.730662 -34.796404) (xy 73.779054 -34.689978)
			(xy 73.834323 -34.586956) (xy 73.896232 -34.487782) (xy 73.964515 -34.392883) (xy 74.038876 -34.302669)
			(xy 74.078592 -34.259774) (xy 74.084926 -34.2525) (xy 74.092101 -34.234611) (xy 74.092562 -34.224976)
			(xy 74.092562 -34.195004) (xy 74.092121 -34.185365) (xy 74.084939 -34.167474) (xy 74.078592 -34.160206)
			(xy 74.037085 -34.115347) (xy 73.959622 -34.020801) (xy 73.888826 -33.921165) (xy 73.82503 -33.816908)
			(xy 73.768536 -33.70852) (xy 73.719608 -33.596513) (xy 73.678479 -33.481414) (xy 73.64534 -33.363765)
			(xy 73.620348 -33.24412) (xy 73.603622 -33.123043) (xy 73.595239 -33.001104) (xy 73.594722 -32.93999)
			(xy 73.595224 -32.879191) (xy 73.603522 -32.757877) (xy 73.620081 -32.637411) (xy 73.644821 -32.518357)
			(xy 73.677628 -32.401268) (xy 73.71835 -32.286692) (xy 73.766795 -32.175161) (xy 73.822739 -32.067196)
			(xy 73.885919 -31.963301) (xy 73.956043 -31.863959) (xy 74.032783 -31.769635) (xy 74.11578 -31.680767)
			(xy 74.204649 -31.597771) (xy 74.298974 -31.521032) (xy 74.398316 -31.45091) (xy 74.502212 -31.38773)
			(xy 74.610177 -31.331787) (xy 74.721708 -31.283343) (xy 74.836286 -31.242623) (xy 74.953374 -31.209817)
			(xy 75.072429 -31.185078) (xy 75.192895 -31.16852) (xy 75.314209 -31.160223) (xy 75.375008 -31.159704)
			(xy 75.436121 -31.160244) (xy 75.558059 -31.168627) (xy 75.679135 -31.185353) (xy 75.798779 -31.210344)
			(xy 75.916427 -31.243482) (xy 76.031526 -31.28461) (xy 76.143532 -31.333535) (xy 76.25192 -31.390027)
			(xy 76.356178 -31.453819) (xy 76.455815 -31.524611) (xy 76.550363 -31.60207) (xy 76.595224 -31.643574)
			(xy 76.60249 -31.649919) (xy 76.620386 -31.657085) (xy 76.630022 -31.657544) (xy 76.659994 -31.657544)
			(xy 76.669633 -31.657106) (xy 76.687525 -31.649922) (xy 76.694792 -31.643574) (xy 76.739649 -31.602065)
			(xy 76.834195 -31.524602) (xy 76.933832 -31.453806) (xy 77.038089 -31.390011) (xy 77.146477 -31.333517)
			(xy 77.258484 -31.28459) (xy 77.373584 -31.24346) (xy 77.491233 -31.210322) (xy 77.610878 -31.185331)
			(xy 77.731955 -31.168604) (xy 77.853894 -31.160222) (xy 77.915008 -31.159704) (xy 77.975807 -31.160225)
			(xy 78.09712 -31.168524) (xy 78.217585 -31.185082) (xy 78.336638 -31.209822) (xy 78.453726 -31.242629)
			(xy 78.568302 -31.283349) (xy 78.679832 -31.331794) (xy 78.787797 -31.387737) (xy 78.891691 -31.450917)
			(xy 78.991032 -31.521039) (xy 79.085357 -31.597778) (xy 79.174224 -31.680774) (xy 79.257221 -31.769642)
			(xy 79.333959 -31.863966) (xy 79.404082 -31.963307) (xy 79.467262 -32.067202) (xy 79.523205 -32.175166)
			(xy 79.57165 -32.286696) (xy 79.612371 -32.401272) (xy 79.645178 -32.51836) (xy 79.669918 -32.637413)
			(xy 79.686476 -32.757878) (xy 79.694774 -32.879191) (xy 79.695294 -32.93999) (xy 79.694808 -33.001104)
			(xy 79.686419 -33.123043) (xy 79.669687 -33.244121) (xy 79.644691 -33.363765) (xy 79.611548 -33.481414)
			(xy 79.570415 -33.596512) (xy 79.521484 -33.708519) (xy 79.464988 -33.816906) (xy 79.401191 -33.921163)
			(xy 79.330393 -34.020799) (xy 79.25293 -34.115346) (xy 79.211424 -34.160206) (xy 79.205087 -34.167477)
			(xy 79.197916 -34.185369) (xy 79.197454 -34.195004) (xy 79.197454 -34.224976) (xy 79.197901 -34.234614)
			(xy 79.205079 -34.252506) (xy 79.211424 -34.259774) (xy 79.251131 -34.302677) (xy 79.325495 -34.392889)
			(xy 79.39378 -34.487786) (xy 79.455692 -34.586959) (xy 79.510964 -34.68998) (xy 79.559357 -34.796405)
			(xy 79.600664 -34.905776) (xy 79.634706 -35.017622) (xy 79.661337 -35.13146) (xy 79.680441 -35.246799)
			(xy 79.691937 -35.363144) (xy 79.695775 -35.479993) (xy 79.691938 -35.596841) (xy 79.680443 -35.713186)
			(xy 79.66134 -35.828526) (xy 79.63471 -35.942364) (xy 79.600669 -36.05421) (xy 79.559363 -36.163582)
			(xy 79.51097 -36.270007) (xy 79.455699 -36.373029) (xy 79.393788 -36.472202) (xy 79.325504 -36.567099)
			(xy 79.251141 -36.657312) (xy 79.211424 -36.700206) (xy 79.205087 -36.707477) (xy 79.197916 -36.725369)
			(xy 79.197454 -36.735004) (xy 79.197454 -36.764976) (xy 79.197901 -36.774614) (xy 79.205079 -36.792506)
			(xy 79.211424 -36.799774) (xy 79.251131 -36.842677) (xy 79.325495 -36.932889) (xy 79.39378 -37.027786)
			(xy 79.455692 -37.126959) (xy 79.510964 -37.22998) (xy 79.559357 -37.336405) (xy 79.600664 -37.445776)
			(xy 79.634706 -37.557622) (xy 79.661337 -37.67146) (xy 79.680441 -37.786799) (xy 79.691937 -37.903144)
			(xy 79.695775 -38.019993) (xy 82.48425 -38.019993) (xy 82.488088 -37.903144) (xy 82.499583 -37.7868)
			(xy 82.518687 -37.67146) (xy 82.545316 -37.557621) (xy 82.579357 -37.445776) (xy 82.620662 -37.336404)
			(xy 82.669054 -37.229978) (xy 82.724323 -37.126956) (xy 82.786232 -37.027782) (xy 82.854515 -36.932883)
			(xy 82.928876 -36.842669) (xy 82.968592 -36.799774) (xy 82.974926 -36.7925) (xy 82.982101 -36.774611)
			(xy 82.982562 -36.764976) (xy 82.982562 -36.735004) (xy 82.982121 -36.725365) (xy 82.974939 -36.707474)
			(xy 82.968592 -36.700206) (xy 82.928867 -36.65732) (xy 82.854506 -36.567105) (xy 82.786224 -36.472206)
			(xy 82.724316 -36.373032) (xy 82.669047 -36.270009) (xy 82.620656 -36.163583) (xy 82.579352 -36.054211)
			(xy 82.545313 -35.942365) (xy 82.518684 -35.828526) (xy 82.499581 -35.713186) (xy 82.488087 -35.596841)
			(xy 82.48425 -35.479993) (xy 82.488088 -35.363144) (xy 82.499583 -35.2468) (xy 82.518687 -35.13146)
			(xy 82.545316 -35.017621) (xy 82.579357 -34.905776) (xy 82.620662 -34.796404) (xy 82.669054 -34.689978)
			(xy 82.724323 -34.586956) (xy 82.786232 -34.487782) (xy 82.854515 -34.392883) (xy 82.928876 -34.302669)
			(xy 82.968592 -34.259774) (xy 82.974926 -34.2525) (xy 82.982101 -34.234611) (xy 82.982562 -34.224976)
			(xy 82.982562 -34.195004) (xy 82.982121 -34.185365) (xy 82.974939 -34.167474) (xy 82.968592 -34.160206)
			(xy 82.927085 -34.115347) (xy 82.849622 -34.020801) (xy 82.778826 -33.921165) (xy 82.71503 -33.816908)
			(xy 82.658536 -33.70852) (xy 82.609608 -33.596513) (xy 82.568479 -33.481414) (xy 82.53534 -33.363765)
			(xy 82.510348 -33.24412) (xy 82.493622 -33.123043) (xy 82.485239 -33.001104) (xy 82.484722 -32.93999)
			(xy 82.485224 -32.879191) (xy 82.493522 -32.757877) (xy 82.510081 -32.637411) (xy 82.534821 -32.518357)
			(xy 82.567628 -32.401268) (xy 82.60835 -32.286692) (xy 82.656795 -32.175161) (xy 82.712739 -32.067196)
			(xy 82.775919 -31.963301) (xy 82.846043 -31.863959) (xy 82.922783 -31.769635) (xy 83.00578 -31.680767)
			(xy 83.094649 -31.597771) (xy 83.188974 -31.521032) (xy 83.288316 -31.45091) (xy 83.392212 -31.38773)
			(xy 83.500177 -31.331787) (xy 83.611708 -31.283343) (xy 83.726286 -31.242623) (xy 83.843374 -31.209817)
			(xy 83.962429 -31.185078) (xy 84.082895 -31.16852) (xy 84.204209 -31.160223) (xy 84.265008 -31.159704)
			(xy 84.326121 -31.160244) (xy 84.448059 -31.168627) (xy 84.569135 -31.185353) (xy 84.688779 -31.210344)
			(xy 84.806427 -31.243482) (xy 84.921526 -31.28461) (xy 85.033532 -31.333535) (xy 85.14192 -31.390027)
			(xy 85.246178 -31.453819) (xy 85.345815 -31.524611) (xy 85.440363 -31.60207) (xy 85.485224 -31.643574)
			(xy 85.49249 -31.649919) (xy 85.510386 -31.657085) (xy 85.520022 -31.657544) (xy 85.549994 -31.657544)
			(xy 85.559633 -31.657106) (xy 85.577525 -31.649922) (xy 85.584792 -31.643574) (xy 85.629649 -31.602065)
			(xy 85.724195 -31.524602) (xy 85.823832 -31.453806) (xy 85.928089 -31.390011) (xy 86.036477 -31.333517)
			(xy 86.148484 -31.28459) (xy 86.263584 -31.24346) (xy 86.381233 -31.210322) (xy 86.500878 -31.185331)
			(xy 86.621955 -31.168604) (xy 86.743894 -31.160222) (xy 86.805008 -31.159704) (xy 86.865807 -31.160225)
			(xy 86.98712 -31.168524) (xy 87.107585 -31.185082) (xy 87.226638 -31.209822) (xy 87.343726 -31.242629)
			(xy 87.458302 -31.283349) (xy 87.569832 -31.331794) (xy 87.677797 -31.387737) (xy 87.781691 -31.450917)
			(xy 87.881032 -31.521039) (xy 87.975357 -31.597778) (xy 88.064224 -31.680774) (xy 88.147221 -31.769642)
			(xy 88.223959 -31.863966) (xy 88.294082 -31.963307) (xy 88.357262 -32.067202) (xy 88.413205 -32.175166)
			(xy 88.46165 -32.286696) (xy 88.502371 -32.401272) (xy 88.535178 -32.51836) (xy 88.559918 -32.637413)
			(xy 88.576476 -32.757878) (xy 88.584774 -32.879191) (xy 88.585294 -32.93999) (xy 88.584808 -33.001104)
			(xy 88.576419 -33.123043) (xy 88.559687 -33.244121) (xy 88.534691 -33.363765) (xy 88.501548 -33.481414)
			(xy 88.460415 -33.596512) (xy 88.411484 -33.708519) (xy 88.354988 -33.816906) (xy 88.291191 -33.921163)
			(xy 88.220393 -34.020799) (xy 88.14293 -34.115346) (xy 88.101424 -34.160206) (xy 88.095087 -34.167477)
			(xy 88.087916 -34.185369) (xy 88.087454 -34.195004) (xy 88.087454 -34.224976) (xy 88.087901 -34.234614)
			(xy 88.095079 -34.252506) (xy 88.101424 -34.259774) (xy 88.141131 -34.302677) (xy 88.215495 -34.392889)
			(xy 88.28378 -34.487786) (xy 88.345692 -34.586959) (xy 88.400964 -34.68998) (xy 88.449357 -34.796405)
			(xy 88.490664 -34.905776) (xy 88.524706 -35.017622) (xy 88.551337 -35.13146) (xy 88.570441 -35.246799)
			(xy 88.581937 -35.363144) (xy 88.585775 -35.479993) (xy 88.581938 -35.596841) (xy 88.570443 -35.713186)
			(xy 88.55134 -35.828526) (xy 88.52471 -35.942364) (xy 88.490669 -36.05421) (xy 88.449363 -36.163582)
			(xy 88.40097 -36.270007) (xy 88.345699 -36.373029) (xy 88.283788 -36.472202) (xy 88.215504 -36.567099)
			(xy 88.141141 -36.657312) (xy 88.101424 -36.700206) (xy 88.095087 -36.707477) (xy 88.087916 -36.725369)
			(xy 88.087454 -36.735004) (xy 88.087454 -36.764976) (xy 88.087901 -36.774614) (xy 88.095079 -36.792506)
			(xy 88.101424 -36.799774) (xy 88.141131 -36.842677) (xy 88.215495 -36.932889) (xy 88.28378 -37.027786)
			(xy 88.345692 -37.126959) (xy 88.400964 -37.22998) (xy 88.449357 -37.336405) (xy 88.490664 -37.445776)
			(xy 88.524706 -37.557622) (xy 88.551337 -37.67146) (xy 88.570441 -37.786799) (xy 88.581937 -37.903144)
			(xy 88.585775 -38.019993) (xy 91.37425 -38.019993) (xy 91.378088 -37.903144) (xy 91.389583 -37.7868)
			(xy 91.408687 -37.67146) (xy 91.435316 -37.557621) (xy 91.469357 -37.445776) (xy 91.510662 -37.336404)
			(xy 91.559054 -37.229978) (xy 91.614323 -37.126956) (xy 91.676232 -37.027782) (xy 91.744515 -36.932883)
			(xy 91.818876 -36.842669) (xy 91.858592 -36.799774) (xy 91.864926 -36.7925) (xy 91.872101 -36.774611)
			(xy 91.872562 -36.764976) (xy 91.872562 -36.735004) (xy 91.872121 -36.725365) (xy 91.864939 -36.707474)
			(xy 91.858592 -36.700206) (xy 91.818867 -36.65732) (xy 91.744506 -36.567105) (xy 91.676224 -36.472206)
			(xy 91.614316 -36.373032) (xy 91.559047 -36.270009) (xy 91.510656 -36.163583) (xy 91.469352 -36.054211)
			(xy 91.435313 -35.942365) (xy 91.408684 -35.828526) (xy 91.389581 -35.713186) (xy 91.378087 -35.596841)
			(xy 91.37425 -35.479993) (xy 91.378088 -35.363144) (xy 91.389583 -35.2468) (xy 91.408687 -35.13146)
			(xy 91.435316 -35.017621) (xy 91.469357 -34.905776) (xy 91.510662 -34.796404) (xy 91.559054 -34.689978)
			(xy 91.614323 -34.586956) (xy 91.676232 -34.487782) (xy 91.744515 -34.392883) (xy 91.818876 -34.302669)
			(xy 91.858592 -34.259774) (xy 91.864926 -34.2525) (xy 91.872101 -34.234611) (xy 91.872562 -34.224976)
			(xy 91.872562 -34.195004) (xy 91.872121 -34.185365) (xy 91.864939 -34.167474) (xy 91.858592 -34.160206)
			(xy 91.817085 -34.115347) (xy 91.739622 -34.020801) (xy 91.668826 -33.921165) (xy 91.60503 -33.816908)
			(xy 91.548536 -33.70852) (xy 91.499608 -33.596513) (xy 91.458479 -33.481414) (xy 91.42534 -33.363765)
			(xy 91.400348 -33.24412) (xy 91.383622 -33.123043) (xy 91.375239 -33.001104) (xy 91.374722 -32.93999)
			(xy 91.375224 -32.879191) (xy 91.383522 -32.757877) (xy 91.400081 -32.637411) (xy 91.424821 -32.518357)
			(xy 91.457628 -32.401268) (xy 91.49835 -32.286692) (xy 91.546795 -32.175161) (xy 91.602739 -32.067196)
			(xy 91.665919 -31.963301) (xy 91.736043 -31.863959) (xy 91.812783 -31.769635) (xy 91.89578 -31.680767)
			(xy 91.984649 -31.597771) (xy 92.078974 -31.521032) (xy 92.178316 -31.45091) (xy 92.282212 -31.38773)
			(xy 92.390177 -31.331787) (xy 92.501708 -31.283343) (xy 92.616286 -31.242623) (xy 92.733374 -31.209817)
			(xy 92.852429 -31.185078) (xy 92.972895 -31.16852) (xy 93.094209 -31.160223) (xy 93.155008 -31.159704)
			(xy 93.216121 -31.160244) (xy 93.338059 -31.168627) (xy 93.459135 -31.185353) (xy 93.578779 -31.210344)
			(xy 93.696427 -31.243482) (xy 93.811526 -31.28461) (xy 93.923532 -31.333535) (xy 94.03192 -31.390027)
			(xy 94.136178 -31.453819) (xy 94.235815 -31.524611) (xy 94.330363 -31.60207) (xy 94.375224 -31.643574)
			(xy 94.38249 -31.649919) (xy 94.400386 -31.657085) (xy 94.410022 -31.657544) (xy 94.439994 -31.657544)
			(xy 94.449633 -31.657106) (xy 94.467525 -31.649922) (xy 94.474792 -31.643574) (xy 94.519649 -31.602065)
			(xy 94.614195 -31.524602) (xy 94.713832 -31.453806) (xy 94.818089 -31.390011) (xy 94.926477 -31.333517)
			(xy 95.038484 -31.28459) (xy 95.153584 -31.24346) (xy 95.271233 -31.210322) (xy 95.390878 -31.185331)
			(xy 95.511955 -31.168604) (xy 95.633894 -31.160222) (xy 95.695008 -31.159704) (xy 95.755807 -31.160225)
			(xy 95.87712 -31.168524) (xy 95.997585 -31.185082) (xy 96.116638 -31.209822) (xy 96.233726 -31.242629)
			(xy 96.348302 -31.283349) (xy 96.459832 -31.331794) (xy 96.567797 -31.387737) (xy 96.671691 -31.450917)
			(xy 96.771032 -31.521039) (xy 96.865357 -31.597778) (xy 96.954224 -31.680774) (xy 97.037221 -31.769642)
			(xy 97.113959 -31.863966) (xy 97.184082 -31.963307) (xy 97.247262 -32.067202) (xy 97.303205 -32.175166)
			(xy 97.35165 -32.286696) (xy 97.392371 -32.401272) (xy 97.425178 -32.51836) (xy 97.449918 -32.637413)
			(xy 97.466476 -32.757878) (xy 97.474774 -32.879191) (xy 97.475294 -32.93999) (xy 130.161799 -32.93999)
			(xy 130.165806 -32.755097) (xy 130.177818 -32.57055) (xy 130.197813 -32.386697) (xy 130.225754 -32.203883)
			(xy 130.261587 -32.022451) (xy 130.305247 -31.842742) (xy 130.35665 -31.665092) (xy 130.415701 -31.489836)
			(xy 130.482288 -31.317303) (xy 130.556286 -31.147816) (xy 130.637557 -30.981693) (xy 130.725948 -30.819247)
			(xy 130.821293 -30.660783) (xy 130.923413 -30.506597) (xy 131.032116 -30.35698) (xy 131.147199 -30.212212)
			(xy 131.268444 -30.072566) (xy 131.395625 -29.938302) (xy 131.528503 -29.809674) (xy 131.666828 -29.686923)
			(xy 131.810341 -29.570279) (xy 131.958771 -29.459962) (xy 132.111842 -29.356177) (xy 132.269264 -29.259121)
			(xy 132.430743 -29.168976) (xy 132.595975 -29.08591) (xy 132.764651 -29.01008) (xy 132.936453 -28.941628)
			(xy 133.111059 -28.880682) (xy 133.288141 -28.827357) (xy 133.467367 -28.781754) (xy 133.6484 -28.743956)
			(xy 133.830901 -28.714037) (xy 134.014526 -28.692051) (xy 134.198932 -28.678041) (xy 134.383771 -28.672031)
			(xy 134.568697 -28.674035) (xy 134.753363 -28.684047) (xy 134.937421 -28.702049) (xy 135.120527 -28.728008)
			(xy 135.302337 -28.761874) (xy 135.482509 -28.803585) (xy 135.660705 -28.85306) (xy 135.83659 -28.910209)
			(xy 136.009835 -28.974923) (xy 136.180114 -29.047081) (xy 136.347107 -29.126548) (xy 136.510501 -29.213174)
			(xy 136.669989 -29.306797) (xy 136.825272 -29.40724) (xy 136.976058 -29.514316) (xy 137.122064 -29.627824)
			(xy 137.263015 -29.747549) (xy 137.398649 -29.873268) (xy 137.528708 -30.004745) (xy 137.652951 -30.141732)
			(xy 137.771143 -30.283973) (xy 137.883062 -30.4312) (xy 137.988498 -30.583137) (xy 138.087254 -30.739498)
			(xy 138.179143 -30.899991) (xy 138.263994 -31.064314) (xy 138.341647 -31.232158) (xy 138.411956 -31.403209)
			(xy 138.47479 -31.577144) (xy 138.53003 -31.753639) (xy 138.577572 -31.93236) (xy 138.617328 -32.112973)
			(xy 138.649223 -32.295139) (xy 138.673197 -32.478515) (xy 138.689204 -32.662758) (xy 138.697215 -32.847522)
			(xy 138.697716 -32.93999) (xy 138.697215 -33.032458) (xy 138.689204 -33.217222) (xy 138.673197 -33.401465)
			(xy 138.649223 -33.584841) (xy 138.617328 -33.767007) (xy 138.577572 -33.94762) (xy 138.53003 -34.126341)
			(xy 138.47479 -34.302836) (xy 138.411956 -34.476771) (xy 138.341647 -34.647822) (xy 138.263994 -34.815666)
			(xy 138.179143 -34.979989) (xy 138.087254 -35.140482) (xy 137.988498 -35.296843) (xy 137.883062 -35.44878)
			(xy 137.771143 -35.596007) (xy 137.652951 -35.738248) (xy 137.528708 -35.875235) (xy 137.398649 -36.006712)
			(xy 137.263015 -36.132431) (xy 137.122064 -36.252156) (xy 136.976058 -36.365664) (xy 136.825272 -36.47274)
			(xy 136.669989 -36.573183) (xy 136.510501 -36.666806) (xy 136.347107 -36.753432) (xy 136.180114 -36.832899)
			(xy 136.009835 -36.905057) (xy 135.83659 -36.969771) (xy 135.660705 -37.02692) (xy 135.482509 -37.076395)
			(xy 135.302337 -37.118106) (xy 135.120527 -37.151972) (xy 134.937421 -37.177931) (xy 134.753363 -37.195933)
			(xy 134.568697 -37.205945) (xy 134.383771 -37.207949) (xy 134.198932 -37.201939) (xy 134.014526 -37.187929)
			(xy 133.830901 -37.165943) (xy 133.6484 -37.136024) (xy 133.467367 -37.098226) (xy 133.288141 -37.052623)
			(xy 133.111059 -36.999298) (xy 132.936453 -36.938352) (xy 132.764651 -36.8699) (xy 132.595975 -36.79407)
			(xy 132.430743 -36.711004) (xy 132.269264 -36.620859) (xy 132.111842 -36.523803) (xy 131.958771 -36.420018)
			(xy 131.810341 -36.309701) (xy 131.666828 -36.193057) (xy 131.528503 -36.070306) (xy 131.395625 -35.941678)
			(xy 131.268444 -35.807414) (xy 131.147199 -35.667768) (xy 131.032116 -35.523) (xy 130.923413 -35.373383)
			(xy 130.821293 -35.219197) (xy 130.725948 -35.060733) (xy 130.637557 -34.898287) (xy 130.556286 -34.732164)
			(xy 130.482288 -34.562677) (xy 130.415701 -34.390144) (xy 130.35665 -34.214888) (xy 130.305247 -34.037238)
			(xy 130.261587 -33.857529) (xy 130.225754 -33.676097) (xy 130.197813 -33.493283) (xy 130.177818 -33.30943)
			(xy 130.165806 -33.124883) (xy 130.161799 -32.93999) (xy 97.475294 -32.93999) (xy 97.474808 -33.001104)
			(xy 97.466419 -33.123043) (xy 97.449687 -33.244121) (xy 97.424691 -33.363765) (xy 97.391548 -33.481414)
			(xy 97.350415 -33.596512) (xy 97.301484 -33.708519) (xy 97.244988 -33.816906) (xy 97.181191 -33.921163)
			(xy 97.110393 -34.020799) (xy 97.03293 -34.115346) (xy 96.991424 -34.160206) (xy 96.985087 -34.167477)
			(xy 96.977916 -34.185369) (xy 96.977454 -34.195004) (xy 96.977454 -34.224976) (xy 96.977901 -34.234614)
			(xy 96.985079 -34.252506) (xy 96.991424 -34.259774) (xy 97.031131 -34.302677) (xy 97.105495 -34.392889)
			(xy 97.17378 -34.487786) (xy 97.235692 -34.586959) (xy 97.290964 -34.68998) (xy 97.339357 -34.796405)
			(xy 97.380664 -34.905776) (xy 97.414706 -35.017622) (xy 97.441337 -35.13146) (xy 97.460441 -35.246799)
			(xy 97.471937 -35.363144) (xy 97.475775 -35.479993) (xy 97.471938 -35.596841) (xy 97.460443 -35.713186)
			(xy 97.44134 -35.828526) (xy 97.41471 -35.942364) (xy 97.380669 -36.05421) (xy 97.339363 -36.163582)
			(xy 97.29097 -36.270007) (xy 97.235699 -36.373029) (xy 97.173788 -36.472202) (xy 97.105504 -36.567099)
			(xy 97.031141 -36.657312) (xy 96.991424 -36.700206) (xy 96.985087 -36.707477) (xy 96.977916 -36.725369)
			(xy 96.977454 -36.735004) (xy 96.977454 -36.764976) (xy 96.977901 -36.774614) (xy 96.985079 -36.792506)
			(xy 96.991424 -36.799774) (xy 97.031131 -36.842677) (xy 97.105495 -36.932889) (xy 97.17378 -37.027786)
			(xy 97.235692 -37.126959) (xy 97.290964 -37.22998) (xy 97.339357 -37.336405) (xy 97.380664 -37.445776)
			(xy 97.414706 -37.557622) (xy 97.441337 -37.67146) (xy 97.460441 -37.786799) (xy 97.471937 -37.903144)
			(xy 97.473464 -37.949632) (xy 164.656777 -37.949632) (xy 164.660784 -37.764739) (xy 164.672796 -37.580192)
			(xy 164.692791 -37.396339) (xy 164.720732 -37.213525) (xy 164.756565 -37.032093) (xy 164.800225 -36.852384)
			(xy 164.851628 -36.674734) (xy 164.910679 -36.499478) (xy 164.977266 -36.326945) (xy 165.051264 -36.157458)
			(xy 165.132535 -35.991335) (xy 165.220926 -35.828889) (xy 165.316271 -35.670425) (xy 165.418391 -35.516239)
			(xy 165.527094 -35.366622) (xy 165.642177 -35.221854) (xy 165.763422 -35.082208) (xy 165.890603 -34.947944)
			(xy 166.023481 -34.819316) (xy 166.161806 -34.696565) (xy 166.305319 -34.579921) (xy 166.453749 -34.469604)
			(xy 166.60682 -34.365819) (xy 166.764242 -34.268763) (xy 166.925721 -34.178618) (xy 167.090953 -34.095552)
			(xy 167.259629 -34.019722) (xy 167.431431 -33.95127) (xy 167.606037 -33.890324) (xy 167.783119 -33.836999)
			(xy 167.962345 -33.791396) (xy 168.143378 -33.753598) (xy 168.325879 -33.723679) (xy 168.509504 -33.701693)
			(xy 168.69391 -33.687683) (xy 168.878749 -33.681673) (xy 169.063675 -33.683677) (xy 169.248341 -33.693689)
			(xy 169.432399 -33.711691) (xy 169.615505 -33.73765) (xy 169.797315 -33.771516) (xy 169.977487 -33.813227)
			(xy 170.155683 -33.862702) (xy 170.331568 -33.919851) (xy 170.504813 -33.984565) (xy 170.675092 -34.056723)
			(xy 170.842085 -34.13619) (xy 171.005479 -34.222816) (xy 171.164967 -34.316439) (xy 171.32025 -34.416882)
			(xy 171.471036 -34.523958) (xy 171.617042 -34.637466) (xy 171.757993 -34.757191) (xy 171.893627 -34.88291)
			(xy 172.023686 -35.014387) (xy 172.147929 -35.151374) (xy 172.266121 -35.293615) (xy 172.37804 -35.440842)
			(xy 172.483476 -35.592779) (xy 172.582232 -35.74914) (xy 172.674121 -35.909633) (xy 172.758972 -36.073956)
			(xy 172.836625 -36.2418) (xy 172.906934 -36.412851) (xy 172.969768 -36.586786) (xy 173.025008 -36.763281)
			(xy 173.07255 -36.942002) (xy 173.112306 -37.122615) (xy 173.144201 -37.304781) (xy 173.168175 -37.488157)
			(xy 173.184182 -37.6724) (xy 173.192193 -37.857164) (xy 173.192694 -37.949632) (xy 173.192193 -38.0421)
			(xy 173.184182 -38.226864) (xy 173.168175 -38.411107) (xy 173.144201 -38.594483) (xy 173.112306 -38.776649)
			(xy 173.07255 -38.957262) (xy 173.025008 -39.135983) (xy 172.969768 -39.312478) (xy 172.906934 -39.486413)
			(xy 172.836625 -39.657464) (xy 172.758972 -39.825308) (xy 172.674121 -39.989631) (xy 172.582232 -40.150124)
			(xy 172.483476 -40.306485) (xy 172.37804 -40.458422) (xy 172.266121 -40.605649) (xy 172.147929 -40.74789)
			(xy 172.023686 -40.884877) (xy 171.893627 -41.016354) (xy 171.757993 -41.142073) (xy 171.617042 -41.261798)
			(xy 171.471036 -41.375306) (xy 171.32025 -41.482382) (xy 171.164967 -41.582825) (xy 171.005479 -41.676448)
			(xy 170.842085 -41.763074) (xy 170.675092 -41.842541) (xy 170.504813 -41.914699) (xy 170.331568 -41.979413)
			(xy 170.155683 -42.036562) (xy 169.977487 -42.086037) (xy 169.797315 -42.127748) (xy 169.615505 -42.161614)
			(xy 169.432399 -42.187573) (xy 169.248341 -42.205575) (xy 169.063675 -42.215587) (xy 168.878749 -42.217591)
			(xy 168.69391 -42.211581) (xy 168.509504 -42.197571) (xy 168.325879 -42.175585) (xy 168.143378 -42.145666)
			(xy 167.962345 -42.107868) (xy 167.783119 -42.062265) (xy 167.606037 -42.00894) (xy 167.431431 -41.947994)
			(xy 167.259629 -41.879542) (xy 167.090953 -41.803712) (xy 166.925721 -41.720646) (xy 166.764242 -41.630501)
			(xy 166.60682 -41.533445) (xy 166.453749 -41.42966) (xy 166.305319 -41.319343) (xy 166.161806 -41.202699)
			(xy 166.023481 -41.079948) (xy 165.890603 -40.95132) (xy 165.763422 -40.817056) (xy 165.642177 -40.67741)
			(xy 165.527094 -40.532642) (xy 165.418391 -40.383025) (xy 165.316271 -40.228839) (xy 165.220926 -40.070375)
			(xy 165.132535 -39.907929) (xy 165.051264 -39.741806) (xy 164.977266 -39.572319) (xy 164.910679 -39.399786)
			(xy 164.851628 -39.22453) (xy 164.800225 -39.04688) (xy 164.756565 -38.867171) (xy 164.720732 -38.685739)
			(xy 164.692791 -38.502925) (xy 164.672796 -38.319072) (xy 164.660784 -38.134525) (xy 164.656777 -37.949632)
			(xy 97.473464 -37.949632) (xy 97.475775 -38.019993) (xy 97.471938 -38.136841) (xy 97.460443 -38.253186)
			(xy 97.44134 -38.368526) (xy 97.41471 -38.482364) (xy 97.380669 -38.59421) (xy 97.339363 -38.703582)
			(xy 97.29097 -38.810007) (xy 97.235699 -38.913029) (xy 97.173788 -39.012202) (xy 97.105504 -39.107099)
			(xy 97.031141 -39.197312) (xy 96.991424 -39.240206) (xy 96.985087 -39.247477) (xy 96.977916 -39.265369)
			(xy 96.977454 -39.275004) (xy 96.977454 -39.304976) (xy 96.977901 -39.314614) (xy 96.985079 -39.332506)
			(xy 96.991424 -39.339774) (xy 97.032924 -39.384639) (xy 97.110387 -39.479184) (xy 97.181183 -39.57882)
			(xy 97.244979 -39.683077) (xy 97.301474 -39.791464) (xy 97.350402 -39.90347) (xy 97.391533 -40.018568)
			(xy 97.424672 -40.136217) (xy 97.449665 -40.255861) (xy 97.466392 -40.376938) (xy 97.474776 -40.498877)
			(xy 97.475294 -40.55999) (xy 97.474769 -40.620789) (xy 97.466471 -40.742103) (xy 97.449914 -40.862568)
			(xy 97.425175 -40.981622) (xy 97.392369 -41.098711) (xy 97.351649 -41.213288) (xy 97.303205 -41.324818)
			(xy 97.247263 -41.432783) (xy 97.184084 -41.536679) (xy 97.113961 -41.636021) (xy 97.037223 -41.730346)
			(xy 96.954227 -41.819214) (xy 96.865359 -41.902211) (xy 96.771035 -41.97895) (xy 96.671694 -42.049074)
			(xy 96.567799 -42.112254) (xy 96.459835 -42.168198) (xy 96.348304 -42.216643) (xy 96.233728 -42.257364)
			(xy 96.11664 -42.290171) (xy 95.997586 -42.314911) (xy 95.877121 -42.331469) (xy 95.755807 -42.339768)
			(xy 95.695008 -42.340276) (xy 95.633894 -42.339796) (xy 95.511954 -42.331407) (xy 95.390877 -42.314675)
			(xy 95.271232 -42.289678) (xy 95.153583 -42.256535) (xy 95.038485 -42.215401) (xy 94.926478 -42.16647)
			(xy 94.818091 -42.109973) (xy 94.713834 -42.046175) (xy 94.614198 -41.975377) (xy 94.519652 -41.897912)
			(xy 94.474792 -41.856406) (xy 94.467513 -41.850079) (xy 94.449628 -41.8429) (xy 94.439994 -41.842436)
			(xy 94.410022 -41.842436) (xy 94.400384 -41.842887) (xy 94.382493 -41.850063) (xy 94.375224 -41.856406)
			(xy 94.330357 -41.897904) (xy 94.235812 -41.975367) (xy 94.136177 -42.046164) (xy 94.03192 -42.10996)
			(xy 93.923534 -42.166455) (xy 93.811528 -42.215384) (xy 93.696429 -42.256515) (xy 93.578781 -42.289654)
			(xy 93.459137 -42.314647) (xy 93.33806 -42.331374) (xy 93.216121 -42.339758) (xy 93.155008 -42.340276)
			(xy 93.094209 -42.339771) (xy 92.972894 -42.331473) (xy 92.852428 -42.314916) (xy 92.733373 -42.290176)
			(xy 92.616284 -42.25737) (xy 92.501706 -42.216649) (xy 92.390175 -42.168204) (xy 92.282209 -42.112261)
			(xy 92.178313 -42.049081) (xy 92.078971 -41.978958) (xy 91.984646 -41.902218) (xy 91.895778 -41.819221)
			(xy 91.81278 -41.730353) (xy 91.736041 -41.636027) (xy 91.665918 -41.536685) (xy 91.602738 -41.432789)
			(xy 91.546795 -41.324823) (xy 91.49835 -41.213292) (xy 91.45763 -41.098714) (xy 91.424823 -40.981625)
			(xy 91.400084 -40.86257) (xy 91.383527 -40.742104) (xy 91.375229 -40.620789) (xy 91.374722 -40.55999)
			(xy 91.375256 -40.498877) (xy 91.383639 -40.376939) (xy 91.400366 -40.255862) (xy 91.425357 -40.136218)
			(xy 91.458495 -40.01857) (xy 91.499624 -39.903471) (xy 91.548549 -39.791465) (xy 91.605042 -39.683077)
			(xy 91.668835 -39.578819) (xy 91.739628 -39.479182) (xy 91.817088 -39.384635) (xy 91.858592 -39.339774)
			(xy 91.864926 -39.3325) (xy 91.872101 -39.314611) (xy 91.872562 -39.304976) (xy 91.872562 -39.275004)
			(xy 91.872121 -39.265365) (xy 91.864939 -39.247474) (xy 91.858592 -39.240206) (xy 91.818867 -39.19732)
			(xy 91.744506 -39.107105) (xy 91.676224 -39.012206) (xy 91.614316 -38.913032) (xy 91.559047 -38.810009)
			(xy 91.510656 -38.703583) (xy 91.469352 -38.594211) (xy 91.435313 -38.482365) (xy 91.408684 -38.368526)
			(xy 91.389581 -38.253186) (xy 91.378087 -38.136841) (xy 91.37425 -38.019993) (xy 88.585775 -38.019993)
			(xy 88.581938 -38.136841) (xy 88.570443 -38.253186) (xy 88.55134 -38.368526) (xy 88.52471 -38.482364)
			(xy 88.490669 -38.59421) (xy 88.449363 -38.703582) (xy 88.40097 -38.810007) (xy 88.345699 -38.913029)
			(xy 88.283788 -39.012202) (xy 88.215504 -39.107099) (xy 88.141141 -39.197312) (xy 88.101424 -39.240206)
			(xy 88.095087 -39.247477) (xy 88.087916 -39.265369) (xy 88.087454 -39.275004) (xy 88.087454 -39.304976)
			(xy 88.087901 -39.314614) (xy 88.095079 -39.332506) (xy 88.101424 -39.339774) (xy 88.142924 -39.384639)
			(xy 88.220387 -39.479184) (xy 88.291183 -39.57882) (xy 88.354979 -39.683077) (xy 88.411474 -39.791464)
			(xy 88.460402 -39.90347) (xy 88.501533 -40.018568) (xy 88.534672 -40.136217) (xy 88.559665 -40.255861)
			(xy 88.576392 -40.376938) (xy 88.584776 -40.498877) (xy 88.585294 -40.55999) (xy 88.584769 -40.620789)
			(xy 88.576471 -40.742103) (xy 88.559914 -40.862568) (xy 88.535175 -40.981622) (xy 88.502369 -41.098711)
			(xy 88.461649 -41.213288) (xy 88.413205 -41.324818) (xy 88.357263 -41.432783) (xy 88.294084 -41.536679)
			(xy 88.223961 -41.636021) (xy 88.147223 -41.730346) (xy 88.064227 -41.819214) (xy 87.975359 -41.902211)
			(xy 87.881035 -41.97895) (xy 87.781694 -42.049074) (xy 87.677799 -42.112254) (xy 87.569835 -42.168198)
			(xy 87.458304 -42.216643) (xy 87.343728 -42.257364) (xy 87.22664 -42.290171) (xy 87.107586 -42.314911)
			(xy 86.987121 -42.331469) (xy 86.865807 -42.339768) (xy 86.805008 -42.340276) (xy 86.743894 -42.339796)
			(xy 86.621954 -42.331407) (xy 86.500877 -42.314675) (xy 86.381232 -42.289678) (xy 86.263583 -42.256535)
			(xy 86.148485 -42.215401) (xy 86.036478 -42.16647) (xy 85.928091 -42.109973) (xy 85.823834 -42.046175)
			(xy 85.724198 -41.975377) (xy 85.629652 -41.897912) (xy 85.584792 -41.856406) (xy 85.577513 -41.850079)
			(xy 85.559628 -41.8429) (xy 85.549994 -41.842436) (xy 85.520022 -41.842436) (xy 85.510384 -41.842887)
			(xy 85.492493 -41.850063) (xy 85.485224 -41.856406) (xy 85.440357 -41.897904) (xy 85.345812 -41.975367)
			(xy 85.246177 -42.046164) (xy 85.14192 -42.10996) (xy 85.033534 -42.166455) (xy 84.921528 -42.215384)
			(xy 84.806429 -42.256515) (xy 84.688781 -42.289654) (xy 84.569137 -42.314647) (xy 84.44806 -42.331374)
			(xy 84.326121 -42.339758) (xy 84.265008 -42.340276) (xy 84.204209 -42.339771) (xy 84.082894 -42.331473)
			(xy 83.962428 -42.314916) (xy 83.843373 -42.290176) (xy 83.726284 -42.25737) (xy 83.611706 -42.216649)
			(xy 83.500175 -42.168204) (xy 83.392209 -42.112261) (xy 83.288313 -42.049081) (xy 83.188971 -41.978958)
			(xy 83.094646 -41.902218) (xy 83.005778 -41.819221) (xy 82.92278 -41.730353) (xy 82.846041 -41.636027)
			(xy 82.775918 -41.536685) (xy 82.712738 -41.432789) (xy 82.656795 -41.324823) (xy 82.60835 -41.213292)
			(xy 82.56763 -41.098714) (xy 82.534823 -40.981625) (xy 82.510084 -40.86257) (xy 82.493527 -40.742104)
			(xy 82.485229 -40.620789) (xy 82.484722 -40.55999) (xy 82.485256 -40.498877) (xy 82.493639 -40.376939)
			(xy 82.510366 -40.255862) (xy 82.535357 -40.136218) (xy 82.568495 -40.01857) (xy 82.609624 -39.903471)
			(xy 82.658549 -39.791465) (xy 82.715042 -39.683077) (xy 82.778835 -39.578819) (xy 82.849628 -39.479182)
			(xy 82.927088 -39.384635) (xy 82.968592 -39.339774) (xy 82.974926 -39.3325) (xy 82.982101 -39.314611)
			(xy 82.982562 -39.304976) (xy 82.982562 -39.275004) (xy 82.982121 -39.265365) (xy 82.974939 -39.247474)
			(xy 82.968592 -39.240206) (xy 82.928867 -39.19732) (xy 82.854506 -39.107105) (xy 82.786224 -39.012206)
			(xy 82.724316 -38.913032) (xy 82.669047 -38.810009) (xy 82.620656 -38.703583) (xy 82.579352 -38.594211)
			(xy 82.545313 -38.482365) (xy 82.518684 -38.368526) (xy 82.499581 -38.253186) (xy 82.488087 -38.136841)
			(xy 82.48425 -38.019993) (xy 79.695775 -38.019993) (xy 79.691938 -38.136841) (xy 79.680443 -38.253186)
			(xy 79.66134 -38.368526) (xy 79.63471 -38.482364) (xy 79.600669 -38.59421) (xy 79.559363 -38.703582)
			(xy 79.51097 -38.810007) (xy 79.455699 -38.913029) (xy 79.393788 -39.012202) (xy 79.325504 -39.107099)
			(xy 79.251141 -39.197312) (xy 79.211424 -39.240206) (xy 79.205087 -39.247477) (xy 79.197916 -39.265369)
			(xy 79.197454 -39.275004) (xy 79.197454 -39.304976) (xy 79.197901 -39.314614) (xy 79.205079 -39.332506)
			(xy 79.211424 -39.339774) (xy 79.252924 -39.384639) (xy 79.330387 -39.479184) (xy 79.401183 -39.57882)
			(xy 79.464979 -39.683077) (xy 79.521474 -39.791464) (xy 79.570402 -39.90347) (xy 79.611533 -40.018568)
			(xy 79.644672 -40.136217) (xy 79.669665 -40.255861) (xy 79.686392 -40.376938) (xy 79.694776 -40.498877)
			(xy 79.695294 -40.55999) (xy 79.694769 -40.620789) (xy 79.686471 -40.742103) (xy 79.669914 -40.862568)
			(xy 79.645175 -40.981622) (xy 79.612369 -41.098711) (xy 79.571649 -41.213288) (xy 79.523205 -41.324818)
			(xy 79.467263 -41.432783) (xy 79.404084 -41.536679) (xy 79.333961 -41.636021) (xy 79.257223 -41.730346)
			(xy 79.174227 -41.819214) (xy 79.085359 -41.902211) (xy 78.991035 -41.97895) (xy 78.891694 -42.049074)
			(xy 78.787799 -42.112254) (xy 78.679835 -42.168198) (xy 78.568304 -42.216643) (xy 78.453728 -42.257364)
			(xy 78.33664 -42.290171) (xy 78.217586 -42.314911) (xy 78.097121 -42.331469) (xy 77.975807 -42.339768)
			(xy 77.915008 -42.340276) (xy 77.85642 -42.339774) (xy 77.739498 -42.332069) (xy 77.623336 -42.316691)
			(xy 77.508437 -42.293708) (xy 77.395298 -42.263218) (xy 77.284409 -42.225354) (xy 77.17625 -42.18028)
			(xy 77.071289 -42.128191) (xy 76.969981 -42.069311) (xy 76.921106 -42.037) (xy 76.911035 -42.030929)
			(xy 76.887755 -42.027829) (xy 76.865531 -42.035425) (xy 76.856844 -42.04335) (xy 76.825156 -42.074297)
			(xy 76.75726 -42.131187) (xy 76.684668 -42.181948) (xy 76.607931 -42.226194) (xy 76.527632 -42.26359)
			(xy 76.444382 -42.29385) (xy 76.358812 -42.316745) (xy 76.271574 -42.332101) (xy 76.18333 -42.339801)
			(xy 76.13904 -42.340276) (xy 74.610976 -42.340276) (xy 74.566624 -42.339815) (xy 74.478256 -42.332098)
			(xy 74.390897 -42.316706) (xy 74.305212 -42.293758) (xy 74.221854 -42.263427) (xy 74.141458 -42.225945)
			(xy 74.064635 -42.181597) (xy 73.991971 -42.130721) (xy 73.924018 -42.073704) (xy 73.861295 -42.01098)
			(xy 73.804278 -41.943028) (xy 73.753402 -41.870363) (xy 73.709054 -41.79354) (xy 73.671572 -41.713144)
			(xy 73.641242 -41.629786) (xy 73.618293 -41.544101) (xy 73.602902 -41.456742) (xy 73.595185 -41.368374)
			(xy 73.594722 -41.324022) (xy 73.594722 -39.795958) (xy 73.595226 -39.751672) (xy 73.602966 -39.663438)
			(xy 73.618349 -39.576212) (xy 73.641258 -39.490653) (xy 73.671521 -39.407411) (xy 73.708906 -39.327115)
			(xy 73.753132 -39.250374) (xy 73.803864 -39.17777) (xy 73.860716 -39.109851) (xy 73.891648 -39.078154)
			(xy 73.899481 -39.069411) (xy 73.907032 -39.047219) (xy 73.904004 -39.023974) (xy 73.897998 -39.013892)
			(xy 73.86569 -38.965015) (xy 73.806805 -38.863709) (xy 73.75471 -38.75875) (xy 73.709631 -38.650592)
			(xy 73.671763 -38.539703) (xy 73.64127 -38.426564) (xy 73.618284 -38.311664) (xy 73.602905 -38.195501)
			(xy 73.595199 -38.078578) (xy 73.594722 -38.01999) (xy 73.595256 -37.958877) (xy 73.603639 -37.836939)
			(xy 73.620366 -37.715862) (xy 73.645357 -37.596218) (xy 73.678495 -37.47857) (xy 73.719624 -37.363471)
			(xy 73.768549 -37.251465) (xy 73.825042 -37.143077) (xy 73.888835 -37.038819) (xy 73.959628 -36.939182)
			(xy 74.037088 -36.844635) (xy 74.078592 -36.799774) (xy 74.084926 -36.7925) (xy 74.092101 -36.774611)
			(xy 74.092562 -36.764976) (xy 74.092562 -36.735004) (xy 74.092121 -36.725365) (xy 74.084939 -36.707474)
			(xy 74.078592 -36.700206) (xy 74.038867 -36.65732) (xy 73.964506 -36.567105) (xy 73.896224 -36.472206)
			(xy 73.834316 -36.373032) (xy 73.779047 -36.270009) (xy 73.730656 -36.163583) (xy 73.689352 -36.054211)
			(xy 73.655313 -35.942365) (xy 73.628684 -35.828526) (xy 73.609581 -35.713186) (xy 73.598087 -35.596841)
			(xy 73.59425 -35.479993) (xy 66.739335 -35.479993) (xy 66.651143 -35.596007) (xy 66.532951 -35.738248)
			(xy 66.408708 -35.875235) (xy 66.278649 -36.006712) (xy 66.143015 -36.132431) (xy 66.002064 -36.252156)
			(xy 65.856058 -36.365664) (xy 65.705272 -36.47274) (xy 65.549989 -36.573183) (xy 65.390501 -36.666806)
			(xy 65.227107 -36.753432) (xy 65.060114 -36.832899) (xy 64.889835 -36.905057) (xy 64.71659 -36.969771)
			(xy 64.540705 -37.02692) (xy 64.362509 -37.076395) (xy 64.182337 -37.118106) (xy 64.000527 -37.151972)
			(xy 63.817421 -37.177931) (xy 63.633363 -37.195933) (xy 63.448697 -37.205945) (xy 63.263771 -37.207949)
			(xy 63.078932 -37.201939) (xy 62.894526 -37.187929) (xy 62.710901 -37.165943) (xy 62.5284 -37.136024)
			(xy 62.347367 -37.098226) (xy 62.168141 -37.052623) (xy 61.991059 -36.999298) (xy 61.816453 -36.938352)
			(xy 61.644651 -36.8699) (xy 61.475975 -36.79407) (xy 61.310743 -36.711004) (xy 61.149264 -36.620859)
			(xy 60.991842 -36.523803) (xy 60.838771 -36.420018) (xy 60.690341 -36.309701) (xy 60.546828 -36.193057)
			(xy 60.408503 -36.070306) (xy 60.275625 -35.941678) (xy 60.148444 -35.807414) (xy 60.027199 -35.667768)
			(xy 59.912116 -35.523) (xy 59.803413 -35.373383) (xy 59.701293 -35.219197) (xy 59.605948 -35.060733)
			(xy 59.517557 -34.898287) (xy 59.436286 -34.732164) (xy 59.362288 -34.562677) (xy 59.295701 -34.390144)
			(xy 59.23665 -34.214888) (xy 59.185247 -34.037238) (xy 59.141587 -33.857529) (xy 59.105754 -33.676097)
			(xy 59.077813 -33.493283) (xy 59.057818 -33.30943) (xy 59.045806 -33.124883) (xy 59.041799 -32.93999)
			(xy 44.47921 -32.93999) (xy 41.0464 -36.3728) (xy 41.0464 -53.25618) (xy 73.283826 -53.25618) (xy 73.283826 -48.598074)
			(xy 73.310014 -48.569356) (xy 73.366131 -48.515575) (xy 73.426197 -48.466243) (xy 73.457816 -48.443642)
			(xy 73.461372 -48.441102) (xy 73.633076 -48.269398) (xy 73.640475 -48.262669) (xy 73.658904 -48.254952)
			(xy 73.66889 -48.254412) (xy 76.01839 -48.254412) (xy 76.028397 -48.254853) (xy 76.046859 -48.262587)
			(xy 76.054204 -48.269398) (xy 76.713842 -48.929036) (xy 76.720603 -48.93641) (xy 76.7283 -48.954858)
			(xy 76.728828 -48.96485) (xy 76.728828 -52.88153) (xy 76.728371 -52.891535) (xy 76.72065 -52.909999)
			(xy 76.713842 -52.917344) (xy 76.375006 -53.25618) (xy 78.744826 -53.25618) (xy 78.744826 -48.598074)
			(xy 78.771014 -48.569356) (xy 78.827131 -48.515575) (xy 78.887197 -48.466243) (xy 78.918816 -48.443642)
			(xy 78.922372 -48.441102) (xy 79.094076 -48.269398) (xy 79.101475 -48.262669) (xy 79.119904 -48.254952)
			(xy 79.12989 -48.254412) (xy 81.47939 -48.254412) (xy 81.489397 -48.254853) (xy 81.507859 -48.262587)
			(xy 81.515204 -48.269398) (xy 82.174842 -48.929036) (xy 82.181603 -48.93641) (xy 82.1893 -48.954858)
			(xy 82.189828 -48.96485) (xy 82.189828 -52.88153) (xy 82.189371 -52.891535) (xy 82.18165 -52.909999)
			(xy 82.174842 -52.917344) (xy 81.836006 -53.25618) (xy 84.205826 -53.25618) (xy 84.205826 -48.598074)
			(xy 84.232014 -48.569356) (xy 84.288131 -48.515575) (xy 84.348197 -48.466243) (xy 84.379816 -48.443642)
			(xy 84.383372 -48.441102) (xy 84.555076 -48.269398) (xy 84.562475 -48.262669) (xy 84.580904 -48.254952)
			(xy 84.59089 -48.254412) (xy 86.94039 -48.254412) (xy 86.950397 -48.254853) (xy 86.968859 -48.262587)
			(xy 86.976204 -48.269398) (xy 87.635842 -48.929036) (xy 87.642603 -48.93641) (xy 87.6503 -48.954858)
			(xy 87.650828 -48.96485) (xy 87.650828 -52.88153) (xy 87.650371 -52.891535) (xy 87.64265 -52.909999)
			(xy 87.635842 -52.917344) (xy 87.297006 -53.25618) (xy 89.666826 -53.25618) (xy 89.666826 -48.598074)
			(xy 89.693014 -48.569356) (xy 89.749131 -48.515575) (xy 89.809197 -48.466243) (xy 89.840816 -48.443642)
			(xy 89.844372 -48.441102) (xy 90.016076 -48.269398) (xy 90.023475 -48.262669) (xy 90.041904 -48.254952)
			(xy 90.05189 -48.254412) (xy 92.40139 -48.254412) (xy 92.411397 -48.254853) (xy 92.429859 -48.262587)
			(xy 92.437204 -48.269398) (xy 93.096842 -48.929036) (xy 93.103603 -48.93641) (xy 93.1113 -48.954858)
			(xy 93.111828 -48.96485) (xy 93.111828 -52.88153) (xy 93.111371 -52.891535) (xy 93.10365 -52.909999)
			(xy 93.096842 -52.917344) (xy 92.758006 -53.25618) (xy 95.127826 -53.25618) (xy 95.127826 -48.618648)
			(xy 95.477076 -48.269398) (xy 95.484475 -48.262669) (xy 95.502904 -48.254952) (xy 95.51289 -48.254412)
			(xy 97.86239 -48.254412) (xy 97.872397 -48.254853) (xy 97.890859 -48.262587) (xy 97.898204 -48.269398)
			(xy 98.557842 -48.929036) (xy 98.564603 -48.93641) (xy 98.5723 -48.954858) (xy 98.572828 -48.96485)
			(xy 98.572828 -52.88153) (xy 98.572371 -52.891535) (xy 98.56465 -52.909999) (xy 98.557842 -52.917344)
			(xy 98.219006 -53.25618) (xy 100.588826 -53.25618) (xy 100.588826 -48.618648) (xy 100.938076 -48.269398)
			(xy 100.945475 -48.262669) (xy 100.963904 -48.254952) (xy 100.97389 -48.254412) (xy 103.32339 -48.254412)
			(xy 103.333397 -48.254853) (xy 103.351859 -48.262587) (xy 103.359204 -48.269398) (xy 104.018842 -48.929036)
			(xy 104.025603 -48.93641) (xy 104.0333 -48.954858) (xy 104.033828 -48.96485) (xy 104.033828 -52.88153)
			(xy 104.033371 -52.891535) (xy 104.02565 -52.909999) (xy 104.018842 -52.917344) (xy 103.680006 -53.25618)
			(xy 106.049826 -53.25618) (xy 106.049826 -48.618648) (xy 106.399076 -48.269398) (xy 106.406475 -48.262669)
			(xy 106.424904 -48.254952) (xy 106.43489 -48.254412) (xy 108.78439 -48.254412) (xy 108.794397 -48.254853)
			(xy 108.812859 -48.262587) (xy 108.820204 -48.269398) (xy 109.479842 -48.929036) (xy 109.486603 -48.93641)
			(xy 109.4943 -48.954858) (xy 109.494828 -48.96485) (xy 109.494828 -52.88153) (xy 109.494371 -52.891535)
			(xy 109.48665 -52.909999) (xy 109.479842 -52.917344) (xy 109.268006 -53.12918) (xy 151.388826 -53.12918)
			(xy 151.388826 -48.491648) (xy 151.738076 -48.142398) (xy 151.745475 -48.135669) (xy 151.763904 -48.127952)
			(xy 151.77389 -48.127412) (xy 154.12339 -48.127412) (xy 154.133397 -48.127853) (xy 154.151859 -48.135587)
			(xy 154.159204 -48.142398) (xy 154.818842 -48.802036) (xy 154.825603 -48.80941) (xy 154.8333 -48.827858)
			(xy 154.833828 -48.83785) (xy 154.833828 -52.75453) (xy 154.833371 -52.764535) (xy 154.82565 -52.782999)
			(xy 154.818842 -52.790344) (xy 154.480006 -53.12918) (xy 156.849826 -53.12918) (xy 156.849826 -48.491648)
			(xy 157.199076 -48.142398) (xy 157.206475 -48.135669) (xy 157.224904 -48.127952) (xy 157.23489 -48.127412)
			(xy 159.58439 -48.127412) (xy 159.594397 -48.127853) (xy 159.612859 -48.135587) (xy 159.620204 -48.142398)
			(xy 160.279842 -48.802036) (xy 160.286603 -48.80941) (xy 160.2943 -48.827858) (xy 160.294828 -48.83785)
			(xy 160.294828 -52.75453) (xy 160.294371 -52.764535) (xy 160.28665 -52.782999) (xy 160.279842 -52.790344)
			(xy 159.941006 -53.12918) (xy 162.310826 -53.12918) (xy 162.310826 -48.491648) (xy 162.660076 -48.142398)
			(xy 162.667475 -48.135669) (xy 162.685904 -48.127952) (xy 162.69589 -48.127412) (xy 165.04539 -48.127412)
			(xy 165.055397 -48.127853) (xy 165.073859 -48.135587) (xy 165.081204 -48.142398) (xy 165.740842 -48.802036)
			(xy 165.747603 -48.80941) (xy 165.7553 -48.827858) (xy 165.755828 -48.83785) (xy 165.755828 -52.75453)
			(xy 165.755371 -52.764535) (xy 165.74765 -52.782999) (xy 165.740842 -52.790344) (xy 165.402006 -53.12918)
			(xy 167.771826 -53.12918) (xy 167.771826 -48.491648) (xy 168.121076 -48.142398) (xy 168.128475 -48.135669)
			(xy 168.146904 -48.127952) (xy 168.15689 -48.127412) (xy 170.50639 -48.127412) (xy 170.516397 -48.127853)
			(xy 170.534859 -48.135587) (xy 170.542204 -48.142398) (xy 171.201842 -48.802036) (xy 171.208603 -48.80941)
			(xy 171.2163 -48.827858) (xy 171.216828 -48.83785) (xy 171.216828 -52.75453) (xy 171.216371 -52.764535)
			(xy 171.20865 -52.782999) (xy 171.201842 -52.790344) (xy 170.863006 -53.12918) (xy 173.232826 -53.12918)
			(xy 173.232826 -48.491648) (xy 173.582076 -48.142398) (xy 173.589475 -48.135669) (xy 173.607904 -48.127952)
			(xy 173.61789 -48.127412) (xy 175.96739 -48.127412) (xy 175.977397 -48.127853) (xy 175.995859 -48.135587)
			(xy 176.003204 -48.142398) (xy 176.662842 -48.802036) (xy 176.669603 -48.80941) (xy 176.6773 -48.827858)
			(xy 176.677828 -48.83785) (xy 176.677828 -52.75453) (xy 176.677371 -52.764535) (xy 176.66965 -52.782999)
			(xy 176.662842 -52.790344) (xy 176.324006 -53.12918) (xy 178.691286 -53.12918) (xy 178.691286 -48.491648)
			(xy 179.040536 -48.142398) (xy 179.047915 -48.135643) (xy 179.066359 -48.127941) (xy 179.07635 -48.127412)
			(xy 181.42585 -48.127412) (xy 181.435854 -48.127874) (xy 181.454317 -48.135593) (xy 181.461664 -48.142398)
			(xy 182.121302 -48.802036) (xy 182.128057 -48.809415) (xy 182.135759 -48.827859) (xy 182.136288 -48.83785)
			(xy 182.136288 -52.75453) (xy 182.135815 -52.764533) (xy 182.128104 -52.782996) (xy 182.121302 -52.790344)
			(xy 181.782466 -53.12918) (xy 184.152286 -53.12918) (xy 184.152286 -48.491648) (xy 184.501536 -48.142398)
			(xy 184.508915 -48.135643) (xy 184.527359 -48.127941) (xy 184.53735 -48.127412) (xy 186.88685 -48.127412)
			(xy 186.896854 -48.127874) (xy 186.915317 -48.135593) (xy 186.922664 -48.142398) (xy 187.582302 -48.802036)
			(xy 187.589057 -48.809415) (xy 187.596759 -48.827859) (xy 187.597288 -48.83785) (xy 187.597288 -52.75453)
			(xy 187.596815 -52.764533) (xy 187.589104 -52.782996) (xy 187.582302 -52.790344) (xy 186.904884 -53.467762)
			(xy 186.897494 -53.474503) (xy 186.879059 -53.482215) (xy 186.86907 -53.482748) (xy 184.55005 -53.482748)
			(xy 184.540044 -53.482296) (xy 184.521582 -53.474571) (xy 184.514236 -53.467762) (xy 184.33796 -53.291486)
			(xy 184.33415 -53.288946) (xy 184.301037 -53.265717) (xy 184.238192 -53.214784) (xy 184.179584 -53.159028)
			(xy 184.152286 -53.12918) (xy 181.782466 -53.12918) (xy 181.443884 -53.467762) (xy 181.436494 -53.474503)
			(xy 181.418059 -53.482215) (xy 181.40807 -53.482748) (xy 179.08905 -53.482748) (xy 179.079044 -53.482296)
			(xy 179.060582 -53.474571) (xy 179.053236 -53.467762) (xy 178.87696 -53.291486) (xy 178.87315 -53.288946)
			(xy 178.840037 -53.265717) (xy 178.777192 -53.214784) (xy 178.718584 -53.159028) (xy 178.691286 -53.12918)
			(xy 176.324006 -53.12918) (xy 175.985424 -53.467762) (xy 175.97802 -53.474486) (xy 175.959595 -53.482207)
			(xy 175.94961 -53.482748) (xy 173.63059 -53.482748) (xy 173.620587 -53.482276) (xy 173.602123 -53.474565)
			(xy 173.594776 -53.467762) (xy 173.4185 -53.291486) (xy 173.41469 -53.288946) (xy 173.381572 -53.265724)
			(xy 173.318729 -53.214788) (xy 173.260123 -53.159029) (xy 173.232826 -53.12918) (xy 170.863006 -53.12918)
			(xy 170.524424 -53.467762) (xy 170.51702 -53.474486) (xy 170.498595 -53.482207) (xy 170.48861 -53.482748)
			(xy 168.16959 -53.482748) (xy 168.159587 -53.482276) (xy 168.141123 -53.474565) (xy 168.133776 -53.467762)
			(xy 167.9575 -53.291486) (xy 167.95369 -53.288946) (xy 167.920572 -53.265724) (xy 167.857729 -53.214788)
			(xy 167.799123 -53.159029) (xy 167.771826 -53.12918) (xy 165.402006 -53.12918) (xy 165.063424 -53.467762)
			(xy 165.05602 -53.474486) (xy 165.037595 -53.482207) (xy 165.02761 -53.482748) (xy 162.70859 -53.482748)
			(xy 162.698587 -53.482276) (xy 162.680123 -53.474565) (xy 162.672776 -53.467762) (xy 162.4965 -53.291486)
			(xy 162.49269 -53.288946) (xy 162.459572 -53.265724) (xy 162.396729 -53.214788) (xy 162.338123 -53.159029)
			(xy 162.310826 -53.12918) (xy 159.941006 -53.12918) (xy 159.602424 -53.467762) (xy 159.59502 -53.474486)
			(xy 159.576595 -53.482207) (xy 159.56661 -53.482748) (xy 157.24759 -53.482748) (xy 157.237587 -53.482276)
			(xy 157.219123 -53.474565) (xy 157.211776 -53.467762) (xy 157.0355 -53.291486) (xy 157.03169 -53.288946)
			(xy 156.998572 -53.265724) (xy 156.935729 -53.214788) (xy 156.877123 -53.159029) (xy 156.849826 -53.12918)
			(xy 154.480006 -53.12918) (xy 154.141424 -53.467762) (xy 154.13402 -53.474486) (xy 154.115595 -53.482207)
			(xy 154.10561 -53.482748) (xy 151.78659 -53.482748) (xy 151.776587 -53.482276) (xy 151.758123 -53.474565)
			(xy 151.750776 -53.467762) (xy 151.5745 -53.291486) (xy 151.57069 -53.288946) (xy 151.537572 -53.265724)
			(xy 151.474729 -53.214788) (xy 151.416123 -53.159029) (xy 151.388826 -53.12918) (xy 109.268006 -53.12918)
			(xy 108.802424 -53.594762) (xy 108.79502 -53.601486) (xy 108.776595 -53.609207) (xy 108.76661 -53.609748)
			(xy 106.44759 -53.609748) (xy 106.437587 -53.609276) (xy 106.419123 -53.601565) (xy 106.411776 -53.594762)
			(xy 106.2355 -53.418486) (xy 106.23169 -53.415946) (xy 106.198572 -53.392724) (xy 106.135729 -53.341788)
			(xy 106.077123 -53.286029) (xy 106.049826 -53.25618) (xy 103.680006 -53.25618) (xy 103.341424 -53.594762)
			(xy 103.33402 -53.601486) (xy 103.315595 -53.609207) (xy 103.30561 -53.609748) (xy 100.98659 -53.609748)
			(xy 100.976587 -53.609276) (xy 100.958123 -53.601565) (xy 100.950776 -53.594762) (xy 100.7745 -53.418486)
			(xy 100.77069 -53.415946) (xy 100.737572 -53.392724) (xy 100.674729 -53.341788) (xy 100.616123 -53.286029)
			(xy 100.588826 -53.25618) (xy 98.219006 -53.25618) (xy 97.880424 -53.594762) (xy 97.87302 -53.601486)
			(xy 97.854595 -53.609207) (xy 97.84461 -53.609748) (xy 95.52559 -53.609748) (xy 95.515587 -53.609276)
			(xy 95.497123 -53.601565) (xy 95.489776 -53.594762) (xy 95.3135 -53.418486) (xy 95.30969 -53.415946)
			(xy 95.276572 -53.392724) (xy 95.213729 -53.341788) (xy 95.155123 -53.286029) (xy 95.127826 -53.25618)
			(xy 92.758006 -53.25618) (xy 92.419424 -53.594762) (xy 92.41202 -53.601486) (xy 92.393595 -53.609207)
			(xy 92.38361 -53.609748) (xy 90.06459 -53.609748) (xy 90.054587 -53.609276) (xy 90.036123 -53.601565)
			(xy 90.028776 -53.594762) (xy 89.8525 -53.418486) (xy 89.84869 -53.415946) (xy 89.815572 -53.392724)
			(xy 89.752729 -53.341788) (xy 89.694123 -53.286029) (xy 89.666826 -53.25618) (xy 87.297006 -53.25618)
			(xy 86.958424 -53.594762) (xy 86.95102 -53.601486) (xy 86.932595 -53.609207) (xy 86.92261 -53.609748)
			(xy 84.60359 -53.609748) (xy 84.593587 -53.609276) (xy 84.575123 -53.601565) (xy 84.567776 -53.594762)
			(xy 84.3915 -53.418486) (xy 84.38769 -53.415946) (xy 84.354572 -53.392724) (xy 84.291729 -53.341788)
			(xy 84.233123 -53.286029) (xy 84.205826 -53.25618) (xy 81.836006 -53.25618) (xy 81.497424 -53.594762)
			(xy 81.49002 -53.601486) (xy 81.471595 -53.609207) (xy 81.46161 -53.609748) (xy 79.14259 -53.609748)
			(xy 79.132587 -53.609276) (xy 79.114123 -53.601565) (xy 79.106776 -53.594762) (xy 78.9305 -53.418486)
			(xy 78.92669 -53.415946) (xy 78.893572 -53.392724) (xy 78.830729 -53.341788) (xy 78.772123 -53.286029)
			(xy 78.744826 -53.25618) (xy 76.375006 -53.25618) (xy 76.036424 -53.594762) (xy 76.02902 -53.601486)
			(xy 76.010595 -53.609207) (xy 76.00061 -53.609748) (xy 73.68159 -53.609748) (xy 73.671587 -53.609276)
			(xy 73.653123 -53.601565) (xy 73.645776 -53.594762) (xy 73.4695 -53.418486) (xy 73.46569 -53.415946)
			(xy 73.432572 -53.392724) (xy 73.369729 -53.341788) (xy 73.311123 -53.286029) (xy 73.283826 -53.25618)
			(xy 41.0464 -53.25618) (xy 41.0464 -59.163966) (xy 41.06418 -59.181746) (xy 42.272712 -59.181746)
			(xy 42.3164 -59.138058) (xy 42.3164 -55.118) (xy 42.320718 -55.118) (xy 43.981878 -53.45684) (xy 43.989279 -53.450001)
			(xy 44.007878 -53.442289) (xy 44.017946 -53.441854) (xy 48.133254 -53.441854) (xy 48.676814 -53.985414)
			(xy 48.683668 -53.992809) (xy 48.69141 -54.011408) (xy 48.6918 -54.021482) (xy 48.6918 -55.122318)
			(xy 48.692227 -55.132387) (xy 48.699946 -55.150986) (xy 48.706786 -55.158386) (xy 48.98263 -55.43423)
			(xy 48.990027 -55.441079) (xy 49.008626 -55.448814) (xy 49.018698 -55.449216) (xy 51.795934 -55.449216)
			(xy 51.806001 -55.449646) (xy 51.824595 -55.457371) (xy 51.832002 -55.464202) (xy 52.387255 -56.019455)
			(xy 66.293988 -56.019455) (xy 66.293988 -55.900565) (xy 66.301929 -55.781939) (xy 66.317776 -55.664109)
			(xy 66.341457 -55.547601) (xy 66.372868 -55.432934) (xy 66.411867 -55.320622) (xy 66.458281 -55.211165)
			(xy 66.511902 -55.105053) (xy 66.57249 -55.002759) (xy 66.639776 -54.90474) (xy 66.713459 -54.811435)
			(xy 66.793209 -54.723259) (xy 66.878671 -54.640607) (xy 66.969462 -54.563848) (xy 67.065177 -54.493324)
			(xy 67.165389 -54.429351) (xy 67.269651 -54.372215) (xy 67.377496 -54.322169) (xy 67.488442 -54.279439)
			(xy 67.601995 -54.244215) (xy 67.717647 -54.216653) (xy 67.834882 -54.196878) (xy 67.953176 -54.184978)
			(xy 68.072 -54.181005) (xy 68.190824 -54.184978) (xy 68.309118 -54.196878) (xy 68.426353 -54.216653)
			(xy 68.542005 -54.244215) (xy 68.655558 -54.279439) (xy 68.766504 -54.322169) (xy 68.874349 -54.372215)
			(xy 68.978611 -54.429351) (xy 69.078823 -54.493324) (xy 69.174538 -54.563848) (xy 69.265329 -54.640607)
			(xy 69.350791 -54.723259) (xy 69.430541 -54.811435) (xy 69.504224 -54.90474) (xy 69.57151 -55.002759)
			(xy 69.632098 -55.105053) (xy 69.685719 -55.211165) (xy 69.732133 -55.320622) (xy 69.771132 -55.432934)
			(xy 69.802543 -55.547601) (xy 69.826224 -55.664109) (xy 69.842071 -55.781939) (xy 69.850012 -55.900565)
			(xy 69.850508 -55.96001) (xy 69.850012 -56.019455) (xy 77.596988 -56.019455) (xy 77.596988 -55.900565)
			(xy 77.604929 -55.781939) (xy 77.620776 -55.664109) (xy 77.644457 -55.547601) (xy 77.675868 -55.432934)
			(xy 77.714867 -55.320622) (xy 77.761281 -55.211165) (xy 77.814902 -55.105053) (xy 77.87549 -55.002759)
			(xy 77.942776 -54.90474) (xy 78.016459 -54.811435) (xy 78.096209 -54.723259) (xy 78.181671 -54.640607)
			(xy 78.272462 -54.563848) (xy 78.368177 -54.493324) (xy 78.468389 -54.429351) (xy 78.572651 -54.372215)
			(xy 78.680496 -54.322169) (xy 78.791442 -54.279439) (xy 78.904995 -54.244215) (xy 79.020647 -54.216653)
			(xy 79.137882 -54.196878) (xy 79.256176 -54.184978) (xy 79.375 -54.181005) (xy 79.493824 -54.184978)
			(xy 79.612118 -54.196878) (xy 79.729353 -54.216653) (xy 79.845005 -54.244215) (xy 79.958558 -54.279439)
			(xy 80.069504 -54.322169) (xy 80.177349 -54.372215) (xy 80.281611 -54.429351) (xy 80.381823 -54.493324)
			(xy 80.477538 -54.563848) (xy 80.568329 -54.640607) (xy 80.653791 -54.723259) (xy 80.733541 -54.811435)
			(xy 80.807224 -54.90474) (xy 80.87451 -55.002759) (xy 80.935098 -55.105053) (xy 80.988719 -55.211165)
			(xy 81.035133 -55.320622) (xy 81.074132 -55.432934) (xy 81.105543 -55.547601) (xy 81.129224 -55.664109)
			(xy 81.145071 -55.781939) (xy 81.153012 -55.900565) (xy 81.153508 -55.96001) (xy 81.153012 -56.019455)
			(xy 88.899988 -56.019455) (xy 88.899988 -55.900565) (xy 88.907929 -55.781939) (xy 88.923776 -55.664109)
			(xy 88.947457 -55.547601) (xy 88.978868 -55.432934) (xy 89.017867 -55.320622) (xy 89.064281 -55.211165)
			(xy 89.117902 -55.105053) (xy 89.17849 -55.002759) (xy 89.245776 -54.90474) (xy 89.319459 -54.811435)
			(xy 89.399209 -54.723259) (xy 89.484671 -54.640607) (xy 89.575462 -54.563848) (xy 89.671177 -54.493324)
			(xy 89.771389 -54.429351) (xy 89.875651 -54.372215) (xy 89.983496 -54.322169) (xy 90.094442 -54.279439)
			(xy 90.207995 -54.244215) (xy 90.323647 -54.216653) (xy 90.440882 -54.196878) (xy 90.559176 -54.184978)
			(xy 90.678 -54.181005) (xy 90.796824 -54.184978) (xy 90.915118 -54.196878) (xy 91.032353 -54.216653)
			(xy 91.148005 -54.244215) (xy 91.261558 -54.279439) (xy 91.372504 -54.322169) (xy 91.480349 -54.372215)
			(xy 91.584611 -54.429351) (xy 91.684823 -54.493324) (xy 91.780538 -54.563848) (xy 91.871329 -54.640607)
			(xy 91.956791 -54.723259) (xy 92.036541 -54.811435) (xy 92.110224 -54.90474) (xy 92.17751 -55.002759)
			(xy 92.238098 -55.105053) (xy 92.291719 -55.211165) (xy 92.338133 -55.320622) (xy 92.377132 -55.432934)
			(xy 92.408543 -55.547601) (xy 92.432224 -55.664109) (xy 92.448071 -55.781939) (xy 92.456012 -55.900565)
			(xy 92.456508 -55.96001) (xy 92.456012 -56.019455) (xy 107.060988 -56.019455) (xy 107.060988 -55.900565)
			(xy 107.068929 -55.781939) (xy 107.084776 -55.664109) (xy 107.108457 -55.547601) (xy 107.139868 -55.432934)
			(xy 107.178867 -55.320622) (xy 107.225281 -55.211165) (xy 107.278902 -55.105053) (xy 107.33949 -55.002759)
			(xy 107.406776 -54.90474) (xy 107.480459 -54.811435) (xy 107.560209 -54.723259) (xy 107.645671 -54.640607)
			(xy 107.736462 -54.563848) (xy 107.832177 -54.493324) (xy 107.932389 -54.429351) (xy 108.036651 -54.372215)
			(xy 108.144496 -54.322169) (xy 108.255442 -54.279439) (xy 108.368995 -54.244215) (xy 108.484647 -54.216653)
			(xy 108.601882 -54.196878) (xy 108.720176 -54.184978) (xy 108.839 -54.181005) (xy 108.957824 -54.184978)
			(xy 109.076118 -54.196878) (xy 109.193353 -54.216653) (xy 109.309005 -54.244215) (xy 109.422558 -54.279439)
			(xy 109.533504 -54.322169) (xy 109.641349 -54.372215) (xy 109.745611 -54.429351) (xy 109.845823 -54.493324)
			(xy 109.941538 -54.563848) (xy 110.032329 -54.640607) (xy 110.117791 -54.723259) (xy 110.197541 -54.811435)
			(xy 110.271224 -54.90474) (xy 110.33851 -55.002759) (xy 110.399098 -55.105053) (xy 110.452719 -55.211165)
			(xy 110.499133 -55.320622) (xy 110.538132 -55.432934) (xy 110.569543 -55.547601) (xy 110.593224 -55.664109)
			(xy 110.609071 -55.781939) (xy 110.617012 -55.900565) (xy 110.617508 -55.96001) (xy 110.617012 -56.019455)
			(xy 118.236988 -56.019455) (xy 118.236988 -55.900565) (xy 118.244929 -55.781939) (xy 118.260776 -55.664109)
			(xy 118.284457 -55.547601) (xy 118.315868 -55.432934) (xy 118.354867 -55.320622) (xy 118.401281 -55.211165)
			(xy 118.454902 -55.105053) (xy 118.51549 -55.002759) (xy 118.582776 -54.90474) (xy 118.656459 -54.811435)
			(xy 118.736209 -54.723259) (xy 118.821671 -54.640607) (xy 118.912462 -54.563848) (xy 119.008177 -54.493324)
			(xy 119.108389 -54.429351) (xy 119.212651 -54.372215) (xy 119.320496 -54.322169) (xy 119.431442 -54.279439)
			(xy 119.544995 -54.244215) (xy 119.660647 -54.216653) (xy 119.777882 -54.196878) (xy 119.896176 -54.184978)
			(xy 120.015 -54.181005) (xy 120.133824 -54.184978) (xy 120.252118 -54.196878) (xy 120.369353 -54.216653)
			(xy 120.485005 -54.244215) (xy 120.598558 -54.279439) (xy 120.709504 -54.322169) (xy 120.817349 -54.372215)
			(xy 120.921611 -54.429351) (xy 121.021823 -54.493324) (xy 121.117538 -54.563848) (xy 121.208329 -54.640607)
			(xy 121.293791 -54.723259) (xy 121.373541 -54.811435) (xy 121.447224 -54.90474) (xy 121.51451 -55.002759)
			(xy 121.575098 -55.105053) (xy 121.628719 -55.211165) (xy 121.675133 -55.320622) (xy 121.714132 -55.432934)
			(xy 121.745543 -55.547601) (xy 121.769224 -55.664109) (xy 121.785071 -55.781939) (xy 121.793012 -55.900565)
			(xy 121.793508 -55.96001) (xy 121.793012 -56.019455) (xy 129.412988 -56.019455) (xy 129.412988 -55.900565)
			(xy 129.420929 -55.781939) (xy 129.436776 -55.664109) (xy 129.460457 -55.547601) (xy 129.491868 -55.432934)
			(xy 129.530867 -55.320622) (xy 129.577281 -55.211165) (xy 129.630902 -55.105053) (xy 129.69149 -55.002759)
			(xy 129.758776 -54.90474) (xy 129.832459 -54.811435) (xy 129.912209 -54.723259) (xy 129.997671 -54.640607)
			(xy 130.088462 -54.563848) (xy 130.184177 -54.493324) (xy 130.284389 -54.429351) (xy 130.388651 -54.372215)
			(xy 130.496496 -54.322169) (xy 130.607442 -54.279439) (xy 130.720995 -54.244215) (xy 130.836647 -54.216653)
			(xy 130.953882 -54.196878) (xy 131.072176 -54.184978) (xy 131.191 -54.181005) (xy 131.309824 -54.184978)
			(xy 131.428118 -54.196878) (xy 131.545353 -54.216653) (xy 131.661005 -54.244215) (xy 131.774558 -54.279439)
			(xy 131.885504 -54.322169) (xy 131.993349 -54.372215) (xy 132.097611 -54.429351) (xy 132.197823 -54.493324)
			(xy 132.293538 -54.563848) (xy 132.384329 -54.640607) (xy 132.469791 -54.723259) (xy 132.549541 -54.811435)
			(xy 132.623224 -54.90474) (xy 132.69051 -55.002759) (xy 132.751098 -55.105053) (xy 132.804719 -55.211165)
			(xy 132.851133 -55.320622) (xy 132.890132 -55.432934) (xy 132.921543 -55.547601) (xy 132.945224 -55.664109)
			(xy 132.961071 -55.781939) (xy 132.969012 -55.900565) (xy 132.969508 -55.96001) (xy 132.969012 -56.019455)
			(xy 145.160988 -56.019455) (xy 145.160988 -55.900565) (xy 145.168929 -55.781939) (xy 145.184776 -55.664109)
			(xy 145.208457 -55.547601) (xy 145.239868 -55.432934) (xy 145.278867 -55.320622) (xy 145.325281 -55.211165)
			(xy 145.378902 -55.105053) (xy 145.43949 -55.002759) (xy 145.506776 -54.90474) (xy 145.580459 -54.811435)
			(xy 145.660209 -54.723259) (xy 145.745671 -54.640607) (xy 145.836462 -54.563848) (xy 145.932177 -54.493324)
			(xy 146.032389 -54.429351) (xy 146.136651 -54.372215) (xy 146.244496 -54.322169) (xy 146.355442 -54.279439)
			(xy 146.468995 -54.244215) (xy 146.584647 -54.216653) (xy 146.701882 -54.196878) (xy 146.820176 -54.184978)
			(xy 146.939 -54.181005) (xy 147.057824 -54.184978) (xy 147.176118 -54.196878) (xy 147.293353 -54.216653)
			(xy 147.409005 -54.244215) (xy 147.522558 -54.279439) (xy 147.633504 -54.322169) (xy 147.741349 -54.372215)
			(xy 147.845611 -54.429351) (xy 147.945823 -54.493324) (xy 148.041538 -54.563848) (xy 148.132329 -54.640607)
			(xy 148.217791 -54.723259) (xy 148.297541 -54.811435) (xy 148.371224 -54.90474) (xy 148.43851 -55.002759)
			(xy 148.499098 -55.105053) (xy 148.552719 -55.211165) (xy 148.599133 -55.320622) (xy 148.638132 -55.432934)
			(xy 148.669543 -55.547601) (xy 148.693224 -55.664109) (xy 148.709071 -55.781939) (xy 148.717012 -55.900565)
			(xy 148.717508 -55.96001) (xy 148.717012 -56.019455) (xy 156.336988 -56.019455) (xy 156.336988 -55.900565)
			(xy 156.344929 -55.781939) (xy 156.360776 -55.664109) (xy 156.384457 -55.547601) (xy 156.415868 -55.432934)
			(xy 156.454867 -55.320622) (xy 156.501281 -55.211165) (xy 156.554902 -55.105053) (xy 156.61549 -55.002759)
			(xy 156.682776 -54.90474) (xy 156.756459 -54.811435) (xy 156.836209 -54.723259) (xy 156.921671 -54.640607)
			(xy 157.012462 -54.563848) (xy 157.108177 -54.493324) (xy 157.208389 -54.429351) (xy 157.312651 -54.372215)
			(xy 157.420496 -54.322169) (xy 157.531442 -54.279439) (xy 157.644995 -54.244215) (xy 157.760647 -54.216653)
			(xy 157.877882 -54.196878) (xy 157.996176 -54.184978) (xy 158.115 -54.181005) (xy 158.233824 -54.184978)
			(xy 158.352118 -54.196878) (xy 158.469353 -54.216653) (xy 158.585005 -54.244215) (xy 158.698558 -54.279439)
			(xy 158.809504 -54.322169) (xy 158.917349 -54.372215) (xy 159.021611 -54.429351) (xy 159.121823 -54.493324)
			(xy 159.217538 -54.563848) (xy 159.308329 -54.640607) (xy 159.393791 -54.723259) (xy 159.473541 -54.811435)
			(xy 159.547224 -54.90474) (xy 159.61451 -55.002759) (xy 159.675098 -55.105053) (xy 159.728719 -55.211165)
			(xy 159.775133 -55.320622) (xy 159.814132 -55.432934) (xy 159.845543 -55.547601) (xy 159.869224 -55.664109)
			(xy 159.885071 -55.781939) (xy 159.893012 -55.900565) (xy 159.893508 -55.96001) (xy 159.893012 -56.019455)
			(xy 167.512988 -56.019455) (xy 167.512988 -55.900565) (xy 167.520929 -55.781939) (xy 167.536776 -55.664109)
			(xy 167.560457 -55.547601) (xy 167.591868 -55.432934) (xy 167.630867 -55.320622) (xy 167.677281 -55.211165)
			(xy 167.730902 -55.105053) (xy 167.79149 -55.002759) (xy 167.858776 -54.90474) (xy 167.932459 -54.811435)
			(xy 168.012209 -54.723259) (xy 168.097671 -54.640607) (xy 168.188462 -54.563848) (xy 168.284177 -54.493324)
			(xy 168.384389 -54.429351) (xy 168.488651 -54.372215) (xy 168.596496 -54.322169) (xy 168.707442 -54.279439)
			(xy 168.820995 -54.244215) (xy 168.936647 -54.216653) (xy 169.053882 -54.196878) (xy 169.172176 -54.184978)
			(xy 169.291 -54.181005) (xy 169.409824 -54.184978) (xy 169.528118 -54.196878) (xy 169.645353 -54.216653)
			(xy 169.761005 -54.244215) (xy 169.874558 -54.279439) (xy 169.985504 -54.322169) (xy 170.093349 -54.372215)
			(xy 170.197611 -54.429351) (xy 170.297823 -54.493324) (xy 170.393538 -54.563848) (xy 170.484329 -54.640607)
			(xy 170.569791 -54.723259) (xy 170.649541 -54.811435) (xy 170.723224 -54.90474) (xy 170.79051 -55.002759)
			(xy 170.851098 -55.105053) (xy 170.904719 -55.211165) (xy 170.951133 -55.320622) (xy 170.990132 -55.432934)
			(xy 171.021543 -55.547601) (xy 171.045224 -55.664109) (xy 171.061071 -55.781939) (xy 171.069012 -55.900565)
			(xy 171.069508 -55.96001) (xy 171.069012 -56.019455) (xy 185.161162 -56.019455) (xy 185.161162 -55.900565)
			(xy 185.169103 -55.781939) (xy 185.18495 -55.664109) (xy 185.208631 -55.547601) (xy 185.240042 -55.432934)
			(xy 185.279041 -55.320622) (xy 185.325455 -55.211165) (xy 185.379076 -55.105053) (xy 185.439664 -55.002759)
			(xy 185.50695 -54.90474) (xy 185.580633 -54.811435) (xy 185.660383 -54.723259) (xy 185.745845 -54.640607)
			(xy 185.836636 -54.563848) (xy 185.932351 -54.493324) (xy 186.032563 -54.429351) (xy 186.136825 -54.372215)
			(xy 186.24467 -54.322169) (xy 186.355616 -54.279439) (xy 186.469169 -54.244215) (xy 186.584821 -54.216653)
			(xy 186.702056 -54.196878) (xy 186.82035 -54.184978) (xy 186.939174 -54.181005) (xy 187.057998 -54.184978)
			(xy 187.176292 -54.196878) (xy 187.293527 -54.216653) (xy 187.409179 -54.244215) (xy 187.522732 -54.279439)
			(xy 187.633678 -54.322169) (xy 187.741523 -54.372215) (xy 187.845785 -54.429351) (xy 187.945997 -54.493324)
			(xy 188.041712 -54.563848) (xy 188.132503 -54.640607) (xy 188.217965 -54.723259) (xy 188.297715 -54.811435)
			(xy 188.371398 -54.90474) (xy 188.438684 -55.002759) (xy 188.499272 -55.105053) (xy 188.552893 -55.211165)
			(xy 188.599307 -55.320622) (xy 188.638306 -55.432934) (xy 188.669717 -55.547601) (xy 188.693398 -55.664109)
			(xy 188.709245 -55.781939) (xy 188.717186 -55.900565) (xy 188.717682 -55.96001) (xy 188.717186 -56.019455)
			(xy 196.337162 -56.019455) (xy 196.337162 -55.900565) (xy 196.345103 -55.781939) (xy 196.36095 -55.664109)
			(xy 196.384631 -55.547601) (xy 196.416042 -55.432934) (xy 196.455041 -55.320622) (xy 196.501455 -55.211165)
			(xy 196.555076 -55.105053) (xy 196.615664 -55.002759) (xy 196.68295 -54.90474) (xy 196.756633 -54.811435)
			(xy 196.836383 -54.723259) (xy 196.921845 -54.640607) (xy 197.012636 -54.563848) (xy 197.108351 -54.493324)
			(xy 197.208563 -54.429351) (xy 197.312825 -54.372215) (xy 197.42067 -54.322169) (xy 197.531616 -54.279439)
			(xy 197.645169 -54.244215) (xy 197.760821 -54.216653) (xy 197.878056 -54.196878) (xy 197.99635 -54.184978)
			(xy 198.115174 -54.181005) (xy 198.233998 -54.184978) (xy 198.352292 -54.196878) (xy 198.469527 -54.216653)
			(xy 198.585179 -54.244215) (xy 198.698732 -54.279439) (xy 198.809678 -54.322169) (xy 198.917523 -54.372215)
			(xy 199.021785 -54.429351) (xy 199.121997 -54.493324) (xy 199.217712 -54.563848) (xy 199.308503 -54.640607)
			(xy 199.393965 -54.723259) (xy 199.473715 -54.811435) (xy 199.547398 -54.90474) (xy 199.614684 -55.002759)
			(xy 199.675272 -55.105053) (xy 199.728893 -55.211165) (xy 199.775307 -55.320622) (xy 199.814306 -55.432934)
			(xy 199.845717 -55.547601) (xy 199.869398 -55.664109) (xy 199.885245 -55.781939) (xy 199.893186 -55.900565)
			(xy 199.893682 -55.96001) (xy 199.893186 -56.019455) (xy 207.513162 -56.019455) (xy 207.513162 -55.900565)
			(xy 207.521103 -55.781939) (xy 207.53695 -55.664109) (xy 207.560631 -55.547601) (xy 207.592042 -55.432934)
			(xy 207.631041 -55.320622) (xy 207.677455 -55.211165) (xy 207.731076 -55.105053) (xy 207.791664 -55.002759)
			(xy 207.85895 -54.90474) (xy 207.932633 -54.811435) (xy 208.012383 -54.723259) (xy 208.097845 -54.640607)
			(xy 208.188636 -54.563848) (xy 208.284351 -54.493324) (xy 208.384563 -54.429351) (xy 208.488825 -54.372215)
			(xy 208.59667 -54.322169) (xy 208.707616 -54.279439) (xy 208.821169 -54.244215) (xy 208.936821 -54.216653)
			(xy 209.054056 -54.196878) (xy 209.17235 -54.184978) (xy 209.291174 -54.181005) (xy 209.409998 -54.184978)
			(xy 209.528292 -54.196878) (xy 209.645527 -54.216653) (xy 209.761179 -54.244215) (xy 209.874732 -54.279439)
			(xy 209.985678 -54.322169) (xy 210.093523 -54.372215) (xy 210.197785 -54.429351) (xy 210.297997 -54.493324)
			(xy 210.393712 -54.563848) (xy 210.484503 -54.640607) (xy 210.569965 -54.723259) (xy 210.649715 -54.811435)
			(xy 210.723398 -54.90474) (xy 210.790684 -55.002759) (xy 210.851272 -55.105053) (xy 210.904893 -55.211165)
			(xy 210.951307 -55.320622) (xy 210.990306 -55.432934) (xy 211.021717 -55.547601) (xy 211.045398 -55.664109)
			(xy 211.061245 -55.781939) (xy 211.069186 -55.900565) (xy 211.069682 -55.96001) (xy 211.069186 -56.019455)
			(xy 211.061245 -56.138081) (xy 211.045398 -56.255911) (xy 211.021717 -56.372419) (xy 210.990306 -56.487086)
			(xy 210.951307 -56.599398) (xy 210.904893 -56.708855) (xy 210.851272 -56.814967) (xy 210.790684 -56.917261)
			(xy 210.723398 -57.01528) (xy 210.649715 -57.108585) (xy 210.569965 -57.196761) (xy 210.484503 -57.279413)
			(xy 210.393712 -57.356172) (xy 210.297997 -57.426696) (xy 210.197785 -57.490669) (xy 210.093523 -57.547805)
			(xy 209.985678 -57.597851) (xy 209.874732 -57.640581) (xy 209.761179 -57.675805) (xy 209.645527 -57.703367)
			(xy 209.528292 -57.723142) (xy 209.409998 -57.735042) (xy 209.291174 -57.739015) (xy 209.17235 -57.735042)
			(xy 209.054056 -57.723142) (xy 208.936821 -57.703367) (xy 208.821169 -57.675805) (xy 208.707616 -57.640581)
			(xy 208.59667 -57.597851) (xy 208.488825 -57.547805) (xy 208.384563 -57.490669) (xy 208.284351 -57.426696)
			(xy 208.188636 -57.356172) (xy 208.097845 -57.279413) (xy 208.012383 -57.196761) (xy 207.932633 -57.108585)
			(xy 207.85895 -57.01528) (xy 207.791664 -56.917261) (xy 207.731076 -56.814967) (xy 207.677455 -56.708855)
			(xy 207.631041 -56.599398) (xy 207.592042 -56.487086) (xy 207.560631 -56.372419) (xy 207.53695 -56.255911)
			(xy 207.521103 -56.138081) (xy 207.513162 -56.019455) (xy 199.893186 -56.019455) (xy 199.885245 -56.138081)
			(xy 199.869398 -56.255911) (xy 199.845717 -56.372419) (xy 199.814306 -56.487086) (xy 199.775307 -56.599398)
			(xy 199.728893 -56.708855) (xy 199.675272 -56.814967) (xy 199.614684 -56.917261) (xy 199.547398 -57.01528)
			(xy 199.473715 -57.108585) (xy 199.393965 -57.196761) (xy 199.308503 -57.279413) (xy 199.217712 -57.356172)
			(xy 199.121997 -57.426696) (xy 199.021785 -57.490669) (xy 198.917523 -57.547805) (xy 198.809678 -57.597851)
			(xy 198.698732 -57.640581) (xy 198.585179 -57.675805) (xy 198.469527 -57.703367) (xy 198.352292 -57.723142)
			(xy 198.233998 -57.735042) (xy 198.115174 -57.739015) (xy 197.99635 -57.735042) (xy 197.878056 -57.723142)
			(xy 197.760821 -57.703367) (xy 197.645169 -57.675805) (xy 197.531616 -57.640581) (xy 197.42067 -57.597851)
			(xy 197.312825 -57.547805) (xy 197.208563 -57.490669) (xy 197.108351 -57.426696) (xy 197.012636 -57.356172)
			(xy 196.921845 -57.279413) (xy 196.836383 -57.196761) (xy 196.756633 -57.108585) (xy 196.68295 -57.01528)
			(xy 196.615664 -56.917261) (xy 196.555076 -56.814967) (xy 196.501455 -56.708855) (xy 196.455041 -56.599398)
			(xy 196.416042 -56.487086) (xy 196.384631 -56.372419) (xy 196.36095 -56.255911) (xy 196.345103 -56.138081)
			(xy 196.337162 -56.019455) (xy 188.717186 -56.019455) (xy 188.709245 -56.138081) (xy 188.693398 -56.255911)
			(xy 188.669717 -56.372419) (xy 188.638306 -56.487086) (xy 188.599307 -56.599398) (xy 188.552893 -56.708855)
			(xy 188.499272 -56.814967) (xy 188.438684 -56.917261) (xy 188.371398 -57.01528) (xy 188.297715 -57.108585)
			(xy 188.217965 -57.196761) (xy 188.132503 -57.279413) (xy 188.041712 -57.356172) (xy 187.945997 -57.426696)
			(xy 187.845785 -57.490669) (xy 187.741523 -57.547805) (xy 187.633678 -57.597851) (xy 187.522732 -57.640581)
			(xy 187.409179 -57.675805) (xy 187.293527 -57.703367) (xy 187.176292 -57.723142) (xy 187.057998 -57.735042)
			(xy 186.939174 -57.739015) (xy 186.82035 -57.735042) (xy 186.702056 -57.723142) (xy 186.584821 -57.703367)
			(xy 186.469169 -57.675805) (xy 186.355616 -57.640581) (xy 186.24467 -57.597851) (xy 186.136825 -57.547805)
			(xy 186.032563 -57.490669) (xy 185.932351 -57.426696) (xy 185.836636 -57.356172) (xy 185.745845 -57.279413)
			(xy 185.660383 -57.196761) (xy 185.580633 -57.108585) (xy 185.50695 -57.01528) (xy 185.439664 -56.917261)
			(xy 185.379076 -56.814967) (xy 185.325455 -56.708855) (xy 185.279041 -56.599398) (xy 185.240042 -56.487086)
			(xy 185.208631 -56.372419) (xy 185.18495 -56.255911) (xy 185.169103 -56.138081) (xy 185.161162 -56.019455)
			(xy 171.069012 -56.019455) (xy 171.061071 -56.138081) (xy 171.045224 -56.255911) (xy 171.021543 -56.372419)
			(xy 170.990132 -56.487086) (xy 170.951133 -56.599398) (xy 170.904719 -56.708855) (xy 170.851098 -56.814967)
			(xy 170.79051 -56.917261) (xy 170.723224 -57.01528) (xy 170.649541 -57.108585) (xy 170.569791 -57.196761)
			(xy 170.484329 -57.279413) (xy 170.393538 -57.356172) (xy 170.297823 -57.426696) (xy 170.197611 -57.490669)
			(xy 170.093349 -57.547805) (xy 169.985504 -57.597851) (xy 169.874558 -57.640581) (xy 169.761005 -57.675805)
			(xy 169.645353 -57.703367) (xy 169.528118 -57.723142) (xy 169.409824 -57.735042) (xy 169.291 -57.739015)
			(xy 169.172176 -57.735042) (xy 169.053882 -57.723142) (xy 168.936647 -57.703367) (xy 168.820995 -57.675805)
			(xy 168.707442 -57.640581) (xy 168.596496 -57.597851) (xy 168.488651 -57.547805) (xy 168.384389 -57.490669)
			(xy 168.284177 -57.426696) (xy 168.188462 -57.356172) (xy 168.097671 -57.279413) (xy 168.012209 -57.196761)
			(xy 167.932459 -57.108585) (xy 167.858776 -57.01528) (xy 167.79149 -56.917261) (xy 167.730902 -56.814967)
			(xy 167.677281 -56.708855) (xy 167.630867 -56.599398) (xy 167.591868 -56.487086) (xy 167.560457 -56.372419)
			(xy 167.536776 -56.255911) (xy 167.520929 -56.138081) (xy 167.512988 -56.019455) (xy 159.893012 -56.019455)
			(xy 159.885071 -56.138081) (xy 159.869224 -56.255911) (xy 159.845543 -56.372419) (xy 159.814132 -56.487086)
			(xy 159.775133 -56.599398) (xy 159.728719 -56.708855) (xy 159.675098 -56.814967) (xy 159.61451 -56.917261)
			(xy 159.547224 -57.01528) (xy 159.473541 -57.108585) (xy 159.393791 -57.196761) (xy 159.308329 -57.279413)
			(xy 159.217538 -57.356172) (xy 159.121823 -57.426696) (xy 159.021611 -57.490669) (xy 158.917349 -57.547805)
			(xy 158.809504 -57.597851) (xy 158.698558 -57.640581) (xy 158.585005 -57.675805) (xy 158.469353 -57.703367)
			(xy 158.352118 -57.723142) (xy 158.233824 -57.735042) (xy 158.115 -57.739015) (xy 157.996176 -57.735042)
			(xy 157.877882 -57.723142) (xy 157.760647 -57.703367) (xy 157.644995 -57.675805) (xy 157.531442 -57.640581)
			(xy 157.420496 -57.597851) (xy 157.312651 -57.547805) (xy 157.208389 -57.490669) (xy 157.108177 -57.426696)
			(xy 157.012462 -57.356172) (xy 156.921671 -57.279413) (xy 156.836209 -57.196761) (xy 156.756459 -57.108585)
			(xy 156.682776 -57.01528) (xy 156.61549 -56.917261) (xy 156.554902 -56.814967) (xy 156.501281 -56.708855)
			(xy 156.454867 -56.599398) (xy 156.415868 -56.487086) (xy 156.384457 -56.372419) (xy 156.360776 -56.255911)
			(xy 156.344929 -56.138081) (xy 156.336988 -56.019455) (xy 148.717012 -56.019455) (xy 148.709071 -56.138081)
			(xy 148.693224 -56.255911) (xy 148.669543 -56.372419) (xy 148.638132 -56.487086) (xy 148.599133 -56.599398)
			(xy 148.552719 -56.708855) (xy 148.499098 -56.814967) (xy 148.43851 -56.917261) (xy 148.371224 -57.01528)
			(xy 148.297541 -57.108585) (xy 148.217791 -57.196761) (xy 148.132329 -57.279413) (xy 148.041538 -57.356172)
			(xy 147.945823 -57.426696) (xy 147.845611 -57.490669) (xy 147.741349 -57.547805) (xy 147.633504 -57.597851)
			(xy 147.522558 -57.640581) (xy 147.409005 -57.675805) (xy 147.293353 -57.703367) (xy 147.176118 -57.723142)
			(xy 147.057824 -57.735042) (xy 146.939 -57.739015) (xy 146.820176 -57.735042) (xy 146.701882 -57.723142)
			(xy 146.584647 -57.703367) (xy 146.468995 -57.675805) (xy 146.355442 -57.640581) (xy 146.244496 -57.597851)
			(xy 146.136651 -57.547805) (xy 146.032389 -57.490669) (xy 145.932177 -57.426696) (xy 145.836462 -57.356172)
			(xy 145.745671 -57.279413) (xy 145.660209 -57.196761) (xy 145.580459 -57.108585) (xy 145.506776 -57.01528)
			(xy 145.43949 -56.917261) (xy 145.378902 -56.814967) (xy 145.325281 -56.708855) (xy 145.278867 -56.599398)
			(xy 145.239868 -56.487086) (xy 145.208457 -56.372419) (xy 145.184776 -56.255911) (xy 145.168929 -56.138081)
			(xy 145.160988 -56.019455) (xy 132.969012 -56.019455) (xy 132.961071 -56.138081) (xy 132.945224 -56.255911)
			(xy 132.921543 -56.372419) (xy 132.890132 -56.487086) (xy 132.851133 -56.599398) (xy 132.804719 -56.708855)
			(xy 132.751098 -56.814967) (xy 132.69051 -56.917261) (xy 132.623224 -57.01528) (xy 132.549541 -57.108585)
			(xy 132.469791 -57.196761) (xy 132.384329 -57.279413) (xy 132.293538 -57.356172) (xy 132.197823 -57.426696)
			(xy 132.097611 -57.490669) (xy 131.993349 -57.547805) (xy 131.885504 -57.597851) (xy 131.774558 -57.640581)
			(xy 131.661005 -57.675805) (xy 131.545353 -57.703367) (xy 131.428118 -57.723142) (xy 131.309824 -57.735042)
			(xy 131.191 -57.739015) (xy 131.072176 -57.735042) (xy 130.953882 -57.723142) (xy 130.836647 -57.703367)
			(xy 130.720995 -57.675805) (xy 130.607442 -57.640581) (xy 130.496496 -57.597851) (xy 130.388651 -57.547805)
			(xy 130.284389 -57.490669) (xy 130.184177 -57.426696) (xy 130.088462 -57.356172) (xy 129.997671 -57.279413)
			(xy 129.912209 -57.196761) (xy 129.832459 -57.108585) (xy 129.758776 -57.01528) (xy 129.69149 -56.917261)
			(xy 129.630902 -56.814967) (xy 129.577281 -56.708855) (xy 129.530867 -56.599398) (xy 129.491868 -56.487086)
			(xy 129.460457 -56.372419) (xy 129.436776 -56.255911) (xy 129.420929 -56.138081) (xy 129.412988 -56.019455)
			(xy 121.793012 -56.019455) (xy 121.785071 -56.138081) (xy 121.769224 -56.255911) (xy 121.745543 -56.372419)
			(xy 121.714132 -56.487086) (xy 121.675133 -56.599398) (xy 121.628719 -56.708855) (xy 121.575098 -56.814967)
			(xy 121.51451 -56.917261) (xy 121.447224 -57.01528) (xy 121.373541 -57.108585) (xy 121.293791 -57.196761)
			(xy 121.208329 -57.279413) (xy 121.117538 -57.356172) (xy 121.021823 -57.426696) (xy 120.921611 -57.490669)
			(xy 120.817349 -57.547805) (xy 120.709504 -57.597851) (xy 120.598558 -57.640581) (xy 120.485005 -57.675805)
			(xy 120.369353 -57.703367) (xy 120.252118 -57.723142) (xy 120.133824 -57.735042) (xy 120.015 -57.739015)
			(xy 119.896176 -57.735042) (xy 119.777882 -57.723142) (xy 119.660647 -57.703367) (xy 119.544995 -57.675805)
			(xy 119.431442 -57.640581) (xy 119.320496 -57.597851) (xy 119.212651 -57.547805) (xy 119.108389 -57.490669)
			(xy 119.008177 -57.426696) (xy 118.912462 -57.356172) (xy 118.821671 -57.279413) (xy 118.736209 -57.196761)
			(xy 118.656459 -57.108585) (xy 118.582776 -57.01528) (xy 118.51549 -56.917261) (xy 118.454902 -56.814967)
			(xy 118.401281 -56.708855) (xy 118.354867 -56.599398) (xy 118.315868 -56.487086) (xy 118.284457 -56.372419)
			(xy 118.260776 -56.255911) (xy 118.244929 -56.138081) (xy 118.236988 -56.019455) (xy 110.617012 -56.019455)
			(xy 110.609071 -56.138081) (xy 110.593224 -56.255911) (xy 110.569543 -56.372419) (xy 110.538132 -56.487086)
			(xy 110.499133 -56.599398) (xy 110.452719 -56.708855) (xy 110.399098 -56.814967) (xy 110.33851 -56.917261)
			(xy 110.271224 -57.01528) (xy 110.197541 -57.108585) (xy 110.117791 -57.196761) (xy 110.032329 -57.279413)
			(xy 109.941538 -57.356172) (xy 109.845823 -57.426696) (xy 109.745611 -57.490669) (xy 109.641349 -57.547805)
			(xy 109.533504 -57.597851) (xy 109.422558 -57.640581) (xy 109.309005 -57.675805) (xy 109.193353 -57.703367)
			(xy 109.076118 -57.723142) (xy 108.957824 -57.735042) (xy 108.839 -57.739015) (xy 108.720176 -57.735042)
			(xy 108.601882 -57.723142) (xy 108.484647 -57.703367) (xy 108.368995 -57.675805) (xy 108.255442 -57.640581)
			(xy 108.144496 -57.597851) (xy 108.036651 -57.547805) (xy 107.932389 -57.490669) (xy 107.832177 -57.426696)
			(xy 107.736462 -57.356172) (xy 107.645671 -57.279413) (xy 107.560209 -57.196761) (xy 107.480459 -57.108585)
			(xy 107.406776 -57.01528) (xy 107.33949 -56.917261) (xy 107.278902 -56.814967) (xy 107.225281 -56.708855)
			(xy 107.178867 -56.599398) (xy 107.139868 -56.487086) (xy 107.108457 -56.372419) (xy 107.084776 -56.255911)
			(xy 107.068929 -56.138081) (xy 107.060988 -56.019455) (xy 92.456012 -56.019455) (xy 92.448071 -56.138081)
			(xy 92.432224 -56.255911) (xy 92.408543 -56.372419) (xy 92.377132 -56.487086) (xy 92.338133 -56.599398)
			(xy 92.291719 -56.708855) (xy 92.238098 -56.814967) (xy 92.17751 -56.917261) (xy 92.110224 -57.01528)
			(xy 92.036541 -57.108585) (xy 91.956791 -57.196761) (xy 91.871329 -57.279413) (xy 91.780538 -57.356172)
			(xy 91.684823 -57.426696) (xy 91.584611 -57.490669) (xy 91.480349 -57.547805) (xy 91.372504 -57.597851)
			(xy 91.261558 -57.640581) (xy 91.148005 -57.675805) (xy 91.032353 -57.703367) (xy 90.915118 -57.723142)
			(xy 90.796824 -57.735042) (xy 90.678 -57.739015) (xy 90.559176 -57.735042) (xy 90.440882 -57.723142)
			(xy 90.323647 -57.703367) (xy 90.207995 -57.675805) (xy 90.094442 -57.640581) (xy 89.983496 -57.597851)
			(xy 89.875651 -57.547805) (xy 89.771389 -57.490669) (xy 89.671177 -57.426696) (xy 89.575462 -57.356172)
			(xy 89.484671 -57.279413) (xy 89.399209 -57.196761) (xy 89.319459 -57.108585) (xy 89.245776 -57.01528)
			(xy 89.17849 -56.917261) (xy 89.117902 -56.814967) (xy 89.064281 -56.708855) (xy 89.017867 -56.599398)
			(xy 88.978868 -56.487086) (xy 88.947457 -56.372419) (xy 88.923776 -56.255911) (xy 88.907929 -56.138081)
			(xy 88.899988 -56.019455) (xy 81.153012 -56.019455) (xy 81.145071 -56.138081) (xy 81.129224 -56.255911)
			(xy 81.105543 -56.372419) (xy 81.074132 -56.487086) (xy 81.035133 -56.599398) (xy 80.988719 -56.708855)
			(xy 80.935098 -56.814967) (xy 80.87451 -56.917261) (xy 80.807224 -57.01528) (xy 80.733541 -57.108585)
			(xy 80.653791 -57.196761) (xy 80.568329 -57.279413) (xy 80.477538 -57.356172) (xy 80.381823 -57.426696)
			(xy 80.281611 -57.490669) (xy 80.177349 -57.547805) (xy 80.069504 -57.597851) (xy 79.958558 -57.640581)
			(xy 79.845005 -57.675805) (xy 79.729353 -57.703367) (xy 79.612118 -57.723142) (xy 79.493824 -57.735042)
			(xy 79.375 -57.739015) (xy 79.256176 -57.735042) (xy 79.137882 -57.723142) (xy 79.020647 -57.703367)
			(xy 78.904995 -57.675805) (xy 78.791442 -57.640581) (xy 78.680496 -57.597851) (xy 78.572651 -57.547805)
			(xy 78.468389 -57.490669) (xy 78.368177 -57.426696) (xy 78.272462 -57.356172) (xy 78.181671 -57.279413)
			(xy 78.096209 -57.196761) (xy 78.016459 -57.108585) (xy 77.942776 -57.01528) (xy 77.87549 -56.917261)
			(xy 77.814902 -56.814967) (xy 77.761281 -56.708855) (xy 77.714867 -56.599398) (xy 77.675868 -56.487086)
			(xy 77.644457 -56.372419) (xy 77.620776 -56.255911) (xy 77.604929 -56.138081) (xy 77.596988 -56.019455)
			(xy 69.850012 -56.019455) (xy 69.842071 -56.138081) (xy 69.826224 -56.255911) (xy 69.802543 -56.372419)
			(xy 69.771132 -56.487086) (xy 69.732133 -56.599398) (xy 69.685719 -56.708855) (xy 69.632098 -56.814967)
			(xy 69.57151 -56.917261) (xy 69.504224 -57.01528) (xy 69.430541 -57.108585) (xy 69.350791 -57.196761)
			(xy 69.265329 -57.279413) (xy 69.174538 -57.356172) (xy 69.078823 -57.426696) (xy 68.978611 -57.490669)
			(xy 68.874349 -57.547805) (xy 68.766504 -57.597851) (xy 68.655558 -57.640581) (xy 68.542005 -57.675805)
			(xy 68.426353 -57.703367) (xy 68.309118 -57.723142) (xy 68.190824 -57.735042) (xy 68.072 -57.739015)
			(xy 67.953176 -57.735042) (xy 67.834882 -57.723142) (xy 67.717647 -57.703367) (xy 67.601995 -57.675805)
			(xy 67.488442 -57.640581) (xy 67.377496 -57.597851) (xy 67.269651 -57.547805) (xy 67.165389 -57.490669)
			(xy 67.065177 -57.426696) (xy 66.969462 -57.356172) (xy 66.878671 -57.279413) (xy 66.793209 -57.196761)
			(xy 66.713459 -57.108585) (xy 66.639776 -57.01528) (xy 66.57249 -56.917261) (xy 66.511902 -56.814967)
			(xy 66.458281 -56.708855) (xy 66.411867 -56.599398) (xy 66.372868 -56.487086) (xy 66.341457 -56.372419)
			(xy 66.317776 -56.255911) (xy 66.301929 -56.138081) (xy 66.293988 -56.019455) (xy 52.387255 -56.019455)
			(xy 52.7558 -56.388) (xy 52.7558 -61.243972) (xy 60.060586 -61.243972) (xy 60.060586 -59.07024) (xy 60.652914 -58.477912)
			(xy 63.056516 -58.477912) (xy 63.066518 -58.478392) (xy 63.084981 -58.486098) (xy 63.09233 -58.492898)
			(xy 63.779908 -59.180476) (xy 63.786596 -59.18788) (xy 63.794165 -59.206322) (xy 63.79464 -59.21629)
			(xy 63.79464 -61.722) (xy 67.182492 -61.722) (xy 67.182492 -60.198) (xy 67.183038 -60.181285) (xy 67.19169 -60.148994)
			(xy 67.208405 -60.120043) (xy 67.232043 -60.096405) (xy 67.260994 -60.07969) (xy 67.293285 -60.071038)
			(xy 67.31 -60.070492) (xy 68.834 -60.070492) (xy 68.850715 -60.071038) (xy 68.883006 -60.07969) (xy 68.911957 -60.096405)
			(xy 68.935595 -60.120043) (xy 68.95231 -60.148994) (xy 68.960962 -60.181285) (xy 68.961508 -60.198)
			(xy 68.961508 -61.722) (xy 78.485492 -61.722) (xy 78.485492 -60.198) (xy 78.486038 -60.181285) (xy 78.49469 -60.148994)
			(xy 78.511405 -60.120043) (xy 78.535043 -60.096405) (xy 78.563994 -60.07969) (xy 78.596285 -60.071038)
			(xy 78.613 -60.070492) (xy 80.137 -60.070492) (xy 80.153715 -60.071038) (xy 80.186006 -60.07969)
			(xy 80.214957 -60.096405) (xy 80.238595 -60.120043) (xy 80.25531 -60.148994) (xy 80.263962 -60.181285)
			(xy 80.264508 -60.198) (xy 80.264508 -61.722) (xy 89.788492 -61.722) (xy 89.788492 -60.198) (xy 89.789038 -60.181285)
			(xy 89.79769 -60.148994) (xy 89.814405 -60.120043) (xy 89.838043 -60.096405) (xy 89.866994 -60.07969)
			(xy 89.899285 -60.071038) (xy 89.916 -60.070492) (xy 91.44 -60.070492) (xy 91.456715 -60.071038)
			(xy 91.489006 -60.07969) (xy 91.517957 -60.096405) (xy 91.541595 -60.120043) (xy 91.55831 -60.148994)
			(xy 91.566962 -60.181285) (xy 91.567508 -60.198) (xy 91.567508 -61.119258) (xy 99.685094 -61.119258)
			(xy 99.685094 -58.942732) (xy 100.276914 -58.350912) (xy 102.680516 -58.350912) (xy 102.690518 -58.351392)
			(xy 102.708981 -58.359098) (xy 102.71633 -58.365898) (xy 103.403908 -59.053476) (xy 103.410596 -59.06088)
			(xy 103.418165 -59.079322) (xy 103.41864 -59.08929) (xy 103.41864 -61.722) (xy 107.949492 -61.722)
			(xy 107.949492 -60.198) (xy 107.950038 -60.181285) (xy 107.95869 -60.148994) (xy 107.975405 -60.120043)
			(xy 107.999043 -60.096405) (xy 108.027994 -60.07969) (xy 108.060285 -60.071038) (xy 108.077 -60.070492)
			(xy 109.601 -60.070492) (xy 109.617715 -60.071038) (xy 109.650006 -60.07969) (xy 109.678957 -60.096405)
			(xy 109.702595 -60.120043) (xy 109.71931 -60.148994) (xy 109.727962 -60.181285) (xy 109.728508 -60.198)
			(xy 109.728508 -61.722) (xy 119.125492 -61.722) (xy 119.125492 -60.198) (xy 119.126038 -60.181285)
			(xy 119.13469 -60.148994) (xy 119.151405 -60.120043) (xy 119.175043 -60.096405) (xy 119.203994 -60.07969)
			(xy 119.236285 -60.071038) (xy 119.253 -60.070492) (xy 120.777 -60.070492) (xy 120.793715 -60.071038)
			(xy 120.826006 -60.07969) (xy 120.854957 -60.096405) (xy 120.878595 -60.120043) (xy 120.89531 -60.148994)
			(xy 120.903962 -60.181285) (xy 120.904508 -60.198) (xy 120.904508 -61.722) (xy 130.301492 -61.722)
			(xy 130.301492 -60.198) (xy 130.302038 -60.181285) (xy 130.31069 -60.148994) (xy 130.327405 -60.120043)
			(xy 130.351043 -60.096405) (xy 130.379994 -60.07969) (xy 130.412285 -60.071038) (xy 130.429 -60.070492)
			(xy 131.953 -60.070492) (xy 131.969715 -60.071038) (xy 132.002006 -60.07969) (xy 132.030957 -60.096405)
			(xy 132.054595 -60.120043) (xy 132.07131 -60.148994) (xy 132.079962 -60.181285) (xy 132.080508 -60.198)
			(xy 132.080508 -61.373258) (xy 138.674348 -61.373258) (xy 138.674348 -59.196478) (xy 139.265914 -58.604912)
			(xy 141.669516 -58.604912) (xy 141.679518 -58.605392) (xy 141.697981 -58.613098) (xy 141.70533 -58.619898)
			(xy 142.392908 -59.307476) (xy 142.399596 -59.31488) (xy 142.407165 -59.333322) (xy 142.40764 -59.34329)
			(xy 142.40764 -61.722) (xy 146.049492 -61.722) (xy 146.049492 -60.198) (xy 146.050038 -60.181285)
			(xy 146.05869 -60.148994) (xy 146.075405 -60.120043) (xy 146.099043 -60.096405) (xy 146.127994 -60.07969)
			(xy 146.160285 -60.071038) (xy 146.177 -60.070492) (xy 147.701 -60.070492) (xy 147.717715 -60.071038)
			(xy 147.750006 -60.07969) (xy 147.778957 -60.096405) (xy 147.802595 -60.120043) (xy 147.81931 -60.148994)
			(xy 147.827962 -60.181285) (xy 147.828508 -60.198) (xy 147.828508 -61.722) (xy 157.225492 -61.722)
			(xy 157.225492 -60.198) (xy 157.226038 -60.181285) (xy 157.23469 -60.148994) (xy 157.251405 -60.120043)
			(xy 157.275043 -60.096405) (xy 157.303994 -60.07969) (xy 157.336285 -60.071038) (xy 157.353 -60.070492)
			(xy 158.877 -60.070492) (xy 158.893715 -60.071038) (xy 158.926006 -60.07969) (xy 158.954957 -60.096405)
			(xy 158.978595 -60.120043) (xy 158.99531 -60.148994) (xy 159.003962 -60.181285) (xy 159.004508 -60.198)
			(xy 159.004508 -61.722) (xy 168.401492 -61.722) (xy 168.401492 -60.198) (xy 168.402038 -60.181285)
			(xy 168.41069 -60.148994) (xy 168.427405 -60.120043) (xy 168.451043 -60.096405) (xy 168.479994 -60.07969)
			(xy 168.512285 -60.071038) (xy 168.529 -60.070492) (xy 170.053 -60.070492) (xy 170.069715 -60.071038)
			(xy 170.102006 -60.07969) (xy 170.130957 -60.096405) (xy 170.154595 -60.120043) (xy 170.17131 -60.148994)
			(xy 170.179962 -60.181285) (xy 170.180508 -60.198) (xy 170.180508 -61.722) (xy 170.179962 -61.738715)
			(xy 170.17131 -61.771006) (xy 170.154595 -61.799957) (xy 170.130957 -61.823595) (xy 170.102006 -61.84031)
			(xy 170.069715 -61.848962) (xy 170.053 -61.849508) (xy 168.529 -61.849508) (xy 168.512285 -61.848962)
			(xy 168.479994 -61.84031) (xy 168.451043 -61.823595) (xy 168.427405 -61.799957) (xy 168.41069 -61.771006)
			(xy 168.402038 -61.738715) (xy 168.401492 -61.722) (xy 159.004508 -61.722) (xy 159.003962 -61.738715)
			(xy 158.99531 -61.771006) (xy 158.978595 -61.799957) (xy 158.954957 -61.823595) (xy 158.926006 -61.84031)
			(xy 158.893715 -61.848962) (xy 158.877 -61.849508) (xy 157.353 -61.849508) (xy 157.336285 -61.848962)
			(xy 157.303994 -61.84031) (xy 157.275043 -61.823595) (xy 157.251405 -61.799957) (xy 157.23469 -61.771006)
			(xy 157.226038 -61.738715) (xy 157.225492 -61.722) (xy 147.828508 -61.722) (xy 147.827962 -61.738715)
			(xy 147.81931 -61.771006) (xy 147.802595 -61.799957) (xy 147.778957 -61.823595) (xy 147.750006 -61.84031)
			(xy 147.717715 -61.848962) (xy 147.701 -61.849508) (xy 146.177 -61.849508) (xy 146.160285 -61.848962)
			(xy 146.127994 -61.84031) (xy 146.099043 -61.823595) (xy 146.075405 -61.799957) (xy 146.05869 -61.771006)
			(xy 146.050038 -61.738715) (xy 146.049492 -61.722) (xy 142.40764 -61.722) (xy 142.40764 -63.60541)
			(xy 142.407184 -63.615379) (xy 142.399595 -63.633815) (xy 142.392908 -63.641224) (xy 141.75613 -64.278002)
			(xy 141.748729 -64.284729) (xy 141.730302 -64.292447) (xy 141.720316 -64.292988) (xy 139.03198 -64.292988)
			(xy 138.892026 -64.153034) (xy 138.892026 -61.590936) (xy 138.674348 -61.373258) (xy 132.080508 -61.373258)
			(xy 132.080508 -61.722) (xy 132.079962 -61.738715) (xy 132.07131 -61.771006) (xy 132.054595 -61.799957)
			(xy 132.030957 -61.823595) (xy 132.002006 -61.84031) (xy 131.969715 -61.848962) (xy 131.953 -61.849508)
			(xy 130.429 -61.849508) (xy 130.412285 -61.848962) (xy 130.379994 -61.84031) (xy 130.351043 -61.823595)
			(xy 130.327405 -61.799957) (xy 130.31069 -61.771006) (xy 130.302038 -61.738715) (xy 130.301492 -61.722)
			(xy 120.904508 -61.722) (xy 120.903962 -61.738715) (xy 120.89531 -61.771006) (xy 120.878595 -61.799957)
			(xy 120.854957 -61.823595) (xy 120.826006 -61.84031) (xy 120.793715 -61.848962) (xy 120.777 -61.849508)
			(xy 119.253 -61.849508) (xy 119.236285 -61.848962) (xy 119.203994 -61.84031) (xy 119.175043 -61.823595)
			(xy 119.151405 -61.799957) (xy 119.13469 -61.771006) (xy 119.126038 -61.738715) (xy 119.125492 -61.722)
			(xy 109.728508 -61.722) (xy 109.727962 -61.738715) (xy 109.71931 -61.771006) (xy 109.702595 -61.799957)
			(xy 109.678957 -61.823595) (xy 109.650006 -61.84031) (xy 109.617715 -61.848962) (xy 109.601 -61.849508)
			(xy 108.077 -61.849508) (xy 108.060285 -61.848962) (xy 108.027994 -61.84031) (xy 107.999043 -61.823595)
			(xy 107.975405 -61.799957) (xy 107.95869 -61.771006) (xy 107.950038 -61.738715) (xy 107.949492 -61.722)
			(xy 103.41864 -61.722) (xy 103.41864 -63.35141) (xy 103.418184 -63.361379) (xy 103.410595 -63.379815)
			(xy 103.403908 -63.387224) (xy 102.76713 -64.024002) (xy 102.759729 -64.030729) (xy 102.741302 -64.038447)
			(xy 102.731316 -64.038988) (xy 100.059236 -64.038988) (xy 99.90328 -63.883032) (xy 99.90328 -61.337444)
			(xy 99.685094 -61.119258) (xy 91.567508 -61.119258) (xy 91.567508 -61.722) (xy 91.566962 -61.738715)
			(xy 91.55831 -61.771006) (xy 91.541595 -61.799957) (xy 91.517957 -61.823595) (xy 91.489006 -61.84031)
			(xy 91.456715 -61.848962) (xy 91.44 -61.849508) (xy 89.916 -61.849508) (xy 89.899285 -61.848962)
			(xy 89.866994 -61.84031) (xy 89.838043 -61.823595) (xy 89.814405 -61.799957) (xy 89.79769 -61.771006)
			(xy 89.789038 -61.738715) (xy 89.788492 -61.722) (xy 80.264508 -61.722) (xy 80.263962 -61.738715)
			(xy 80.25531 -61.771006) (xy 80.238595 -61.799957) (xy 80.214957 -61.823595) (xy 80.186006 -61.84031)
			(xy 80.153715 -61.848962) (xy 80.137 -61.849508) (xy 78.613 -61.849508) (xy 78.596285 -61.848962)
			(xy 78.563994 -61.84031) (xy 78.535043 -61.823595) (xy 78.511405 -61.799957) (xy 78.49469 -61.771006)
			(xy 78.486038 -61.738715) (xy 78.485492 -61.722) (xy 68.961508 -61.722) (xy 68.960962 -61.738715)
			(xy 68.95231 -61.771006) (xy 68.935595 -61.799957) (xy 68.911957 -61.823595) (xy 68.883006 -61.84031)
			(xy 68.850715 -61.848962) (xy 68.834 -61.849508) (xy 67.31 -61.849508) (xy 67.293285 -61.848962)
			(xy 67.260994 -61.84031) (xy 67.232043 -61.823595) (xy 67.208405 -61.799957) (xy 67.19169 -61.771006)
			(xy 67.183038 -61.738715) (xy 67.182492 -61.722) (xy 63.79464 -61.722) (xy 63.79464 -63.47841) (xy 63.794184 -63.488379)
			(xy 63.786595 -63.506815) (xy 63.779908 -63.514224) (xy 63.14313 -64.151002) (xy 63.135729 -64.157729)
			(xy 63.117302 -64.165447) (xy 63.107316 -64.165988) (xy 60.414662 -64.165988) (xy 60.278772 -64.030098)
			(xy 60.278772 -61.462158) (xy 60.060586 -61.243972) (xy 52.7558 -61.243972) (xy 52.7558 -65.884552)
			(xy 53.074062 -66.202814) (xy 53.088286 -66.209926) (xy 53.096414 -66.211196) (xy 53.15196 -66.219896)
			(xy 53.261832 -66.243793) (xy 53.369857 -66.275001) (xy 53.475547 -66.313377) (xy 53.578427 -66.35875)
			(xy 53.678036 -66.410916) (xy 53.773924 -66.46964) (xy 53.82006 -66.501772) (xy 53.826156 -66.50609)
			(xy 53.839872 -66.510916) (xy 53.848 -66.51117) (xy 53.854163 -66.511284) (xy 53.866244 -66.50885)
			(xy 53.871876 -66.506344) (xy 53.877972 -66.503296) (xy 53.881528 -66.500756) (xy 53.92618 -66.469727)
			(xy 54.018864 -66.412851) (xy 54.11504 -66.362101) (xy 54.214303 -66.31769) (xy 54.316235 -66.279806)
			(xy 54.368192 -66.263774) (xy 54.42687 -66.246729) (xy 54.546155 -66.220194) (xy 54.667055 -66.202414)
			(xy 54.78893 -66.193483) (xy 54.85003 -66.192908) (xy 54.850284 -66.192908) (xy 54.907687 -66.19339)
			(xy 55.022225 -66.201244) (xy 55.135957 -66.216915) (xy 55.24835 -66.24033) (xy 55.358878 -66.271381)
			(xy 55.467023 -66.30992) (xy 55.572278 -66.355768) (xy 55.674149 -66.408709) (xy 55.77216 -66.468496)
			(xy 55.819294 -66.501264) (xy 55.820818 -66.502534) (xy 55.823358 -66.504058) (xy 55.828932 -66.507131)
			(xy 55.841138 -66.510725) (xy 55.847488 -66.51117) (xy 55.860442 -66.511678) (xy 55.871872 -66.50609)
			(xy 55.876698 -66.504058) (xy 55.881016 -66.50101) (xy 55.926677 -66.469249) (xy 56.021533 -66.411144)
			(xy 56.120031 -66.359453) (xy 56.221737 -66.314402) (xy 56.326206 -66.27619) (xy 56.432976 -66.244984)
			(xy 56.54158 -66.220922) (xy 56.65154 -66.20411) (xy 56.762372 -66.194621) (xy 56.87359 -66.192497)
			(xy 56.984703 -66.197747) (xy 57.040018 -66.203576) (xy 57.099794 -66.210928) (xy 57.218181 -66.233123)
			(xy 57.334669 -66.263757) (xy 57.448659 -66.302671) (xy 57.559562 -66.349665) (xy 57.666807 -66.404496)
			(xy 57.769841 -66.466883) (xy 57.81929 -66.501264) (xy 57.820814 -66.502534) (xy 57.823354 -66.504058)
			(xy 57.828928 -66.507131) (xy 57.841134 -66.510726) (xy 57.847484 -66.51117) (xy 57.860438 -66.511678)
			(xy 57.871868 -66.50609) (xy 57.876694 -66.504058) (xy 57.881012 -66.50101) (xy 57.926673 -66.469249)
			(xy 58.021529 -66.411144) (xy 58.120026 -66.359453) (xy 58.221733 -66.314402) (xy 58.326201 -66.276189)
			(xy 58.432972 -66.244983) (xy 58.541576 -66.220921) (xy 58.651536 -66.204108) (xy 58.762368 -66.194619)
			(xy 58.873586 -66.192494) (xy 58.9847 -66.197744) (xy 59.040014 -66.203576) (xy 59.099791 -66.210928)
			(xy 59.218177 -66.233123) (xy 59.334666 -66.263756) (xy 59.448656 -66.30267) (xy 59.559559 -66.349664)
			(xy 59.666804 -66.404495) (xy 59.769838 -66.466881) (xy 59.819286 -66.501264) (xy 59.82081 -66.502534)
			(xy 59.82335 -66.504058) (xy 59.828924 -66.507132) (xy 59.84113 -66.510727) (xy 59.84748 -66.51117)
			(xy 59.860434 -66.511678) (xy 59.871864 -66.50609) (xy 59.87669 -66.504058) (xy 59.881008 -66.50101)
			(xy 59.92955 -66.467297) (xy 60.030604 -66.405986) (xy 60.135722 -66.351942) (xy 60.244385 -66.305432)
			(xy 60.356052 -66.266687) (xy 60.47017 -66.235899) (xy 60.586172 -66.213222) (xy 60.703482 -66.198767)
			(xy 60.821519 -66.192606) (xy 60.939697 -66.194771) (xy 60.998608 -66.199512) (xy 61.053708 -66.204868)
			(xy 61.1631 -66.221928) (xy 61.271128 -66.246172) (xy 61.37732 -66.277492) (xy 61.481213 -66.315754)
			(xy 61.582355 -66.360789) (xy 61.680303 -66.412401) (xy 61.774632 -66.470366) (xy 61.820044 -66.502026)
			(xy 61.825826 -66.505805) (xy 61.838829 -66.510452) (xy 61.845698 -66.51117) (xy 61.859414 -66.512186)
			(xy 61.878718 -66.502788) (xy 61.88202 -66.500502) (xy 61.929114 -66.467799) (xy 62.027051 -66.408159)
			(xy 62.128833 -66.35535) (xy 62.233986 -66.309619) (xy 62.342017 -66.271178) (xy 62.452422 -66.240208)
			(xy 62.564685 -66.216853) (xy 62.678282 -66.201222) (xy 62.792681 -66.193389) (xy 62.850014 -66.192908)
			(xy 62.907282 -66.193386) (xy 63.021551 -66.201204) (xy 63.13502 -66.216801) (xy 63.247161 -66.240105)
			(xy 63.357449 -66.271007) (xy 63.465372 -66.309364) (xy 63.570425 -66.354996) (xy 63.67212 -66.407691)
			(xy 63.769981 -66.467203) (xy 63.863553 -66.533254) (xy 63.952399 -66.605538) (xy 64.036106 -66.683715)
			(xy 64.114282 -66.767423) (xy 64.186564 -66.856271) (xy 64.252614 -66.949844) (xy 64.312124 -67.047706)
			(xy 64.364817 -67.149402) (xy 64.410447 -67.254456) (xy 64.448802 -67.362379) (xy 64.479703 -67.472669)
			(xy 64.503005 -67.584809) (xy 64.5186 -67.698279) (xy 64.526415 -67.812548) (xy 64.526922 -67.869816)
			(xy 64.526399 -67.929349) (xy 64.517951 -68.048115) (xy 64.5011 -68.165983) (xy 64.475929 -68.282358)
			(xy 64.442566 -68.396654) (xy 64.401179 -68.508296) (xy 64.377062 -68.562728) (xy 64.376808 -68.562982)
			(xy 64.372998 -68.571872) (xy 64.36995 -68.580762) (xy 64.36868 -68.587112) (xy 64.366771 -68.597113)
			(xy 64.370169 -68.617171) (xy 64.375284 -68.625974) (xy 64.42075 -68.69684) (xy 64.425606 -68.703796)
			(xy 64.438933 -68.714277) (xy 64.454946 -68.719851) (xy 64.463422 -68.720208) (xy 64.470026 -68.720208)
			(xy 64.528576 -68.720708) (xy 64.645395 -68.728819) (xy 64.761372 -68.744998) (xy 64.87595 -68.76917)
			(xy 64.988579 -68.801218) (xy 65.098719 -68.840987) (xy 65.205841 -68.888288) (xy 65.309431 -68.942892)
			(xy 65.40899 -69.004539) (xy 65.504043 -69.072931) (xy 65.594131 -69.147741) (xy 65.678823 -69.22861)
			(xy 65.757711 -69.315149) (xy 65.830419 -69.406943) (xy 65.896595 -69.503551) (xy 65.955923 -69.604509)
			(xy 66.008118 -69.709333) (xy 66.05293 -69.81752) (xy 66.090142 -69.92855) (xy 66.119577 -70.04189)
			(xy 66.141093 -70.156997) (xy 66.154587 -70.273317) (xy 66.159994 -70.390292) (xy 66.159543 -70.409816)
			(xy 66.589915 -70.409816) (xy 66.593942 -70.293213) (xy 66.606004 -70.177166) (xy 66.626043 -70.062228)
			(xy 66.653965 -69.948946) (xy 66.689635 -69.83786) (xy 66.732884 -69.7295) (xy 66.783507 -69.624382)
			(xy 66.84126 -69.523007) (xy 66.905871 -69.425858) (xy 66.977029 -69.333398) (xy 67.054397 -69.246067)
			(xy 67.137606 -69.164283) (xy 67.226259 -69.088434) (xy 67.319933 -69.018882) (xy 67.418183 -68.955958)
			(xy 67.52054 -68.899962) (xy 67.626516 -68.851162) (xy 67.735607 -68.80979) (xy 67.847291 -68.776042)
			(xy 67.961038 -68.75008) (xy 68.076306 -68.732027) (xy 68.192544 -68.72197) (xy 68.309198 -68.719956)
			(xy 68.425714 -68.725995) (xy 68.541536 -68.740059) (xy 68.656111 -68.762079) (xy 68.768894 -68.791952)
			(xy 68.879348 -68.829534) (xy 68.986945 -68.874648) (xy 69.091174 -68.927077) (xy 69.191537 -68.986572)
			(xy 69.287556 -69.052849) (xy 69.378774 -69.125593) (xy 69.464756 -69.204457) (xy 69.545093 -69.289065)
			(xy 69.6194 -69.379014) (xy 69.687325 -69.473875) (xy 69.748544 -69.573196) (xy 69.802764 -69.676504)
			(xy 69.849728 -69.783307) (xy 69.889211 -69.893095) (xy 69.921026 -70.005346) (xy 69.945021 -70.119524)
			(xy 69.961081 -70.235086) (xy 69.96913 -70.35148) (xy 69.969634 -70.409816) (xy 69.96913 -70.468152)
			(xy 69.968162 -70.482155) (xy 82.841845 -70.482155) (xy 82.841845 -70.337485) (xy 82.849957 -70.193044)
			(xy 82.866155 -70.049284) (xy 82.890387 -69.906659) (xy 82.922579 -69.765617) (xy 82.962629 -69.626602)
			(xy 83.01041 -69.490051) (xy 83.065772 -69.356394) (xy 83.128542 -69.226052) (xy 83.198521 -69.099434)
			(xy 83.27549 -68.976939) (xy 83.359205 -68.858953) (xy 83.449405 -68.745846) (xy 83.545805 -68.637974)
			(xy 83.648101 -68.535678) (xy 83.755973 -68.439278) (xy 83.869079 -68.349078) (xy 83.987066 -68.265362)
			(xy 84.109561 -68.188393) (xy 84.236178 -68.118414) (xy 84.366521 -68.055644) (xy 84.500178 -68.000281)
			(xy 84.636728 -67.9525) (xy 84.775743 -67.91245) (xy 84.916785 -67.880258) (xy 85.05941 -67.856025)
			(xy 85.20317 -67.839827) (xy 85.347611 -67.831715) (xy 85.419946 -67.831208) (xy 85.492762 -67.831704)
			(xy 85.638163 -67.839921) (xy 85.782868 -67.856333) (xy 85.926416 -67.880886) (xy 86.06835 -67.913503)
			(xy 86.208216 -67.954079) (xy 86.345568 -68.002486) (xy 86.47997 -68.058568) (xy 86.610991 -68.122147)
			(xy 86.738215 -68.193021) (xy 86.861235 -68.270962) (xy 86.97966 -68.355724) (xy 87.093111 -68.447035)
			(xy 87.201228 -68.544604) (xy 87.25281 -68.596002) (xy 87.259922 -68.603368) (xy 87.278464 -68.610988)
			(xy 87.371428 -68.610988) (xy 87.38997 -68.603368) (xy 87.397082 -68.596002) (xy 87.449805 -68.543447)
			(xy 87.56046 -68.44384) (xy 87.676678 -68.350783) (xy 87.798071 -68.264588) (xy 87.924237 -68.185542)
			(xy 88.054753 -68.113907) (xy 88.189185 -68.049922) (xy 88.327086 -67.993802) (xy 88.467995 -67.945732)
			(xy 88.611443 -67.905873) (xy 88.756952 -67.874358) (xy 88.904037 -67.851292) (xy 89.052208 -67.836752)
			(xy 89.126568 -67.83324) (xy 89.135943 -67.832349) (xy 89.153169 -67.824791) (xy 89.166512 -67.811531)
			(xy 89.174176 -67.794352) (xy 89.175082 -67.78498) (xy 89.178491 -67.727134) (xy 89.192343 -67.612077)
			(xy 89.214105 -67.49825) (xy 89.243673 -67.386198) (xy 89.280906 -67.276454) (xy 89.325628 -67.169542)
			(xy 89.377623 -67.065973) (xy 89.436645 -66.966241) (xy 89.502412 -66.870822) (xy 89.574609 -66.78017)
			(xy 89.652892 -66.69472) (xy 89.736887 -66.614878) (xy 89.826195 -66.541025) (xy 89.920388 -66.473514)
			(xy 90.019017 -66.412667) (xy 90.121612 -66.358774) (xy 90.227683 -66.312093) (xy 90.336723 -66.272847)
			(xy 90.448212 -66.241222) (xy 90.561619 -66.217369) (xy 90.676402 -66.201403) (xy 90.792014 -66.193399)
			(xy 90.849958 -66.192908) (xy 90.907464 -66.193411) (xy 91.022206 -66.201283) (xy 91.136138 -66.217001)
			(xy 91.248725 -66.24049) (xy 91.359438 -66.27164) (xy 91.467756 -66.310304) (xy 91.573169 -66.356301)
			(xy 91.675182 -66.409415) (xy 91.773315 -66.469394) (xy 91.820492 -66.50228) (xy 91.829364 -66.507955)
			(xy 91.849956 -66.512262) (xy 91.870548 -66.507955) (xy 91.87942 -66.50228) (xy 91.926598 -66.469394)
			(xy 92.024731 -66.409414) (xy 92.126744 -66.356298) (xy 92.232157 -66.310298) (xy 92.340474 -66.27163)
			(xy 92.451186 -66.240475) (xy 92.563773 -66.216979) (xy 92.677706 -66.201254) (xy 92.792448 -66.193373)
			(xy 92.90746 -66.193373) (xy 93.022202 -66.201254) (xy 93.136135 -66.216979) (xy 93.248722 -66.240475)
			(xy 93.359434 -66.27163) (xy 93.467751 -66.310298) (xy 93.573164 -66.356298) (xy 93.675177 -66.409414)
			(xy 93.77331 -66.469394) (xy 93.820488 -66.50228) (xy 93.82936 -66.507955) (xy 93.849952 -66.512262)
			(xy 93.870544 -66.507955) (xy 93.879416 -66.50228) (xy 93.926594 -66.469394) (xy 94.024727 -66.409414)
			(xy 94.12674 -66.356298) (xy 94.232153 -66.310298) (xy 94.34047 -66.27163) (xy 94.451182 -66.240475)
			(xy 94.563769 -66.216979) (xy 94.677702 -66.201254) (xy 94.792444 -66.193373) (xy 94.907456 -66.193373)
			(xy 95.022198 -66.201254) (xy 95.136131 -66.216979) (xy 95.248718 -66.240475) (xy 95.35943 -66.27163)
			(xy 95.467747 -66.310298) (xy 95.57316 -66.356298) (xy 95.675173 -66.409414) (xy 95.773306 -66.469394)
			(xy 95.820484 -66.50228) (xy 95.829356 -66.507955) (xy 95.849948 -66.512262) (xy 95.87054 -66.507955)
			(xy 95.879412 -66.50228) (xy 95.92659 -66.469394) (xy 96.024723 -66.409414) (xy 96.126736 -66.356298)
			(xy 96.232149 -66.310298) (xy 96.340466 -66.27163) (xy 96.451178 -66.240475) (xy 96.563765 -66.216979)
			(xy 96.677698 -66.201254) (xy 96.79244 -66.193373) (xy 96.907452 -66.193373) (xy 97.022194 -66.201254)
			(xy 97.136127 -66.216979) (xy 97.248714 -66.240475) (xy 97.359426 -66.27163) (xy 97.467743 -66.310298)
			(xy 97.573156 -66.356298) (xy 97.675169 -66.409414) (xy 97.773302 -66.469394) (xy 97.82048 -66.50228)
			(xy 97.829352 -66.507955) (xy 97.849944 -66.512262) (xy 97.870536 -66.507955) (xy 97.879408 -66.50228)
			(xy 97.926586 -66.469394) (xy 98.024719 -66.409414) (xy 98.126732 -66.356298) (xy 98.232145 -66.310298)
			(xy 98.340462 -66.27163) (xy 98.451174 -66.240475) (xy 98.563761 -66.216979) (xy 98.677694 -66.201254)
			(xy 98.792436 -66.193373) (xy 98.907448 -66.193373) (xy 99.02219 -66.201254) (xy 99.136123 -66.216979)
			(xy 99.24871 -66.240475) (xy 99.359422 -66.27163) (xy 99.467739 -66.310298) (xy 99.573152 -66.356298)
			(xy 99.675165 -66.409414) (xy 99.773298 -66.469394) (xy 99.820476 -66.50228) (xy 99.829348 -66.507955)
			(xy 99.84994 -66.512262) (xy 99.870532 -66.507955) (xy 99.879404 -66.50228) (xy 99.926582 -66.469394)
			(xy 100.024715 -66.409414) (xy 100.126728 -66.356298) (xy 100.232141 -66.310298) (xy 100.340458 -66.27163)
			(xy 100.45117 -66.240475) (xy 100.563757 -66.216979) (xy 100.67769 -66.201254) (xy 100.792432 -66.193373)
			(xy 100.907444 -66.193373) (xy 101.022186 -66.201254) (xy 101.136119 -66.216979) (xy 101.248706 -66.240475)
			(xy 101.359418 -66.27163) (xy 101.467735 -66.310298) (xy 101.573148 -66.356298) (xy 101.675161 -66.409414)
			(xy 101.773294 -66.469394) (xy 101.820472 -66.50228) (xy 101.829344 -66.507955) (xy 101.849936 -66.512262)
			(xy 101.870528 -66.507955) (xy 101.8794 -66.50228) (xy 101.926592 -66.469417) (xy 102.024726 -66.409439)
			(xy 102.126738 -66.356327) (xy 102.232149 -66.310329) (xy 102.340464 -66.271661) (xy 102.451174 -66.240505)
			(xy 102.563759 -66.217008) (xy 102.677689 -66.201281) (xy 102.792429 -66.193396) (xy 102.849934 -66.192908)
			(xy 102.907203 -66.193348) (xy 103.021474 -66.201167) (xy 103.134945 -66.216765) (xy 103.247086 -66.240071)
			(xy 103.357376 -66.270975) (xy 103.4653 -66.309333) (xy 103.570355 -66.354967) (xy 103.672051 -66.407663)
			(xy 103.769913 -66.467177) (xy 103.863486 -66.53323) (xy 103.952333 -66.605515) (xy 104.036041 -66.683695)
			(xy 104.114218 -66.767404) (xy 104.1865 -66.856254) (xy 104.25255 -66.949829) (xy 104.312061 -67.047693)
			(xy 104.364755 -67.14939) (xy 104.410385 -67.254446) (xy 104.44874 -67.362371) (xy 104.479641 -67.472662)
			(xy 104.502943 -67.584805) (xy 104.518538 -67.698276) (xy 104.526354 -67.812547) (xy 104.526842 -67.869816)
			(xy 104.526281 -67.930561) (xy 104.517476 -68.051731) (xy 104.499929 -68.171946) (xy 104.47373 -68.290577)
			(xy 104.439017 -68.407002) (xy 104.395972 -68.52061) (xy 104.370886 -68.575936) (xy 104.365298 -68.587874)
			(xy 104.367076 -68.613528) (xy 104.427528 -68.708016) (xy 104.450388 -68.720208) (xy 104.469946 -68.720208)
			(xy 104.528495 -68.720739) (xy 104.645311 -68.728851) (xy 104.761286 -68.745031) (xy 104.875861 -68.769204)
			(xy 104.988488 -68.801252) (xy 105.098625 -68.841022) (xy 105.205744 -68.888323) (xy 105.309331 -68.942927)
			(xy 105.408888 -69.004574) (xy 105.503938 -69.072966) (xy 105.594023 -69.147775) (xy 105.678713 -69.228643)
			(xy 105.757599 -69.315181) (xy 105.830304 -69.406973) (xy 105.896478 -69.50358) (xy 105.955804 -69.604537)
			(xy 106.007997 -69.709359) (xy 106.052807 -69.817544) (xy 106.090017 -69.928573) (xy 106.119451 -70.041911)
			(xy 106.140966 -70.157015) (xy 106.154458 -70.273333) (xy 106.159865 -70.390306) (xy 106.159414 -70.409816)
			(xy 106.589835 -70.409816) (xy 106.593862 -70.293213) (xy 106.605924 -70.177166) (xy 106.625963 -70.062228)
			(xy 106.653885 -69.948946) (xy 106.689555 -69.83786) (xy 106.732804 -69.7295) (xy 106.783427 -69.624382)
			(xy 106.84118 -69.523007) (xy 106.905791 -69.425858) (xy 106.976949 -69.333398) (xy 107.054317 -69.246067)
			(xy 107.137526 -69.164283) (xy 107.226179 -69.088434) (xy 107.319853 -69.018882) (xy 107.418103 -68.955958)
			(xy 107.52046 -68.899962) (xy 107.626436 -68.851162) (xy 107.735527 -68.80979) (xy 107.847211 -68.776042)
			(xy 107.960958 -68.75008) (xy 108.076226 -68.732027) (xy 108.192464 -68.72197) (xy 108.309118 -68.719956)
			(xy 108.425634 -68.725995) (xy 108.541456 -68.740059) (xy 108.656031 -68.762079) (xy 108.768814 -68.791952)
			(xy 108.879268 -68.829534) (xy 108.986865 -68.874648) (xy 109.091094 -68.927077) (xy 109.191457 -68.986572)
			(xy 109.287476 -69.052849) (xy 109.378694 -69.125593) (xy 109.464676 -69.204457) (xy 109.545013 -69.289065)
			(xy 109.61932 -69.379014) (xy 109.687245 -69.473875) (xy 109.748464 -69.573196) (xy 109.802684 -69.676504)
			(xy 109.849648 -69.783307) (xy 109.889131 -69.893095) (xy 109.920946 -70.005346) (xy 109.944941 -70.119524)
			(xy 109.961001 -70.235086) (xy 109.96905 -70.35148) (xy 109.969554 -70.409816) (xy 109.96905 -70.468152)
			(xy 109.968083 -70.482135) (xy 122.842006 -70.482135) (xy 122.842006 -70.337465) (xy 122.850118 -70.193024)
			(xy 122.866316 -70.049264) (xy 122.890549 -69.906638) (xy 122.922741 -69.765596) (xy 122.962791 -69.626581)
			(xy 123.010572 -69.49003) (xy 123.065935 -69.356373) (xy 123.128705 -69.226031) (xy 123.198685 -69.099413)
			(xy 123.275654 -68.976918) (xy 123.35937 -68.858931) (xy 123.44957 -68.745825) (xy 123.545971 -68.637953)
			(xy 123.648268 -68.535657) (xy 123.75614 -68.439258) (xy 123.869247 -68.349058) (xy 123.987234 -68.265343)
			(xy 124.10973 -68.188375) (xy 124.236348 -68.118396) (xy 124.366691 -68.055627) (xy 124.500349 -68.000265)
			(xy 124.6369 -67.952485) (xy 124.775916 -67.912436) (xy 124.916958 -67.880245) (xy 125.059584 -67.856013)
			(xy 125.203343 -67.839816) (xy 125.347785 -67.831706) (xy 125.42012 -67.831208) (xy 125.492936 -67.831722)
			(xy 125.638337 -67.839938) (xy 125.783041 -67.856348) (xy 125.926589 -67.8809) (xy 126.068522 -67.913515)
			(xy 126.208388 -67.95409) (xy 126.345741 -68.002495) (xy 126.480142 -68.058576) (xy 126.611164 -68.122154)
			(xy 126.738387 -68.193026) (xy 126.861408 -68.270966) (xy 126.979833 -68.355727) (xy 127.093285 -68.447036)
			(xy 127.201402 -68.544604) (xy 127.252984 -68.596002) (xy 127.260096 -68.603368) (xy 127.278638 -68.610988)
			(xy 127.371602 -68.610988) (xy 127.390144 -68.603368) (xy 127.397256 -68.596002) (xy 127.449991 -68.543459)
			(xy 127.560645 -68.443851) (xy 127.676861 -68.350794) (xy 127.798254 -68.264599) (xy 127.924418 -68.185551)
			(xy 128.054933 -68.113916) (xy 128.189365 -68.04993) (xy 128.327264 -67.993809) (xy 128.468172 -67.945738)
			(xy 128.611619 -67.905878) (xy 128.757127 -67.874362) (xy 128.904212 -67.851294) (xy 129.052382 -67.836753)
			(xy 129.126742 -67.83324) (xy 129.136115 -67.832328) (xy 129.153341 -67.824779) (xy 129.166684 -67.811525)
			(xy 129.174349 -67.79435) (xy 129.175256 -67.78498) (xy 129.178691 -67.727136) (xy 129.192542 -67.61208)
			(xy 129.214304 -67.498254) (xy 129.243871 -67.386203) (xy 129.281104 -67.27646) (xy 129.325825 -67.169549)
			(xy 129.377819 -67.065981) (xy 129.43684 -66.966249) (xy 129.502605 -66.870831) (xy 129.574801 -66.78018)
			(xy 129.653083 -66.694729) (xy 129.737077 -66.614887) (xy 129.826383 -66.541034) (xy 129.920574 -66.473523)
			(xy 130.019202 -66.412676) (xy 130.121795 -66.358783) (xy 130.227864 -66.312101) (xy 130.336903 -66.272853)
			(xy 130.448391 -66.241227) (xy 130.561797 -66.217373) (xy 130.676578 -66.201406) (xy 130.792188 -66.1934)
			(xy 130.850132 -66.192908) (xy 130.907638 -66.19337) (xy 131.022381 -66.201248) (xy 131.136315 -66.216971)
			(xy 131.248902 -66.240465) (xy 131.359615 -66.27162) (xy 131.467933 -66.310289) (xy 131.573345 -66.35629)
			(xy 131.675357 -66.409408) (xy 131.773489 -66.469392) (xy 131.820666 -66.50228) (xy 131.829538 -66.507955)
			(xy 131.85013 -66.512262) (xy 131.870722 -66.507955) (xy 131.879594 -66.50228) (xy 131.926772 -66.469394)
			(xy 132.024905 -66.409414) (xy 132.126918 -66.356298) (xy 132.232331 -66.310298) (xy 132.340648 -66.27163)
			(xy 132.45136 -66.240475) (xy 132.563947 -66.216979) (xy 132.67788 -66.201254) (xy 132.792622 -66.193373)
			(xy 132.907634 -66.193373) (xy 133.022376 -66.201254) (xy 133.136309 -66.216979) (xy 133.248896 -66.240475)
			(xy 133.359608 -66.27163) (xy 133.467925 -66.310298) (xy 133.573338 -66.356298) (xy 133.675351 -66.409414)
			(xy 133.773484 -66.469394) (xy 133.820662 -66.50228) (xy 133.829534 -66.507955) (xy 133.850126 -66.512262)
			(xy 133.870718 -66.507955) (xy 133.87959 -66.50228) (xy 133.926768 -66.469394) (xy 134.024901 -66.409414)
			(xy 134.126914 -66.356298) (xy 134.232327 -66.310298) (xy 134.340644 -66.27163) (xy 134.451356 -66.240475)
			(xy 134.563943 -66.216979) (xy 134.677876 -66.201254) (xy 134.792618 -66.193373) (xy 134.90763 -66.193373)
			(xy 135.022372 -66.201254) (xy 135.136305 -66.216979) (xy 135.248892 -66.240475) (xy 135.359604 -66.27163)
			(xy 135.467921 -66.310298) (xy 135.573334 -66.356298) (xy 135.675347 -66.409414) (xy 135.77348 -66.469394)
			(xy 135.820658 -66.50228) (xy 135.82953 -66.507955) (xy 135.850122 -66.512262) (xy 135.870714 -66.507955)
			(xy 135.879586 -66.50228) (xy 135.926764 -66.469394) (xy 136.024897 -66.409414) (xy 136.12691 -66.356298)
			(xy 136.232323 -66.310298) (xy 136.34064 -66.27163) (xy 136.451352 -66.240475) (xy 136.563939 -66.216979)
			(xy 136.677872 -66.201254) (xy 136.792614 -66.193373) (xy 136.907626 -66.193373) (xy 137.022368 -66.201254)
			(xy 137.136301 -66.216979) (xy 137.248888 -66.240475) (xy 137.3596 -66.27163) (xy 137.467917 -66.310298)
			(xy 137.57333 -66.356298) (xy 137.675343 -66.409414) (xy 137.773476 -66.469394) (xy 137.820654 -66.50228)
			(xy 137.829526 -66.507955) (xy 137.850118 -66.512262) (xy 137.87071 -66.507955) (xy 137.879582 -66.50228)
			(xy 137.92676 -66.469394) (xy 138.024893 -66.409414) (xy 138.126906 -66.356298) (xy 138.232319 -66.310298)
			(xy 138.340636 -66.27163) (xy 138.451348 -66.240475) (xy 138.563935 -66.216979) (xy 138.677868 -66.201254)
			(xy 138.79261 -66.193373) (xy 138.907622 -66.193373) (xy 139.022364 -66.201254) (xy 139.136297 -66.216979)
			(xy 139.248884 -66.240475) (xy 139.359596 -66.27163) (xy 139.467913 -66.310298) (xy 139.573326 -66.356298)
			(xy 139.675339 -66.409414) (xy 139.773472 -66.469394) (xy 139.82065 -66.50228) (xy 139.829522 -66.507955)
			(xy 139.850114 -66.512262) (xy 139.870706 -66.507955) (xy 139.879578 -66.50228) (xy 139.926756 -66.469394)
			(xy 140.024889 -66.409414) (xy 140.126902 -66.356298) (xy 140.232315 -66.310298) (xy 140.340632 -66.27163)
			(xy 140.451344 -66.240475) (xy 140.563931 -66.216979) (xy 140.677864 -66.201254) (xy 140.792606 -66.193373)
			(xy 140.907618 -66.193373) (xy 141.02236 -66.201254) (xy 141.136293 -66.216979) (xy 141.24888 -66.240475)
			(xy 141.359592 -66.27163) (xy 141.467909 -66.310298) (xy 141.573322 -66.356298) (xy 141.675335 -66.409414)
			(xy 141.773468 -66.469394) (xy 141.820646 -66.50228) (xy 141.829518 -66.507955) (xy 141.85011 -66.512262)
			(xy 141.870702 -66.507955) (xy 141.879574 -66.50228) (xy 141.926743 -66.469383) (xy 142.02488 -66.409409)
			(xy 142.126895 -66.356299) (xy 142.23231 -66.310304) (xy 142.340628 -66.27164) (xy 142.451341 -66.240489)
			(xy 142.563928 -66.216996) (xy 142.67786 -66.201273) (xy 142.792602 -66.193394) (xy 142.850108 -66.192908)
			(xy 142.907377 -66.193362) (xy 143.021648 -66.201179) (xy 143.135119 -66.216776) (xy 143.247261 -66.24008)
			(xy 143.357552 -66.270983) (xy 143.465476 -66.30934) (xy 143.570532 -66.354972) (xy 143.672228 -66.407668)
			(xy 143.770091 -66.467181) (xy 143.863665 -66.533233) (xy 143.952513 -66.605517) (xy 144.036221 -66.683696)
			(xy 144.114398 -66.767405) (xy 144.186681 -66.856254) (xy 144.252732 -66.949829) (xy 144.312244 -67.047693)
			(xy 144.364938 -67.14939) (xy 144.410569 -67.254446) (xy 144.448925 -67.362371) (xy 144.479826 -67.472662)
			(xy 144.503128 -67.584805) (xy 144.518723 -67.698276) (xy 144.526539 -67.812547) (xy 144.527016 -67.869816)
			(xy 144.526458 -67.930561) (xy 144.517653 -68.051731) (xy 144.500105 -68.171947) (xy 144.473905 -68.290578)
			(xy 144.439192 -68.407002) (xy 144.396146 -68.520611) (xy 144.37106 -68.575936) (xy 144.365472 -68.587874)
			(xy 144.36725 -68.613528) (xy 144.427702 -68.708016) (xy 144.450562 -68.720208) (xy 144.47012 -68.720208)
			(xy 144.52867 -68.720712) (xy 144.645489 -68.728822) (xy 144.761465 -68.745001) (xy 144.876044 -68.769173)
			(xy 144.988673 -68.80122) (xy 145.098813 -68.840989) (xy 145.205935 -68.888289) (xy 145.309524 -68.942893)
			(xy 145.409084 -69.004539) (xy 145.504136 -69.072931) (xy 145.594224 -69.147741) (xy 145.678916 -69.228609)
			(xy 145.757805 -69.315148) (xy 145.830513 -69.406941) (xy 145.896689 -69.503549) (xy 145.956018 -69.604507)
			(xy 146.008213 -69.709331) (xy 146.053024 -69.817517) (xy 146.090237 -69.928547) (xy 146.119672 -70.041887)
			(xy 146.141189 -70.156993) (xy 146.154683 -70.273313) (xy 146.16009 -70.390288) (xy 146.159639 -70.409816)
			(xy 146.590009 -70.409816) (xy 146.594036 -70.293213) (xy 146.606098 -70.177166) (xy 146.626137 -70.062228)
			(xy 146.654059 -69.948946) (xy 146.689729 -69.83786) (xy 146.732978 -69.7295) (xy 146.783601 -69.624382)
			(xy 146.841354 -69.523007) (xy 146.905965 -69.425858) (xy 146.977123 -69.333398) (xy 147.054491 -69.246067)
			(xy 147.1377 -69.164283) (xy 147.226353 -69.088434) (xy 147.320027 -69.018882) (xy 147.418277 -68.955958)
			(xy 147.520634 -68.899962) (xy 147.62661 -68.851162) (xy 147.735701 -68.80979) (xy 147.847385 -68.776042)
			(xy 147.961132 -68.75008) (xy 148.0764 -68.732027) (xy 148.192638 -68.72197) (xy 148.309292 -68.719956)
			(xy 148.425808 -68.725995) (xy 148.54163 -68.740059) (xy 148.656205 -68.762079) (xy 148.768988 -68.791952)
			(xy 148.879442 -68.829534) (xy 148.987039 -68.874648) (xy 149.091268 -68.927077) (xy 149.191631 -68.986572)
			(xy 149.28765 -69.052849) (xy 149.378868 -69.125593) (xy 149.46485 -69.204457) (xy 149.545187 -69.289065)
			(xy 149.619494 -69.379014) (xy 149.687419 -69.473875) (xy 149.748638 -69.573196) (xy 149.802858 -69.676504)
			(xy 149.849822 -69.783307) (xy 149.889305 -69.893095) (xy 149.92112 -70.005346) (xy 149.945115 -70.119524)
			(xy 149.961175 -70.235086) (xy 149.969224 -70.35148) (xy 149.969728 -70.409816) (xy 149.969224 -70.468152)
			(xy 149.968257 -70.482134) (xy 162.842215 -70.482134) (xy 162.842215 -70.337466) (xy 162.850327 -70.193026)
			(xy 162.866524 -70.049267) (xy 162.890757 -69.906643) (xy 162.922949 -69.765603) (xy 162.962998 -69.626589)
			(xy 163.010779 -69.490039) (xy 163.06614 -69.356383) (xy 163.128909 -69.226042) (xy 163.198888 -69.099425)
			(xy 163.275856 -68.976931) (xy 163.359571 -68.858945) (xy 163.44977 -68.745839) (xy 163.546169 -68.637969)
			(xy 163.648464 -68.535673) (xy 163.756335 -68.439274) (xy 163.869441 -68.349075) (xy 163.987426 -68.265359)
			(xy 164.10992 -68.188391) (xy 164.236536 -68.118412) (xy 164.366878 -68.055643) (xy 164.500533 -68.000281)
			(xy 164.637083 -67.9525) (xy 164.776097 -67.91245) (xy 164.917137 -67.880258) (xy 165.059761 -67.856025)
			(xy 165.20352 -67.839827) (xy 165.34796 -67.831715) (xy 165.420294 -67.831208) (xy 165.49311 -67.83174)
			(xy 165.63851 -67.839954) (xy 165.783214 -67.856363) (xy 165.926762 -67.880913) (xy 166.068695 -67.913527)
			(xy 166.208561 -67.954101) (xy 166.345913 -68.002504) (xy 166.480315 -68.058584) (xy 166.611336 -68.12216)
			(xy 166.73856 -68.193031) (xy 166.861581 -68.27097) (xy 166.980006 -68.355729) (xy 167.093458 -68.447038)
			(xy 167.201576 -68.544605) (xy 167.253158 -68.596002) (xy 167.26027 -68.603368) (xy 167.278812 -68.610988)
			(xy 167.371776 -68.610988) (xy 167.390318 -68.603368) (xy 167.39743 -68.596002) (xy 167.450177 -68.543471)
			(xy 167.560829 -68.443863) (xy 167.677045 -68.350806) (xy 167.798436 -68.264609) (xy 167.9246 -68.185561)
			(xy 168.055114 -68.113925) (xy 168.189544 -68.049938) (xy 168.327442 -67.993816) (xy 168.46835 -67.945744)
			(xy 168.611796 -67.905883) (xy 168.757303 -67.874365) (xy 168.904387 -67.851297) (xy 169.052556 -67.836753)
			(xy 169.126916 -67.83324) (xy 169.136286 -67.832308) (xy 169.153512 -67.824767) (xy 169.166857 -67.811519)
			(xy 169.174523 -67.794348) (xy 169.17543 -67.78498) (xy 169.178891 -67.727138) (xy 169.192742 -67.612083)
			(xy 169.214503 -67.498258) (xy 169.24407 -67.386208) (xy 169.281302 -67.276466) (xy 169.326021 -67.169556)
			(xy 169.378015 -67.065988) (xy 169.437035 -66.966258) (xy 169.502799 -66.870839) (xy 169.574993 -66.780189)
			(xy 169.653273 -66.694738) (xy 169.737266 -66.614896) (xy 169.826571 -66.541043) (xy 169.920761 -66.473532)
			(xy 170.019387 -66.412684) (xy 170.121978 -66.358791) (xy 170.228046 -66.312108) (xy 170.337083 -66.27286)
			(xy 170.44857 -66.241232) (xy 170.561974 -66.217377) (xy 170.676754 -66.201408) (xy 170.792363 -66.193401)
			(xy 170.850306 -66.192908) (xy 170.907812 -66.193384) (xy 171.022555 -66.20126) (xy 171.136488 -66.216981)
			(xy 171.249075 -66.240474) (xy 171.359788 -66.271627) (xy 171.468106 -66.310294) (xy 171.573519 -66.356294)
			(xy 171.675531 -66.40941) (xy 171.773663 -66.469393) (xy 171.82084 -66.50228) (xy 171.829712 -66.507955)
			(xy 171.850304 -66.512262) (xy 171.870896 -66.507955) (xy 171.879768 -66.50228) (xy 171.926946 -66.469394)
			(xy 172.025079 -66.409414) (xy 172.127092 -66.356298) (xy 172.232505 -66.310298) (xy 172.340822 -66.27163)
			(xy 172.451534 -66.240475) (xy 172.564121 -66.216979) (xy 172.678054 -66.201254) (xy 172.792796 -66.193373)
			(xy 172.907808 -66.193373) (xy 173.02255 -66.201254) (xy 173.136483 -66.216979) (xy 173.24907 -66.240475)
			(xy 173.359782 -66.27163) (xy 173.468099 -66.310298) (xy 173.573512 -66.356298) (xy 173.675525 -66.409414)
			(xy 173.773658 -66.469394) (xy 173.820836 -66.50228) (xy 173.829708 -66.507955) (xy 173.8503 -66.512262)
			(xy 173.870892 -66.507955) (xy 173.879764 -66.50228) (xy 173.926292 -66.469815) (xy 174.023054 -66.410558)
			(xy 174.1236 -66.357977) (xy 174.22747 -66.312312) (xy 174.33419 -66.273774) (xy 174.443271 -66.242537)
			(xy 174.554214 -66.218746) (xy 174.666511 -66.202508) (xy 174.723044 -66.197734) (xy 174.733712 -66.196972)
			(xy 174.762821 -66.195065) (xy 174.821127 -66.193033) (xy 174.850298 -66.192908) (xy 174.907804 -66.193389)
			(xy 175.022547 -66.201264) (xy 175.136479 -66.216985) (xy 175.249067 -66.240476) (xy 175.35978 -66.271629)
			(xy 175.468097 -66.310296) (xy 175.57351 -66.356295) (xy 175.675523 -66.409411) (xy 175.773655 -66.469393)
			(xy 175.820832 -66.50228) (xy 175.829704 -66.507955) (xy 175.850296 -66.512262) (xy 175.870888 -66.507955)
			(xy 175.87976 -66.50228) (xy 175.929221 -66.467853) (xy 176.03227 -66.405352) (xy 176.139539 -66.350408)
			(xy 176.250474 -66.303302) (xy 176.364503 -66.264279) (xy 176.481038 -66.233539) (xy 176.54016 -66.221864)
			(xy 176.551082 -66.219832) (xy 176.569116 -66.206878) (xy 176.597818 -66.15684) (xy 176.583765 -66.11055)
			(xy 176.561879 -66.016311) (xy 176.547215 -65.920681) (xy 176.539856 -65.824214) (xy 176.539398 -65.77584)
			(xy 176.539502 -65.750986) (xy 176.541406 -65.701315) (xy 176.543208 -65.676526) (xy 176.543208 -65.662048)
			(xy 176.543208 -65.661286) (xy 176.543698 -65.611387) (xy 176.551528 -65.511896) (xy 176.56714 -65.413327)
			(xy 176.590437 -65.316286) (xy 176.621277 -65.221372) (xy 176.659468 -65.12917) (xy 176.704775 -65.040249)
			(xy 176.75692 -64.955157) (xy 176.81558 -64.874419) (xy 176.880394 -64.798532) (xy 176.950962 -64.727964)
			(xy 177.026849 -64.66315) (xy 177.107587 -64.60449) (xy 177.192679 -64.552345) (xy 177.2816 -64.507038)
			(xy 177.373802 -64.468847) (xy 177.468716 -64.438007) (xy 177.565757 -64.41471) (xy 177.664326 -64.399098)
			(xy 177.763817 -64.391268) (xy 177.863615 -64.391268) (xy 177.963106 -64.399098) (xy 178.061675 -64.41471)
			(xy 178.158716 -64.438007) (xy 178.25363 -64.468847) (xy 178.345832 -64.507038) (xy 178.434753 -64.552345)
			(xy 178.519845 -64.60449) (xy 178.600583 -64.66315) (xy 178.67647 -64.727964) (xy 178.747038 -64.798532)
			(xy 178.811852 -64.874419) (xy 178.870512 -64.955157) (xy 178.922657 -65.040249) (xy 178.967964 -65.12917)
			(xy 179.006155 -65.221372) (xy 179.036995 -65.316286) (xy 179.060292 -65.413327) (xy 179.075904 -65.511896)
			(xy 179.083734 -65.611387) (xy 179.084224 -65.661286) (xy 179.08409 -65.684677) (xy 179.082311 -65.731425)
			(xy 179.080668 -65.754758) (xy 179.080922 -65.77584) (xy 179.080488 -65.821528) (xy 179.073897 -65.912665)
			(xy 179.060773 -66.003093) (xy 179.041184 -66.092344) (xy 179.028598 -66.136266) (xy 179.065428 -66.196718)
			(xy 179.08397 -66.209164) (xy 179.0954 -66.210942) (xy 179.151089 -66.219643) (xy 179.261249 -66.243557)
			(xy 179.369553 -66.274819) (xy 179.475512 -66.313288) (xy 179.578646 -66.35879) (xy 179.678489 -66.411119)
			(xy 179.77459 -66.47004) (xy 179.820824 -66.50228) (xy 179.829696 -66.507955) (xy 179.850288 -66.512262)
			(xy 179.87088 -66.507955) (xy 179.879752 -66.50228) (xy 179.926928 -66.469393) (xy 180.025064 -66.409418)
			(xy 180.127078 -66.356307) (xy 180.232492 -66.310312) (xy 180.340809 -66.271646) (xy 180.451521 -66.240494)
			(xy 180.564108 -66.217) (xy 180.678039 -66.201276) (xy 180.79278 -66.193394) (xy 180.850286 -66.192908)
			(xy 180.896229 -66.19324) (xy 180.987975 -66.198324) (xy 181.033674 -66.203068) (xy 181.050438 -66.204846)
			(xy 181.079902 -66.18732) (xy 181.129432 -66.0654) (xy 181.120796 -66.03238) (xy 181.107334 -66.021966)
			(xy 181.066363 -65.989251) (xy 180.989325 -65.91812) (xy 180.918413 -65.84088) (xy 180.85411 -65.758059)
			(xy 180.796852 -65.670218) (xy 180.74703 -65.577957) (xy 180.704982 -65.481902) (xy 180.670996 -65.382709)
			(xy 180.645301 -65.281052) (xy 180.628074 -65.177623) (xy 180.619431 -65.073125) (xy 180.618892 -65.020698)
			(xy 180.618892 -65.020444) (xy 180.619396 -64.97028) (xy 180.627319 -64.870264) (xy 180.643103 -64.771185)
			(xy 180.666649 -64.673658) (xy 180.697812 -64.578292) (xy 180.736396 -64.485679) (xy 180.758846 -64.440816)
			(xy 180.765196 -64.428878) (xy 180.76418 -64.402716) (xy 180.711856 -64.317118) (xy 180.706998 -64.309917)
			(xy 180.693485 -64.299024) (xy 180.677102 -64.293294) (xy 180.668422 -64.292988) (xy 179.000912 -64.292988)
			(xy 178.892454 -64.18453) (xy 178.892454 -61.594238) (xy 178.67376 -61.375544) (xy 178.67376 -59.19724)
			(xy 179.266088 -58.604912) (xy 181.66969 -58.604912) (xy 181.679697 -58.605353) (xy 181.698159 -58.613087)
			(xy 181.705504 -58.619898) (xy 182.393082 -59.307476) (xy 182.399809 -59.314878) (xy 182.407528 -59.333304)
			(xy 182.408068 -59.34329) (xy 182.408068 -61.722508) (xy 186.04992 -61.722508) (xy 186.04992 -60.198)
			(xy 186.050435 -60.181304) (xy 186.059068 -60.149047) (xy 186.075747 -60.120118) (xy 186.099338 -60.096485)
			(xy 186.128237 -60.079755) (xy 186.160479 -60.071065) (xy 186.177174 -60.070492) (xy 187.701174 -60.070492)
			(xy 187.717837 -60.071011) (xy 187.750032 -60.079622) (xy 187.778905 -60.096265) (xy 187.802492 -60.119809)
			(xy 187.819188 -60.148651) (xy 187.827859 -60.18083) (xy 187.828428 -60.197492) (xy 187.828428 -61.722)
			(xy 187.828411 -61.722508) (xy 197.22592 -61.722508) (xy 197.22592 -60.198) (xy 197.226435 -60.181304)
			(xy 197.235068 -60.149047) (xy 197.251747 -60.120118) (xy 197.275338 -60.096485) (xy 197.304237 -60.079755)
			(xy 197.336479 -60.071065) (xy 197.353174 -60.070492) (xy 198.877174 -60.070492) (xy 198.893837 -60.071011)
			(xy 198.926032 -60.079622) (xy 198.954905 -60.096265) (xy 198.978492 -60.119809) (xy 198.995188 -60.148651)
			(xy 199.003859 -60.18083) (xy 199.004428 -60.197492) (xy 199.004428 -61.722) (xy 199.004411 -61.722508)
			(xy 208.40192 -61.722508) (xy 208.40192 -60.198) (xy 208.402435 -60.181304) (xy 208.411068 -60.149047)
			(xy 208.427747 -60.120118) (xy 208.451338 -60.096485) (xy 208.480237 -60.079755) (xy 208.512479 -60.071065)
			(xy 208.529174 -60.070492) (xy 210.053174 -60.070492) (xy 210.069837 -60.071011) (xy 210.102032 -60.079622)
			(xy 210.130905 -60.096265) (xy 210.154492 -60.119809) (xy 210.171188 -60.148651) (xy 210.179859 -60.18083)
			(xy 210.180428 -60.197492) (xy 210.180428 -61.722) (xy 210.179866 -61.738692) (xy 210.171237 -61.770942)
			(xy 210.154565 -61.799866) (xy 210.130984 -61.823498) (xy 210.102096 -61.840231) (xy 210.069865 -61.84893)
			(xy 210.053174 -61.849508) (xy 208.529174 -61.849508) (xy 208.512508 -61.849035) (xy 208.480312 -61.840411)
			(xy 208.45144 -61.823757) (xy 208.427854 -61.800205) (xy 208.411159 -61.771357) (xy 208.402489 -61.739173)
			(xy 208.40192 -61.722508) (xy 199.004411 -61.722508) (xy 199.003866 -61.738692) (xy 198.995237 -61.770942)
			(xy 198.978565 -61.799866) (xy 198.954984 -61.823498) (xy 198.926096 -61.840231) (xy 198.893865 -61.84893)
			(xy 198.877174 -61.849508) (xy 197.353174 -61.849508) (xy 197.336508 -61.849035) (xy 197.304312 -61.840411)
			(xy 197.27544 -61.823757) (xy 197.251854 -61.800205) (xy 197.235159 -61.771357) (xy 197.226489 -61.739173)
			(xy 197.22592 -61.722508) (xy 187.828411 -61.722508) (xy 187.827866 -61.738692) (xy 187.819237 -61.770942)
			(xy 187.802565 -61.799866) (xy 187.778984 -61.823498) (xy 187.750096 -61.840231) (xy 187.717865 -61.84893)
			(xy 187.701174 -61.849508) (xy 186.177174 -61.849508) (xy 186.160508 -61.849035) (xy 186.128312 -61.840411)
			(xy 186.09944 -61.823757) (xy 186.075854 -61.800205) (xy 186.059159 -61.771357) (xy 186.050489 -61.739173)
			(xy 186.04992 -61.722508) (xy 182.408068 -61.722508) (xy 182.408068 -63.860934) (xy 182.4555 -63.882737)
			(xy 182.546987 -63.93303) (xy 182.634039 -63.990662) (xy 182.716066 -64.055244) (xy 182.792516 -64.126341)
			(xy 182.862873 -64.203472) (xy 182.926662 -64.286118) (xy 182.983453 -64.37372) (xy 183.032863 -64.465688)
			(xy 183.074557 -64.561401) (xy 183.108256 -64.660212) (xy 183.13373 -64.761457) (xy 183.15081 -64.86445)
			(xy 183.159378 -64.968498) (xy 183.159908 -65.020698) (xy 183.15942 -65.072618) (xy 183.150946 -65.176111)
			(xy 183.134053 -65.278568) (xy 183.108855 -65.379304) (xy 183.07552 -65.477647) (xy 183.03427 -65.572942)
			(xy 182.98538 -65.664552) (xy 182.929176 -65.751867) (xy 182.866034 -65.834303) (xy 182.796375 -65.911312)
			(xy 182.720663 -65.982378) (xy 182.680356 -66.015108) (xy 182.667148 -66.025268) (xy 182.658512 -66.057272)
			(xy 182.704994 -66.178938) (xy 182.732934 -66.196972) (xy 182.749698 -66.195956) (xy 182.77482 -66.194534)
			(xy 182.82512 -66.193009) (xy 182.850282 -66.192908) (xy 182.90775 -66.193369) (xy 183.022416 -66.20124)
			(xy 183.136273 -66.216946) (xy 183.248788 -66.240414) (xy 183.359431 -66.271533) (xy 183.467683 -66.310156)
			(xy 183.573035 -66.356104) (xy 183.674992 -66.409159) (xy 183.773077 -66.469073) (xy 183.866827 -66.535564)
			(xy 183.955804 -66.60832) (xy 184.039588 -66.686999) (xy 184.117786 -66.771232) (xy 184.190032 -66.860623)
			(xy 184.223406 -66.90741) (xy 184.225184 -66.90995) (xy 184.257286 -66.95679) (xy 184.315846 -67.054092)
			(xy 184.36769 -67.155133) (xy 184.412581 -67.259448) (xy 184.450314 -67.366562) (xy 184.480714 -67.475982)
			(xy 184.503644 -67.587208) (xy 184.518998 -67.69973) (xy 184.526705 -67.813034) (xy 184.52719 -67.869816)
			(xy 184.526625 -67.930561) (xy 184.51782 -68.05173) (xy 184.500273 -68.171946) (xy 184.474075 -68.290577)
			(xy 184.439363 -68.407002) (xy 184.396319 -68.52061) (xy 184.371234 -68.575936) (xy 184.365646 -68.587874)
			(xy 184.367424 -68.613528) (xy 184.427876 -68.708016) (xy 184.450736 -68.720208) (xy 184.470294 -68.720208)
			(xy 184.528845 -68.720685) (xy 184.645666 -68.728794) (xy 184.761645 -68.744971) (xy 184.876226 -68.769142)
			(xy 184.988858 -68.801188) (xy 185.099 -68.840956) (xy 185.206125 -68.888255) (xy 185.309717 -68.942859)
			(xy 185.409279 -69.004505) (xy 185.504334 -69.072897) (xy 185.594425 -69.147707) (xy 185.67912 -69.228576)
			(xy 185.758011 -69.315115) (xy 185.830721 -69.406909) (xy 185.8969 -69.503518) (xy 185.956231 -69.604477)
			(xy 186.008428 -69.709302) (xy 186.053242 -69.81749) (xy 186.090456 -69.928521) (xy 186.119893 -70.041863)
			(xy 186.141412 -70.156971) (xy 186.154907 -70.273293) (xy 186.160316 -70.39027) (xy 186.159865 -70.409816)
			(xy 186.590183 -70.409816) (xy 186.59421 -70.293213) (xy 186.606272 -70.177166) (xy 186.626311 -70.062228)
			(xy 186.654233 -69.948946) (xy 186.689903 -69.83786) (xy 186.733152 -69.7295) (xy 186.783775 -69.624382)
			(xy 186.841528 -69.523007) (xy 186.906139 -69.425858) (xy 186.977297 -69.333398) (xy 187.054665 -69.246067)
			(xy 187.137874 -69.164283) (xy 187.226527 -69.088434) (xy 187.320201 -69.018882) (xy 187.418451 -68.955958)
			(xy 187.520808 -68.899962) (xy 187.626784 -68.851162) (xy 187.735875 -68.80979) (xy 187.847559 -68.776042)
			(xy 187.961306 -68.75008) (xy 188.076574 -68.732027) (xy 188.192812 -68.72197) (xy 188.309466 -68.719956)
			(xy 188.425982 -68.725995) (xy 188.541804 -68.740059) (xy 188.656379 -68.762079) (xy 188.769162 -68.791952)
			(xy 188.879616 -68.829534) (xy 188.987213 -68.874648) (xy 189.091442 -68.927077) (xy 189.191805 -68.986572)
			(xy 189.287824 -69.052849) (xy 189.379042 -69.125593) (xy 189.465024 -69.204457) (xy 189.545361 -69.289065)
			(xy 189.619668 -69.379014) (xy 189.687593 -69.473875) (xy 189.748812 -69.573196) (xy 189.803032 -69.676504)
			(xy 189.849996 -69.783307) (xy 189.889479 -69.893095) (xy 189.921294 -70.005346) (xy 189.945289 -70.119524)
			(xy 189.961349 -70.235086) (xy 189.969398 -70.35148) (xy 189.969902 -70.409816) (xy 189.969398 -70.468152)
			(xy 189.961349 -70.584546) (xy 189.945289 -70.700108) (xy 189.921294 -70.814286) (xy 189.889479 -70.926537)
			(xy 189.849996 -71.036325) (xy 189.803032 -71.143128) (xy 189.748812 -71.246436) (xy 189.687593 -71.345757)
			(xy 189.619668 -71.440618) (xy 189.545361 -71.530567) (xy 189.465024 -71.615175) (xy 189.379042 -71.694039)
			(xy 189.287824 -71.766783) (xy 189.191805 -71.83306) (xy 189.091442 -71.892555) (xy 188.987213 -71.944984)
			(xy 188.879616 -71.990098) (xy 188.769162 -72.02768) (xy 188.656379 -72.057553) (xy 188.541804 -72.079573)
			(xy 188.425982 -72.093637) (xy 188.309466 -72.099676) (xy 188.192812 -72.097662) (xy 188.076574 -72.087605)
			(xy 187.961306 -72.069552) (xy 187.847559 -72.04359) (xy 187.735875 -72.009842) (xy 187.626784 -71.96847)
			(xy 187.520808 -71.91967) (xy 187.418451 -71.863674) (xy 187.320201 -71.80075) (xy 187.226527 -71.731198)
			(xy 187.137874 -71.655349) (xy 187.054665 -71.573565) (xy 186.977297 -71.486234) (xy 186.906139 -71.393774)
			(xy 186.841528 -71.296625) (xy 186.783775 -71.19525) (xy 186.733152 -71.090132) (xy 186.689903 -70.981772)
			(xy 186.654233 -70.870686) (xy 186.626311 -70.757404) (xy 186.606272 -70.642466) (xy 186.59421 -70.526419)
			(xy 186.590183 -70.409816) (xy 186.159865 -70.409816) (xy 186.157612 -70.507341) (xy 186.146808 -70.623944)
			(xy 186.127956 -70.739518) (xy 186.101146 -70.85351) (xy 186.066507 -70.965372) (xy 186.024205 -71.074566)
			(xy 185.974444 -71.18057) (xy 185.917462 -71.282873) (xy 185.853534 -71.380985) (xy 185.782964 -71.474435)
			(xy 185.706094 -71.562774) (xy 185.623291 -71.645579) (xy 185.534952 -71.72245) (xy 185.441503 -71.793021)
			(xy 185.343392 -71.856951) (xy 185.241089 -71.913934) (xy 185.135087 -71.963697) (xy 185.025893 -72.006)
			(xy 184.914031 -72.04064) (xy 184.80004 -72.067451) (xy 184.684465 -72.086305) (xy 184.567863 -72.097111)
			(xy 184.450792 -72.099816) (xy 184.333815 -72.094409) (xy 184.217493 -72.080915) (xy 184.102385 -72.059398)
			(xy 183.989043 -72.029963) (xy 183.878011 -71.99275) (xy 183.769822 -71.947937) (xy 183.664996 -71.895741)
			(xy 183.564036 -71.836412) (xy 183.467427 -71.770234) (xy 183.375632 -71.697525) (xy 183.289091 -71.618635)
			(xy 183.208222 -71.533942) (xy 183.133411 -71.443852) (xy 183.065017 -71.348798) (xy 183.00337 -71.249236)
			(xy 182.948765 -71.145645) (xy 182.901464 -71.038521) (xy 182.861694 -70.928379) (xy 182.829647 -70.815747)
			(xy 182.805475 -70.701167) (xy 182.789296 -70.585188) (xy 182.781186 -70.468367) (xy 182.780686 -70.409816)
			(xy 182.781228 -70.347982) (xy 182.790274 -70.224645) (xy 182.808313 -70.102299) (xy 182.835246 -69.981599)
			(xy 182.870931 -69.863191) (xy 182.915177 -69.747709) (xy 182.94096 -69.691504) (xy 182.946548 -69.679566)
			(xy 182.945024 -69.653912) (xy 182.884826 -69.55917) (xy 182.86222 -69.546724) (xy 182.849012 -69.546724)
			(xy 182.791577 -69.546207) (xy 182.67698 -69.538263) (xy 182.563197 -69.522493) (xy 182.450759 -69.498973)
			(xy 182.340195 -69.467811) (xy 182.232023 -69.429155) (xy 182.126752 -69.383185) (xy 182.024873 -69.330117)
			(xy 181.926866 -69.2702) (xy 181.879748 -69.237352) (xy 181.870876 -69.231677) (xy 181.850284 -69.22737)
			(xy 181.829692 -69.231677) (xy 181.82082 -69.237352) (xy 181.773642 -69.270238) (xy 181.675509 -69.330218)
			(xy 181.573496 -69.383334) (xy 181.468083 -69.429334) (xy 181.359766 -69.468002) (xy 181.249054 -69.499157)
			(xy 181.136467 -69.522653) (xy 181.022534 -69.538378) (xy 180.907792 -69.546259) (xy 180.79278 -69.546259)
			(xy 180.678038 -69.538378) (xy 180.564105 -69.522653) (xy 180.451518 -69.499157) (xy 180.340806 -69.468002)
			(xy 180.232489 -69.429334) (xy 180.127076 -69.383334) (xy 180.025063 -69.330218) (xy 179.92693 -69.270238)
			(xy 179.879752 -69.237352) (xy 179.87088 -69.231677) (xy 179.850288 -69.22737) (xy 179.829696 -69.231677)
			(xy 179.820824 -69.237352) (xy 179.773646 -69.270238) (xy 179.675513 -69.330218) (xy 179.5735 -69.383334)
			(xy 179.468087 -69.429334) (xy 179.35977 -69.468002) (xy 179.249058 -69.499157) (xy 179.136471 -69.522653)
			(xy 179.022538 -69.538378) (xy 178.907796 -69.546259) (xy 178.792784 -69.546259) (xy 178.678042 -69.538378)
			(xy 178.564109 -69.522653) (xy 178.451522 -69.499157) (xy 178.34081 -69.468002) (xy 178.232493 -69.429334)
			(xy 178.12708 -69.383334) (xy 178.025067 -69.330218) (xy 177.926934 -69.270238) (xy 177.879756 -69.237352)
			(xy 177.870884 -69.231677) (xy 177.850292 -69.22737) (xy 177.8297 -69.231677) (xy 177.820828 -69.237352)
			(xy 177.77365 -69.270238) (xy 177.675517 -69.330218) (xy 177.573504 -69.383334) (xy 177.468091 -69.429334)
			(xy 177.359774 -69.468002) (xy 177.249062 -69.499157) (xy 177.136475 -69.522653) (xy 177.022542 -69.538378)
			(xy 176.9078 -69.546259) (xy 176.792788 -69.546259) (xy 176.678046 -69.538378) (xy 176.564113 -69.522653)
			(xy 176.451526 -69.499157) (xy 176.340814 -69.468002) (xy 176.232497 -69.429334) (xy 176.127084 -69.383334)
			(xy 176.025071 -69.330218) (xy 175.926938 -69.270238) (xy 175.87976 -69.237352) (xy 175.870888 -69.231677)
			(xy 175.850296 -69.22737) (xy 175.829704 -69.231677) (xy 175.820832 -69.237352) (xy 175.773654 -69.270238)
			(xy 175.675521 -69.330218) (xy 175.573508 -69.383334) (xy 175.468095 -69.429334) (xy 175.359778 -69.468002)
			(xy 175.249066 -69.499157) (xy 175.136479 -69.522653) (xy 175.022546 -69.538378) (xy 174.907804 -69.546259)
			(xy 174.792792 -69.546259) (xy 174.67805 -69.538378) (xy 174.564117 -69.522653) (xy 174.45153 -69.499157)
			(xy 174.340818 -69.468002) (xy 174.232501 -69.429334) (xy 174.127088 -69.383334) (xy 174.025075 -69.330218)
			(xy 173.926942 -69.270238) (xy 173.879764 -69.237352) (xy 173.870892 -69.231677) (xy 173.8503 -69.22737)
			(xy 173.829708 -69.231677) (xy 173.820836 -69.237352) (xy 173.773658 -69.270238) (xy 173.675525 -69.330218)
			(xy 173.573512 -69.383334) (xy 173.468099 -69.429334) (xy 173.359782 -69.468002) (xy 173.24907 -69.499157)
			(xy 173.136483 -69.522653) (xy 173.02255 -69.538378) (xy 172.907808 -69.546259) (xy 172.792796 -69.546259)
			(xy 172.678054 -69.538378) (xy 172.564121 -69.522653) (xy 172.451534 -69.499157) (xy 172.340822 -69.468002)
			(xy 172.232505 -69.429334) (xy 172.127092 -69.383334) (xy 172.025079 -69.330218) (xy 171.926946 -69.270238)
			(xy 171.879768 -69.237352) (xy 171.870896 -69.231677) (xy 171.850304 -69.22737) (xy 171.829712 -69.231677)
			(xy 171.82084 -69.237352) (xy 171.775674 -69.268854) (xy 171.681872 -69.326559) (xy 171.633388 -69.352668)
			(xy 171.625248 -69.357441) (xy 171.612918 -69.371709) (xy 171.606566 -69.389464) (xy 171.607048 -69.408314)
			(xy 171.610274 -69.417184) (xy 171.637809 -69.484523) (xy 171.686148 -69.621757) (xy 171.72667 -69.761499)
			(xy 171.759246 -69.903304) (xy 171.783772 -70.046721) (xy 171.800169 -70.191292) (xy 171.808387 -70.336559)
			(xy 171.808902 -70.409308) (xy 171.808902 -70.409816) (xy 171.808416 -70.482151) (xy 171.800304 -70.626593)
			(xy 171.784105 -70.770353) (xy 171.759871 -70.912978) (xy 171.727679 -71.05402) (xy 171.687628 -71.193036)
			(xy 171.639846 -71.329587) (xy 171.584483 -71.463244) (xy 171.521712 -71.593586) (xy 171.451732 -71.720204)
			(xy 171.374763 -71.842699) (xy 171.291046 -71.960685) (xy 171.200845 -72.073792) (xy 171.104445 -72.181664)
			(xy 171.002148 -72.28396) (xy 170.894275 -72.38036) (xy 170.781168 -72.470559) (xy 170.663181 -72.554275)
			(xy 170.540685 -72.631243) (xy 170.414067 -72.701222) (xy 170.283724 -72.763992) (xy 170.150066 -72.819354)
			(xy 170.013515 -72.867135) (xy 169.874499 -72.907184) (xy 169.733456 -72.939376) (xy 169.590831 -72.963608)
			(xy 169.447071 -72.979806) (xy 169.302629 -72.987917) (xy 169.230294 -72.988424) (xy 169.157478 -72.987891)
			(xy 169.012078 -72.979676) (xy 168.867374 -72.963267) (xy 168.723827 -72.938716) (xy 168.581894 -72.906102)
			(xy 168.442028 -72.865529) (xy 168.304676 -72.817125) (xy 168.170275 -72.761045) (xy 168.039253 -72.697469)
			(xy 167.912029 -72.626598) (xy 167.789008 -72.54866) (xy 167.670583 -72.463901) (xy 167.55713 -72.372593)
			(xy 167.449013 -72.275027) (xy 167.39743 -72.22363) (xy 167.390318 -72.216264) (xy 167.371776 -72.208644)
			(xy 167.278812 -72.208644) (xy 167.26027 -72.216264) (xy 167.253158 -72.22363) (xy 167.201588 -72.27504)
			(xy 167.093468 -72.372604) (xy 166.980013 -72.46391) (xy 166.861585 -72.548667) (xy 166.738563 -72.626604)
			(xy 166.611338 -72.697474) (xy 166.480315 -72.76105) (xy 166.345914 -72.81713) (xy 166.208561 -72.865535)
			(xy 166.068695 -72.90611) (xy 165.926762 -72.938727) (xy 165.783215 -72.963281) (xy 165.63851 -72.979693)
			(xy 165.49311 -72.987913) (xy 165.420294 -72.988424) (xy 165.34796 -72.987885) (xy 165.20352 -72.979773)
			(xy 165.059761 -72.963575) (xy 164.917137 -72.939342) (xy 164.776097 -72.90715) (xy 164.637083 -72.8671)
			(xy 164.500533 -72.819319) (xy 164.366878 -72.763957) (xy 164.236536 -72.701188) (xy 164.10992 -72.631209)
			(xy 163.987426 -72.554241) (xy 163.869441 -72.470525) (xy 163.756335 -72.380326) (xy 163.648464 -72.283927)
			(xy 163.546169 -72.181631) (xy 163.44977 -72.073761) (xy 163.359571 -71.960655) (xy 163.275856 -71.842669)
			(xy 163.198888 -71.720175) (xy 163.128909 -71.593558) (xy 163.06614 -71.463217) (xy 163.010779 -71.329561)
			(xy 162.962998 -71.193011) (xy 162.922949 -71.053997) (xy 162.890757 -70.912957) (xy 162.866524 -70.770333)
			(xy 162.850327 -70.626574) (xy 162.842215 -70.482134) (xy 149.968257 -70.482134) (xy 149.961175 -70.584546)
			(xy 149.945115 -70.700108) (xy 149.92112 -70.814286) (xy 149.889305 -70.926537) (xy 149.849822 -71.036325)
			(xy 149.802858 -71.143128) (xy 149.748638 -71.246436) (xy 149.687419 -71.345757) (xy 149.619494 -71.440618)
			(xy 149.545187 -71.530567) (xy 149.46485 -71.615175) (xy 149.378868 -71.694039) (xy 149.28765 -71.766783)
			(xy 149.191631 -71.83306) (xy 149.091268 -71.892555) (xy 148.987039 -71.944984) (xy 148.879442 -71.990098)
			(xy 148.768988 -72.02768) (xy 148.656205 -72.057553) (xy 148.54163 -72.079573) (xy 148.425808 -72.093637)
			(xy 148.309292 -72.099676) (xy 148.192638 -72.097662) (xy 148.0764 -72.087605) (xy 147.961132 -72.069552)
			(xy 147.847385 -72.04359) (xy 147.735701 -72.009842) (xy 147.62661 -71.96847) (xy 147.520634 -71.91967)
			(xy 147.418277 -71.863674) (xy 147.320027 -71.80075) (xy 147.226353 -71.731198) (xy 147.1377 -71.655349)
			(xy 147.054491 -71.573565) (xy 146.977123 -71.486234) (xy 146.905965 -71.393774) (xy 146.841354 -71.296625)
			(xy 146.783601 -71.19525) (xy 146.732978 -71.090132) (xy 146.689729 -70.981772) (xy 146.654059 -70.870686)
			(xy 146.626137 -70.757404) (xy 146.606098 -70.642466) (xy 146.594036 -70.526419) (xy 146.590009 -70.409816)
			(xy 146.159639 -70.409816) (xy 146.157385 -70.507357) (xy 146.14658 -70.623957) (xy 146.127727 -70.739529)
			(xy 146.100916 -70.853519) (xy 146.066277 -70.965378) (xy 146.023975 -71.07457) (xy 145.974214 -71.180571)
			(xy 145.917233 -71.282872) (xy 145.853304 -71.380982) (xy 145.782736 -71.474429) (xy 145.705866 -71.562766)
			(xy 145.623063 -71.645568) (xy 145.534726 -71.722438) (xy 145.441279 -71.793007) (xy 145.343169 -71.856935)
			(xy 145.240868 -71.913916) (xy 145.134866 -71.963677) (xy 145.025674 -72.005978) (xy 144.913815 -72.040617)
			(xy 144.799825 -72.067428) (xy 144.684253 -72.08628) (xy 144.567653 -72.097085) (xy 144.450584 -72.09979)
			(xy 144.333609 -72.094383) (xy 144.217289 -72.080888) (xy 144.102183 -72.059371) (xy 143.988843 -72.029936)
			(xy 143.877813 -71.992723) (xy 143.769627 -71.947911) (xy 143.664803 -71.895716) (xy 143.563845 -71.836387)
			(xy 143.467238 -71.77021) (xy 143.375445 -71.697503) (xy 143.288906 -71.618613) (xy 143.208038 -71.533921)
			(xy 143.133229 -71.443833) (xy 143.064837 -71.34878) (xy 143.003191 -71.249221) (xy 142.948587 -71.145631)
			(xy 142.901287 -71.038509) (xy 142.861519 -70.928369) (xy 142.829472 -70.81574) (xy 142.805301 -70.701162)
			(xy 142.789122 -70.585185) (xy 142.781012 -70.468366) (xy 142.780512 -70.409816) (xy 142.781052 -70.347982)
			(xy 142.790098 -70.224645) (xy 142.808137 -70.102299) (xy 142.835071 -69.981599) (xy 142.870756 -69.863191)
			(xy 142.915002 -69.747709) (xy 142.940786 -69.691504) (xy 142.946374 -69.679566) (xy 142.94485 -69.653912)
			(xy 142.884652 -69.55917) (xy 142.862046 -69.546724) (xy 142.848838 -69.546724) (xy 142.791403 -69.546193)
			(xy 142.676807 -69.53825) (xy 142.563023 -69.522483) (xy 142.450586 -69.498964) (xy 142.340022 -69.467804)
			(xy 142.23185 -69.429149) (xy 142.126578 -69.383181) (xy 142.0247 -69.330115) (xy 141.926692 -69.270199)
			(xy 141.879574 -69.237352) (xy 141.870702 -69.231677) (xy 141.85011 -69.22737) (xy 141.829518 -69.231677)
			(xy 141.820646 -69.237352) (xy 141.773468 -69.270238) (xy 141.675335 -69.330218) (xy 141.573322 -69.383334)
			(xy 141.467909 -69.429334) (xy 141.359592 -69.468002) (xy 141.24888 -69.499157) (xy 141.136293 -69.522653)
			(xy 141.02236 -69.538378) (xy 140.907618 -69.546259) (xy 140.792606 -69.546259) (xy 140.677864 -69.538378)
			(xy 140.563931 -69.522653) (xy 140.451344 -69.499157) (xy 140.340632 -69.468002) (xy 140.232315 -69.429334)
			(xy 140.126902 -69.383334) (xy 140.024889 -69.330218) (xy 139.926756 -69.270238) (xy 139.879578 -69.237352)
			(xy 139.870706 -69.231677) (xy 139.850114 -69.22737) (xy 139.829522 -69.231677) (xy 139.82065 -69.237352)
			(xy 139.773472 -69.270238) (xy 139.675339 -69.330218) (xy 139.573326 -69.383334) (xy 139.467913 -69.429334)
			(xy 139.359596 -69.468002) (xy 139.248884 -69.499157) (xy 139.136297 -69.522653) (xy 139.022364 -69.538378)
			(xy 138.907622 -69.546259) (xy 138.79261 -69.546259) (xy 138.677868 -69.538378) (xy 138.563935 -69.522653)
			(xy 138.451348 -69.499157) (xy 138.340636 -69.468002) (xy 138.232319 -69.429334) (xy 138.126906 -69.383334)
			(xy 138.024893 -69.330218) (xy 137.92676 -69.270238) (xy 137.879582 -69.237352) (xy 137.87071 -69.231677)
			(xy 137.850118 -69.22737) (xy 137.829526 -69.231677) (xy 137.820654 -69.237352) (xy 137.773476 -69.270238)
			(xy 137.675343 -69.330218) (xy 137.57333 -69.383334) (xy 137.467917 -69.429334) (xy 137.3596 -69.468002)
			(xy 137.248888 -69.499157) (xy 137.136301 -69.522653) (xy 137.022368 -69.538378) (xy 136.907626 -69.546259)
			(xy 136.792614 -69.546259) (xy 136.677872 -69.538378) (xy 136.563939 -69.522653) (xy 136.451352 -69.499157)
			(xy 136.34064 -69.468002) (xy 136.232323 -69.429334) (xy 136.12691 -69.383334) (xy 136.024897 -69.330218)
			(xy 135.926764 -69.270238) (xy 135.879586 -69.237352) (xy 135.870714 -69.231677) (xy 135.850122 -69.22737)
			(xy 135.82953 -69.231677) (xy 135.820658 -69.237352) (xy 135.77348 -69.270238) (xy 135.675347 -69.330218)
			(xy 135.573334 -69.383334) (xy 135.467921 -69.429334) (xy 135.359604 -69.468002) (xy 135.248892 -69.499157)
			(xy 135.136305 -69.522653) (xy 135.022372 -69.538378) (xy 134.90763 -69.546259) (xy 134.792618 -69.546259)
			(xy 134.677876 -69.538378) (xy 134.563943 -69.522653) (xy 134.451356 -69.499157) (xy 134.340644 -69.468002)
			(xy 134.232327 -69.429334) (xy 134.126914 -69.383334) (xy 134.024901 -69.330218) (xy 133.926768 -69.270238)
			(xy 133.87959 -69.237352) (xy 133.870718 -69.231677) (xy 133.850126 -69.22737) (xy 133.829534 -69.231677)
			(xy 133.820662 -69.237352) (xy 133.773484 -69.270238) (xy 133.675351 -69.330218) (xy 133.573338 -69.383334)
			(xy 133.467925 -69.429334) (xy 133.359608 -69.468002) (xy 133.248896 -69.499157) (xy 133.136309 -69.522653)
			(xy 133.022376 -69.538378) (xy 132.907634 -69.546259) (xy 132.792622 -69.546259) (xy 132.67788 -69.538378)
			(xy 132.563947 -69.522653) (xy 132.45136 -69.499157) (xy 132.340648 -69.468002) (xy 132.232331 -69.429334)
			(xy 132.126918 -69.383334) (xy 132.024905 -69.330218) (xy 131.926772 -69.270238) (xy 131.879594 -69.237352)
			(xy 131.870722 -69.231677) (xy 131.85013 -69.22737) (xy 131.829538 -69.231677) (xy 131.820666 -69.237352)
			(xy 131.775498 -69.268852) (xy 131.681698 -69.326559) (xy 131.633214 -69.352668) (xy 131.625077 -69.357448)
			(xy 131.612744 -69.371712) (xy 131.60639 -69.389465) (xy 131.606872 -69.408315) (xy 131.6101 -69.417184)
			(xy 131.637636 -69.484522) (xy 131.685975 -69.621757) (xy 131.726497 -69.761499) (xy 131.759072 -69.903304)
			(xy 131.783598 -70.046721) (xy 131.799995 -70.191292) (xy 131.808213 -70.336559) (xy 131.808728 -70.409308)
			(xy 131.808728 -70.409816) (xy 131.808203 -70.481813) (xy 131.800166 -70.625584) (xy 131.784116 -70.768682)
			(xy 131.760105 -70.910661) (xy 131.728206 -71.051078) (xy 131.68852 -71.189496) (xy 131.64117 -71.325483)
			(xy 131.586305 -71.458616) (xy 131.524094 -71.588479) (xy 131.454731 -71.714667) (xy 131.378434 -71.836787)
			(xy 131.29544 -71.954458) (xy 131.206008 -72.067314) (xy 131.110416 -72.175002) (xy 131.008962 -72.277187)
			(xy 130.955796 -72.325738) (xy 130.95478 -72.326754) (xy 130.90044 -72.375002) (xy 130.787095 -72.46597)
			(xy 130.668806 -72.550408) (xy 130.545949 -72.628048) (xy 130.418913 -72.698645) (xy 130.288101 -72.761973)
			(xy 130.153931 -72.817832) (xy 130.016826 -72.866044) (xy 129.877223 -72.906456) (xy 129.735566 -72.93894)
			(xy 129.592303 -72.963393) (xy 129.447891 -72.979736) (xy 129.302787 -72.987919) (xy 129.23012 -72.988424)
			(xy 129.159966 -72.987943) (xy 129.019867 -72.980318) (xy 128.880389 -72.965084) (xy 128.741947 -72.942286)
			(xy 128.604949 -72.911991) (xy 128.469803 -72.87429) (xy 128.336906 -72.829294) (xy 128.206654 -72.777136)
			(xy 128.079432 -72.71797) (xy 127.955616 -72.651972) (xy 127.89535 -72.61606) (xy 127.89408 -72.615298)
			(xy 127.826574 -72.573708) (xy 127.696243 -72.483379) (xy 127.571713 -72.385207) (xy 127.453456 -72.279561)
			(xy 127.397256 -72.22363) (xy 127.390144 -72.216264) (xy 127.371602 -72.208644) (xy 127.278638 -72.208644)
			(xy 127.260096 -72.216264) (xy 127.252984 -72.22363) (xy 127.201402 -72.275027) (xy 127.093282 -72.372592)
			(xy 126.979828 -72.463898) (xy 126.861402 -72.548655) (xy 126.738381 -72.626594) (xy 126.611157 -72.697464)
			(xy 126.480135 -72.761041) (xy 126.345735 -72.817122) (xy 126.208383 -72.865528) (xy 126.068518 -72.906105)
			(xy 125.926586 -72.938722) (xy 125.783039 -72.963277) (xy 125.638335 -72.979691) (xy 125.492936 -72.987912)
			(xy 125.42012 -72.988424) (xy 125.347785 -72.987894) (xy 125.203343 -72.979784) (xy 125.059584 -72.963587)
			(xy 124.916958 -72.939355) (xy 124.775916 -72.907164) (xy 124.6369 -72.867115) (xy 124.500349 -72.819335)
			(xy 124.366691 -72.763973) (xy 124.236348 -72.701204) (xy 124.10973 -72.631225) (xy 123.987234 -72.554257)
			(xy 123.869247 -72.470542) (xy 123.75614 -72.380342) (xy 123.648268 -72.283943) (xy 123.545971 -72.181647)
			(xy 123.44957 -72.073775) (xy 123.35937 -71.960669) (xy 123.275654 -71.842682) (xy 123.198685 -71.720187)
			(xy 123.128705 -71.593569) (xy 123.065935 -71.463227) (xy 123.010572 -71.32957) (xy 122.962791 -71.193019)
			(xy 122.922741 -71.054004) (xy 122.890549 -70.912962) (xy 122.866316 -70.770336) (xy 122.850118 -70.626576)
			(xy 122.842006 -70.482135) (xy 109.968083 -70.482135) (xy 109.961001 -70.584546) (xy 109.944941 -70.700108)
			(xy 109.920946 -70.814286) (xy 109.889131 -70.926537) (xy 109.849648 -71.036325) (xy 109.802684 -71.143128)
			(xy 109.748464 -71.246436) (xy 109.687245 -71.345757) (xy 109.61932 -71.440618) (xy 109.545013 -71.530567)
			(xy 109.464676 -71.615175) (xy 109.378694 -71.694039) (xy 109.287476 -71.766783) (xy 109.191457 -71.83306)
			(xy 109.091094 -71.892555) (xy 108.986865 -71.944984) (xy 108.879268 -71.990098) (xy 108.768814 -72.02768)
			(xy 108.656031 -72.057553) (xy 108.541456 -72.079573) (xy 108.425634 -72.093637) (xy 108.309118 -72.099676)
			(xy 108.192464 -72.097662) (xy 108.076226 -72.087605) (xy 107.960958 -72.069552) (xy 107.847211 -72.04359)
			(xy 107.735527 -72.009842) (xy 107.626436 -71.96847) (xy 107.52046 -71.91967) (xy 107.418103 -71.863674)
			(xy 107.319853 -71.80075) (xy 107.226179 -71.731198) (xy 107.137526 -71.655349) (xy 107.054317 -71.573565)
			(xy 106.976949 -71.486234) (xy 106.905791 -71.393774) (xy 106.84118 -71.296625) (xy 106.783427 -71.19525)
			(xy 106.732804 -71.090132) (xy 106.689555 -70.981772) (xy 106.653885 -70.870686) (xy 106.625963 -70.757404)
			(xy 106.605924 -70.642466) (xy 106.593862 -70.526419) (xy 106.589835 -70.409816) (xy 106.159414 -70.409816)
			(xy 106.157158 -70.507372) (xy 106.146352 -70.62397) (xy 106.127498 -70.73954) (xy 106.100687 -70.853527)
			(xy 106.066047 -70.965384) (xy 106.023746 -71.074574) (xy 105.973984 -71.180572) (xy 105.917003 -71.282871)
			(xy 105.853075 -71.380978) (xy 105.782507 -71.474424) (xy 105.705638 -71.562758) (xy 105.622836 -71.645558)
			(xy 105.5345 -71.722426) (xy 105.441054 -71.792992) (xy 105.342945 -71.856919) (xy 105.240646 -71.913898)
			(xy 105.134646 -71.963657) (xy 105.025456 -72.005957) (xy 104.913598 -72.040595) (xy 104.799611 -72.067404)
			(xy 104.68404 -72.086256) (xy 104.567442 -72.09706) (xy 104.450376 -72.099764) (xy 104.333403 -72.094356)
			(xy 104.217085 -72.080861) (xy 104.101981 -72.059344) (xy 103.988644 -72.029909) (xy 103.877616 -71.992696)
			(xy 103.769432 -71.947885) (xy 103.66461 -71.89569) (xy 103.563655 -71.836362) (xy 103.467049 -71.770186)
			(xy 103.375258 -71.69748) (xy 103.288721 -71.618592) (xy 103.207855 -71.533901) (xy 103.133047 -71.443814)
			(xy 103.064657 -71.348763) (xy 103.003012 -71.249205) (xy 102.94841 -71.145617) (xy 102.901111 -71.038497)
			(xy 102.861343 -70.928359) (xy 102.829297 -70.815732) (xy 102.805126 -70.701156) (xy 102.788947 -70.585181)
			(xy 102.780838 -70.468365) (xy 102.780338 -70.409816) (xy 102.780875 -70.347982) (xy 102.789922 -70.224645)
			(xy 102.807961 -70.102299) (xy 102.834895 -69.981599) (xy 102.870581 -69.863191) (xy 102.914828 -69.747709)
			(xy 102.940612 -69.691504) (xy 102.9462 -69.679566) (xy 102.944676 -69.653912) (xy 102.884478 -69.55917)
			(xy 102.861872 -69.546724) (xy 102.848664 -69.546724) (xy 102.791229 -69.546178) (xy 102.676634 -69.538238)
			(xy 102.56285 -69.522472) (xy 102.450413 -69.498955) (xy 102.339849 -69.467797) (xy 102.231677 -69.429144)
			(xy 102.126405 -69.383177) (xy 102.024526 -69.330112) (xy 101.926518 -69.270198) (xy 101.8794 -69.237352)
			(xy 101.870528 -69.231677) (xy 101.849936 -69.22737) (xy 101.829344 -69.231677) (xy 101.820472 -69.237352)
			(xy 101.773294 -69.270238) (xy 101.675161 -69.330218) (xy 101.573148 -69.383334) (xy 101.467735 -69.429334)
			(xy 101.359418 -69.468002) (xy 101.248706 -69.499157) (xy 101.136119 -69.522653) (xy 101.022186 -69.538378)
			(xy 100.907444 -69.546259) (xy 100.792432 -69.546259) (xy 100.67769 -69.538378) (xy 100.563757 -69.522653)
			(xy 100.45117 -69.499157) (xy 100.340458 -69.468002) (xy 100.232141 -69.429334) (xy 100.126728 -69.383334)
			(xy 100.024715 -69.330218) (xy 99.926582 -69.270238) (xy 99.879404 -69.237352) (xy 99.870532 -69.231677)
			(xy 99.84994 -69.22737) (xy 99.829348 -69.231677) (xy 99.820476 -69.237352) (xy 99.773298 -69.270238)
			(xy 99.675165 -69.330218) (xy 99.573152 -69.383334) (xy 99.467739 -69.429334) (xy 99.359422 -69.468002)
			(xy 99.24871 -69.499157) (xy 99.136123 -69.522653) (xy 99.02219 -69.538378) (xy 98.907448 -69.546259)
			(xy 98.792436 -69.546259) (xy 98.677694 -69.538378) (xy 98.563761 -69.522653) (xy 98.451174 -69.499157)
			(xy 98.340462 -69.468002) (xy 98.232145 -69.429334) (xy 98.126732 -69.383334) (xy 98.024719 -69.330218)
			(xy 97.926586 -69.270238) (xy 97.879408 -69.237352) (xy 97.870536 -69.231677) (xy 97.849944 -69.22737)
			(xy 97.829352 -69.231677) (xy 97.82048 -69.237352) (xy 97.773302 -69.270238) (xy 97.675169 -69.330218)
			(xy 97.573156 -69.383334) (xy 97.467743 -69.429334) (xy 97.359426 -69.468002) (xy 97.248714 -69.499157)
			(xy 97.136127 -69.522653) (xy 97.022194 -69.538378) (xy 96.907452 -69.546259) (xy 96.79244 -69.546259)
			(xy 96.677698 -69.538378) (xy 96.563765 -69.522653) (xy 96.451178 -69.499157) (xy 96.340466 -69.468002)
			(xy 96.232149 -69.429334) (xy 96.126736 -69.383334) (xy 96.024723 -69.330218) (xy 95.92659 -69.270238)
			(xy 95.879412 -69.237352) (xy 95.87054 -69.231677) (xy 95.849948 -69.22737) (xy 95.829356 -69.231677)
			(xy 95.820484 -69.237352) (xy 95.773306 -69.270238) (xy 95.675173 -69.330218) (xy 95.57316 -69.383334)
			(xy 95.467747 -69.429334) (xy 95.35943 -69.468002) (xy 95.248718 -69.499157) (xy 95.136131 -69.522653)
			(xy 95.022198 -69.538378) (xy 94.907456 -69.546259) (xy 94.792444 -69.546259) (xy 94.677702 -69.538378)
			(xy 94.563769 -69.522653) (xy 94.451182 -69.499157) (xy 94.34047 -69.468002) (xy 94.232153 -69.429334)
			(xy 94.12674 -69.383334) (xy 94.024727 -69.330218) (xy 93.926594 -69.270238) (xy 93.879416 -69.237352)
			(xy 93.870544 -69.231677) (xy 93.849952 -69.22737) (xy 93.82936 -69.231677) (xy 93.820488 -69.237352)
			(xy 93.77331 -69.270238) (xy 93.675177 -69.330218) (xy 93.573164 -69.383334) (xy 93.467751 -69.429334)
			(xy 93.359434 -69.468002) (xy 93.248722 -69.499157) (xy 93.136135 -69.522653) (xy 93.022202 -69.538378)
			(xy 92.90746 -69.546259) (xy 92.792448 -69.546259) (xy 92.677706 -69.538378) (xy 92.563773 -69.522653)
			(xy 92.451186 -69.499157) (xy 92.340474 -69.468002) (xy 92.232157 -69.429334) (xy 92.126744 -69.383334)
			(xy 92.024731 -69.330218) (xy 91.926598 -69.270238) (xy 91.87942 -69.237352) (xy 91.870548 -69.231677)
			(xy 91.849956 -69.22737) (xy 91.829364 -69.231677) (xy 91.820492 -69.237352) (xy 91.775328 -69.268857)
			(xy 91.681525 -69.326561) (xy 91.63304 -69.352668) (xy 91.624907 -69.357455) (xy 91.61257 -69.371714)
			(xy 91.606215 -69.389466) (xy 91.606697 -69.408316) (xy 91.609926 -69.417184) (xy 91.637464 -69.484522)
			(xy 91.685802 -69.621756) (xy 91.726324 -69.761498) (xy 91.758899 -69.903304) (xy 91.783424 -70.04672)
			(xy 91.799822 -70.191292) (xy 91.808039 -70.336559) (xy 91.808554 -70.409308) (xy 91.808554 -70.409816)
			(xy 91.808017 -70.48215) (xy 91.799904 -70.62659) (xy 91.783706 -70.770348) (xy 91.759473 -70.912972)
			(xy 91.727281 -71.054012) (xy 91.687231 -71.193026) (xy 91.63945 -71.329575) (xy 91.584088 -71.463231)
			(xy 91.521319 -71.593572) (xy 91.451341 -71.720189) (xy 91.374373 -71.842683) (xy 91.290659 -71.960668)
			(xy 91.20046 -72.073774) (xy 91.104062 -72.181645) (xy 91.001767 -72.283941) (xy 90.893897 -72.380341)
			(xy 90.780792 -72.470541) (xy 90.662808 -72.554257) (xy 90.540315 -72.631226) (xy 90.413699 -72.701206)
			(xy 90.283358 -72.763976) (xy 90.149703 -72.81934) (xy 90.013154 -72.867122) (xy 89.874141 -72.907173)
			(xy 89.733101 -72.939367) (xy 89.590478 -72.963602) (xy 89.44672 -72.979802) (xy 89.30228 -72.987916)
			(xy 89.229946 -72.988424) (xy 89.15713 -72.987924) (xy 89.011729 -72.979706) (xy 88.867024 -72.963294)
			(xy 88.723476 -72.938741) (xy 88.581543 -72.906124) (xy 88.441677 -72.865548) (xy 88.304325 -72.817142)
			(xy 88.169924 -72.76106) (xy 88.038902 -72.697481) (xy 87.911679 -72.626608) (xy 87.788658 -72.548667)
			(xy 87.670233 -72.463906) (xy 87.556781 -72.372596) (xy 87.448664 -72.275028) (xy 87.397082 -72.22363)
			(xy 87.38997 -72.216264) (xy 87.371428 -72.208644) (xy 87.278464 -72.208644) (xy 87.259922 -72.216264)
			(xy 87.25281 -72.22363) (xy 87.201215 -72.275014) (xy 87.093097 -72.372579) (xy 86.979644 -72.463886)
			(xy 86.861219 -72.548644) (xy 86.738199 -72.626583) (xy 86.610976 -72.697454) (xy 86.479955 -72.761032)
			(xy 86.345556 -72.817114) (xy 86.208205 -72.865521) (xy 86.068341 -72.906099) (xy 85.92641 -72.938717)
			(xy 85.782864 -72.963274) (xy 85.638161 -72.979689) (xy 85.492762 -72.987911) (xy 85.419946 -72.988424)
			(xy 85.347611 -72.987925) (xy 85.20317 -72.979813) (xy 85.05941 -72.963615) (xy 84.916785 -72.939382)
			(xy 84.775743 -72.90719) (xy 84.636728 -72.86714) (xy 84.500178 -72.819359) (xy 84.366521 -72.763996)
			(xy 84.236178 -72.701226) (xy 84.109561 -72.631247) (xy 83.987066 -72.554278) (xy 83.869079 -72.470562)
			(xy 83.755973 -72.380362) (xy 83.648101 -72.283962) (xy 83.545805 -72.181666) (xy 83.449405 -72.073794)
			(xy 83.359205 -71.960687) (xy 83.27549 -71.842701) (xy 83.198521 -71.720206) (xy 83.128542 -71.593588)
			(xy 83.065772 -71.463246) (xy 83.01041 -71.329589) (xy 82.962629 -71.193038) (xy 82.922579 -71.054023)
			(xy 82.890387 -70.912981) (xy 82.866155 -70.770356) (xy 82.849957 -70.626596) (xy 82.841845 -70.482155)
			(xy 69.968162 -70.482155) (xy 69.961081 -70.584546) (xy 69.945021 -70.700108) (xy 69.921026 -70.814286)
			(xy 69.889211 -70.926537) (xy 69.849728 -71.036325) (xy 69.802764 -71.143128) (xy 69.748544 -71.246436)
			(xy 69.687325 -71.345757) (xy 69.6194 -71.440618) (xy 69.545093 -71.530567) (xy 69.464756 -71.615175)
			(xy 69.378774 -71.694039) (xy 69.287556 -71.766783) (xy 69.191537 -71.83306) (xy 69.091174 -71.892555)
			(xy 68.986945 -71.944984) (xy 68.879348 -71.990098) (xy 68.768894 -72.02768) (xy 68.656111 -72.057553)
			(xy 68.541536 -72.079573) (xy 68.425714 -72.093637) (xy 68.309198 -72.099676) (xy 68.192544 -72.097662)
			(xy 68.076306 -72.087605) (xy 67.961038 -72.069552) (xy 67.847291 -72.04359) (xy 67.735607 -72.009842)
			(xy 67.626516 -71.96847) (xy 67.52054 -71.91967) (xy 67.418183 -71.863674) (xy 67.319933 -71.80075)
			(xy 67.226259 -71.731198) (xy 67.137606 -71.655349) (xy 67.054397 -71.573565) (xy 66.977029 -71.486234)
			(xy 66.905871 -71.393774) (xy 66.84126 -71.296625) (xy 66.783507 -71.19525) (xy 66.732884 -71.090132)
			(xy 66.689635 -70.981772) (xy 66.653965 -70.870686) (xy 66.626043 -70.757404) (xy 66.606004 -70.642466)
			(xy 66.593942 -70.526419) (xy 66.589915 -70.409816) (xy 66.159543 -70.409816) (xy 66.157289 -70.507361)
			(xy 66.146483 -70.623961) (xy 66.12763 -70.739534) (xy 66.100819 -70.853523) (xy 66.06618 -70.965383)
			(xy 66.023878 -71.074575) (xy 65.974116 -71.180576) (xy 65.917134 -71.282877) (xy 65.853206 -71.380987)
			(xy 65.782637 -71.474434) (xy 65.705767 -71.562771) (xy 65.622964 -71.645573) (xy 65.534627 -71.722443)
			(xy 65.441179 -71.793011) (xy 65.343068 -71.85694) (xy 65.240767 -71.913921) (xy 65.134766 -71.963682)
			(xy 65.025573 -72.005983) (xy 64.913713 -72.040622) (xy 64.799724 -72.067432) (xy 64.684151 -72.086285)
			(xy 64.567551 -72.097089) (xy 64.450482 -72.099794) (xy 64.333507 -72.094386) (xy 64.217187 -72.080892)
			(xy 64.102081 -72.059375) (xy 63.98874 -72.029939) (xy 63.877711 -71.992726) (xy 63.769524 -71.947914)
			(xy 63.6647 -71.895719) (xy 63.563742 -71.83639) (xy 63.467135 -71.770213) (xy 63.375341 -71.697505)
			(xy 63.288803 -71.618616) (xy 63.207935 -71.533923) (xy 63.133125 -71.443835) (xy 63.064733 -71.348782)
			(xy 63.003087 -71.249222) (xy 62.948483 -71.145632) (xy 62.901183 -71.03851) (xy 62.861415 -70.92837)
			(xy 62.829368 -70.81574) (xy 62.805197 -70.701162) (xy 62.789018 -70.585185) (xy 62.780908 -70.468366)
			(xy 62.780418 -70.409816) (xy 62.780418 -70.409308) (xy 62.780972 -70.347474) (xy 62.790013 -70.224137)
			(xy 62.808047 -70.101791) (xy 62.834978 -69.98109) (xy 62.870661 -69.862682) (xy 62.914906 -69.7472)
			(xy 62.940692 -69.690996) (xy 62.942978 -69.685916) (xy 62.944502 -69.680074) (xy 62.946246 -69.670091)
			(xy 62.942563 -69.650182) (xy 62.93739 -69.641466) (xy 62.89421 -69.57441) (xy 62.892432 -69.571362)
			(xy 62.886336 -69.560694) (xy 62.862714 -69.546724) (xy 62.847728 -69.546724) (xy 62.807337 -69.546396)
			(xy 62.726657 -69.542329) (xy 62.686438 -69.538596) (xy 62.674754 -69.53758) (xy 62.653672 -69.5452)
			(xy 62.490858 -69.708014) (xy 62.484007 -69.71541) (xy 62.476269 -69.734009) (xy 62.475872 -69.744082)
			(xy 62.475872 -75.057) (xy 130.44704 -75.057) (xy 130.451057 -74.956018) (xy 130.463086 -74.855674)
			(xy 130.483048 -74.756604) (xy 130.510819 -74.659432) (xy 130.546222 -74.564774) (xy 130.589033 -74.473228)
			(xy 130.638983 -74.385373) (xy 130.695755 -74.301764) (xy 130.75899 -74.22293) (xy 130.828289 -74.149369)
			(xy 130.903213 -74.081547) (xy 130.983289 -74.019892) (xy 131.06801 -73.964793) (xy 131.156841 -73.9166)
			(xy 131.24922 -73.875617) (xy 131.344563 -73.842103) (xy 131.442268 -73.81627) (xy 131.541716 -73.798281)
			(xy 131.642279 -73.78825) (xy 131.74332 -73.786241) (xy 131.844203 -73.792266) (xy 131.944287 -73.806286)
			(xy 132.042941 -73.828215) (xy 132.139542 -73.857912) (xy 132.233477 -73.89519) (xy 132.324154 -73.939813)
			(xy 132.410998 -73.9915) (xy 132.493462 -74.049923) (xy 132.571023 -74.114713) (xy 132.643192 -74.185461)
			(xy 132.709511 -74.261718) (xy 132.769562 -74.343004) (xy 132.822965 -74.428804) (xy 132.869383 -74.518576)
			(xy 132.908521 -74.611751) (xy 132.940133 -74.707742) (xy 132.964018 -74.805941) (xy 132.980026 -74.905727)
			(xy 132.988056 -75.006469) (xy 132.988558 -75.057) (xy 132.988056 -75.107531) (xy 132.980026 -75.208273)
			(xy 132.964018 -75.308059) (xy 132.940133 -75.406258) (xy 132.908521 -75.502249) (xy 132.869383 -75.595424)
			(xy 132.822965 -75.685196) (xy 132.769562 -75.770996) (xy 132.709511 -75.852282) (xy 132.643192 -75.928539)
			(xy 132.571023 -75.999287) (xy 132.493462 -76.064077) (xy 132.410998 -76.1225) (xy 132.324154 -76.174187)
			(xy 132.233477 -76.21881) (xy 132.139542 -76.256088) (xy 132.042941 -76.285785) (xy 131.944287 -76.307714)
			(xy 131.844203 -76.321734) (xy 131.74332 -76.327759) (xy 131.642279 -76.32575) (xy 131.541716 -76.315719)
			(xy 131.442268 -76.29773) (xy 131.344563 -76.271897) (xy 131.24922 -76.238383) (xy 131.156841 -76.1974)
			(xy 131.06801 -76.149207) (xy 130.983289 -76.094108) (xy 130.903213 -76.032453) (xy 130.828289 -75.964631)
			(xy 130.75899 -75.89107) (xy 130.695755 -75.812236) (xy 130.638983 -75.728627) (xy 130.589033 -75.640772)
			(xy 130.546222 -75.549226) (xy 130.510819 -75.454568) (xy 130.483048 -75.357396) (xy 130.463086 -75.258326)
			(xy 130.451057 -75.157982) (xy 130.44704 -75.057) (xy 62.475872 -75.057) (xy 62.475872 -77.94879)
			(xy 62.476293 -77.958862) (xy 62.484001 -77.977471) (xy 62.490858 -77.984858) (xy 62.646814 -78.140814)
			(xy 62.654209 -78.147668) (xy 62.672808 -78.15541) (xy 62.682882 -78.1558)
		)
		(stroke
			(width 0)
			(type solid)
		)
		(fill yes)
		(layer "F.Cu")
		(net "P12V_BRICK")
	)
	(gr_poly
		(pts
			(xy 143.745712 -113.735612) (xy 143.745712 -112.053878) (xy 143.64081 -111.948976) (xy 142.402306 -111.948976)
			(xy 142.28953 -112.061752) (xy 142.28953 -113.78057) (xy 142.349728 -113.840768) (xy 143.640556 -113.840768)
		)
		(stroke
			(width 0)
			(type solid)
		)
		(fill yes)
		(layer "B.Cu")
		(net "P52V_HS")
	)
	(gr_poly
		(pts
			(xy 193.935604 -18.134584) (xy 193.935604 -6.637782) (xy 193.669666 -6.371844) (xy 192.006728 -6.371844)
			(xy 191.740536 -6.638036) (xy 191.740536 -18.126964) (xy 192.0748 -18.461228) (xy 193.60896 -18.461228)
		)
		(stroke
			(width 0)
			(type solid)
		)
		(fill yes)
		(layer "B.Cu")
		(net "GND")
	)
	(gr_poly
		(pts
			(xy 242.73002 -94.56928) (xy 242.73002 -92.73794) (xy 242.49888 -92.5068) (xy 214.77224 -92.5068)
			(xy 214.63508 -92.64396) (xy 214.63508 -94.55912) (xy 214.81796 -94.742) (xy 242.320318 -94.742)
			(xy 242.5573 -94.742)
		)
		(stroke
			(width 0)
			(type solid)
		)
		(fill yes)
		(layer "B.Cu")
		(net "GND")
	)
	(gr_poly
		(pts
			(xy 272.161 -32.131) (xy 272.161 -31.115) (xy 272.034 -30.988) (xy 269.748 -30.988) (xy 269.621 -31.115)
			(xy 269.621 -32.131) (xy 269.748 -32.258) (xy 271.526 -32.258) (xy 272.034 -32.258)
		)
		(stroke
			(width 0)
			(type solid)
		)
		(fill yes)
		(layer "B.Cu")
		(net "GND")
	)
	(gr_poly
		(pts
			(xy 283.821886 -32.421576) (xy 283.821886 -31.39821) (xy 283.538676 -31.115) (xy 283.1846 -31.115)
			(xy 281.3812 -31.115) (xy 281.3558 -31.1404) (xy 281.3558 -32.3088) (xy 281.5844 -32.5374) (xy 283.706062 -32.5374)
		)
		(stroke
			(width 0)
			(type solid)
		)
		(fill yes)
		(layer "B.Cu")
		(net "P52V_1_R")
	)
	(gr_poly
		(pts
			(xy 285.128208 -55.146956) (xy 285.128208 -53.721) (xy 282.72867 -51.321462) (xy 278.61006 -51.321462)
			(xy 278.479504 -51.452018) (xy 278.479504 -52.042822) (xy 281.640534 -55.203852) (xy 283.012642 -55.203852)
			(xy 285.071312 -55.203852)
		)
		(stroke
			(width 0)
			(type solid)
		)
		(fill yes)
		(layer "B.Cu")
		(net "P52V_HS1_ISET")
	)
	(gr_poly
		(pts
			(xy 275.83384 -34.9758) (xy 275.83384 -33.30956) (xy 275.971 -33.1724) (xy 275.971 -32.893) (xy 275.844 -32.766)
			(xy 274.574 -32.766) (xy 274.447 -32.893) (xy 274.447 -34.798) (xy 274.701 -35.052) (xy 275.75764 -35.052)
		)
		(stroke
			(width 0)
			(type solid)
		)
		(fill yes)
		(layer "B.Cu")
		(net "P52V_1_R")
	)
	(gr_poly
		(pts
			(xy 276.5552 -99.8728) (xy 277.495 -99.8728) (xy 277.5458 -99.822) (xy 277.5458 -99.1108) (xy 277.495 -99.06)
			(xy 275.7678 -99.06) (xy 275.4884 -99.3394) (xy 275.4884 -100.0506) (xy 275.5138 -100.076) (xy 276.352 -100.076)
		)
		(stroke
			(width 0)
			(type solid)
		)
		(fill yes)
		(layer "B.Cu")
		(net "P52V_HS1_GATE_RC")
	)
	(gr_poly
		(pts
			(xy 294.513 -45.974) (xy 294.513 -45.466) (xy 293.878 -44.831) (xy 293.878 -44.3738) (xy 293.7002 -44.196)
			(xy 292.735 -44.196) (xy 292.608 -44.323) (xy 292.608 -45.72) (xy 293.243 -46.355) (xy 294.132 -46.355)
		)
		(stroke
			(width 0)
			(type solid)
		)
		(fill yes)
		(layer "B.Cu")
		(net "P52V_1_R")
	)
	(gr_poly
		(pts
			(xy 277.749 -87.7824) (xy 277.749 -86.995) (xy 277.7236 -86.9696) (xy 275.5392 -86.9696) (xy 275.4884 -87.0204)
			(xy 275.4884 -87.7316) (xy 275.5138 -87.757) (xy 276.606 -87.757) (xy 276.9616 -87.757) (xy 277.0124 -87.8078)
			(xy 277.7236 -87.8078)
		)
		(stroke
			(width 0)
			(type solid)
		)
		(fill yes)
		(layer "B.Cu")
		(net "P52V_HS1_4287_GATE2_RC")
	)
	(gr_poly
		(pts
			(xy 42.1132 -108.585) (xy 42.1132 -103.0732) (xy 41.9354 -102.8954) (xy 38.0746 -102.8954) (xy 37.888164 -103.081836)
			(xy 37.888164 -103.580692) (xy 37.888164 -104.773476) (xy 37.912294 -104.797606) (xy 37.881052 -104.828848)
			(xy 37.881052 -105.778046) (xy 37.881052 -107.0102) (xy 37.881052 -108.543852) (xy 38.1254 -108.7882)
			(xy 41.91 -108.7882)
		)
		(stroke
			(width 0)
			(type solid)
		)
		(fill yes)
		(layer "B.Cu")
		(net "P52V_HS")
	)
	(gr_poly
		(pts
			(xy 33.189672 -108.567728) (xy 33.189672 -107.027472) (xy 33.231836 -106.985308) (xy 33.231836 -105.792524)
			(xy 33.231836 -104.795066) (xy 33.238948 -104.787954) (xy 33.238948 -103.549958) (xy 33.238948 -103.063548)
			(xy 33.0708 -102.8954) (xy 29.083 -102.8954) (xy 28.9052 -102.8954) (xy 28.6766 -103.124) (xy 28.6766 -103.3018)
			(xy 28.6766 -108.712) (xy 28.8036 -108.839) (xy 32.9184 -108.839)
		)
		(stroke
			(width 0)
			(type solid)
		)
		(fill yes)
		(layer "B.Cu")
		(net "P52V_FAN")
	)
	(gr_poly
		(pts
			(xy 277.749 -102.743) (xy 277.749 -100.8126) (xy 277.4696 -100.5332) (xy 276.7584 -100.5332) (xy 276.098 -101.1936)
			(xy 275.522436 -101.1936) (xy 275.499322 -101.216714) (xy 275.499322 -102.224078) (xy 275.471636 -102.251764)
			(xy 275.471636 -102.916228) (xy 275.271992 -103.115872) (xy 274.1676 -103.115872) (xy 274.141692 -103.14178)
			(xy 274.141692 -103.631492) (xy 274.1676 -103.6574) (xy 275.30679 -103.6574) (xy 275.476208 -103.826818)
			(xy 276.665182 -103.826818)
		)
		(stroke
			(width 0)
			(type solid)
		)
		(fill yes)
		(layer "B.Cu")
		(net "P52V_HS1_4287_GATE_R")
	)
	(gr_poly
		(pts
			(xy 191.516 -18.161) (xy 191.516 -6.604) (xy 191.262 -6.35) (xy 185.723276 -6.35) (xy 185.543952 -6.529324)
			(xy 185.543698 -6.529578)
			(arc
				(start 185.198004 -6.875272)
				(mid 185.186893 -6.891806)
				(end 185.183018 -6.91134)
			)
			(arc
				(start 185.183018 -18.103596)
				(mid 185.186919 -18.123119)
				(end 185.198004 -18.139664)
			)
			(arc
				(start 185.660792 -18.602452)
				(mid 185.677326 -18.613563)
				(end 185.69686 -18.617438)
			)
			(xy 190.515494 -18.617438) (xy 191.059562 -18.617438)
		)
		(stroke
			(width 0)
			(type solid)
		)
		(fill yes)
		(layer "B.Cu")
		(net "P3V3_AUX")
	)
	(gr_poly
		(pts
			(xy 277.749 -90.678) (xy 277.749 -88.9) (xy 277.749 -88.4682) (xy 277.7236 -88.4428) (xy 277.0124 -88.4428)
			(xy 276.9489 -88.5063) (xy 276.9489 -88.7857) (xy 276.606 -89.1286) (xy 275.522436 -89.1286) (xy 275.471636 -89.1794)
			(xy 275.471636 -89.578434) (xy 275.471636 -90.851228) (xy 275.271992 -91.050872) (xy 275.128736 -91.050872)
			(xy 274.1676 -91.050872) (xy 274.141692 -91.07678) (xy 274.141692 -91.532964) (xy 274.175728 -91.567)
			(xy 275.28139 -91.567) (xy 275.476208 -91.761818) (xy 276.665182 -91.761818)
		)
		(stroke
			(width 0)
			(type solid)
		)
		(fill yes)
		(layer "B.Cu")
		(net "P52V_HS1_4287_GATE2_R")
	)
	(gr_poly
		(pts
			(arc
				(start 186.107832 -84.4296)
				(mid 185.798968 -84.4296)
				(end 186.107832 -84.4296)
			)
		)
		(stroke
			(width 0)
			(type solid)
		)
		(fill yes)
		(layer "B.Cu")
		(net "GND")
	)
	(gr_poly
		(pts
			(arc
				(start 163.097718 -12.5984)
				(mid 163.117241 -12.594499)
				(end 163.133786 -12.583414)
			)
			(arc
				(start 163.281614 -12.435586)
				(mid 163.292725 -12.419052)
				(end 163.2966 -12.399518)
			)
			(arc
				(start 163.2966 -10.587482)
				(mid 163.292699 -10.567959)
				(end 163.281614 -10.551414)
			)
			(arc
				(start 163.197286 -10.467086)
				(mid 163.180752 -10.455975)
				(end 163.161218 -10.4521)
			)
			(arc
				(start 161.857182 -10.4521)
				(mid 161.837659 -10.456001)
				(end 161.821114 -10.467086)
			)
			(arc
				(start 161.736786 -10.551414)
				(mid 161.725675 -10.567948)
				(end 161.7218 -10.587482)
			)
			(arc
				(start 161.7218 -12.374118)
				(mid 161.725701 -12.393641)
				(end 161.736786 -12.410186)
			)
			(arc
				(start 161.910014 -12.583414)
				(mid 161.926548 -12.594525)
				(end 161.946082 -12.5984)
			)
		)
		(stroke
			(width 0)
			(type solid)
		)
		(fill yes)
		(layer "B.Cu")
		(net "P12V_BRICK")
	)
	(gr_poly
		(pts
			(arc
				(start 177.270918 -16.9672)
				(mid 177.290441 -16.963299)
				(end 177.306986 -16.952214)
			)
			(arc
				(start 177.442114 -16.817086)
				(mid 177.453225 -16.800552)
				(end 177.4571 -16.781018)
			)
			(arc
				(start 177.4571 -12.225782)
				(mid 177.453199 -12.206259)
				(end 177.442114 -12.189714)
			)
			(arc
				(start 177.205386 -11.952986)
				(mid 177.188852 -11.941875)
				(end 177.169318 -11.938)
			)
			(arc
				(start 165.527482 -11.938)
				(mid 165.507959 -11.941901)
				(end 165.491414 -11.952986)
			)
			(arc
				(start 165.216586 -12.227814)
				(mid 165.205475 -12.244348)
				(end 165.2016 -12.263882)
			)
			(arc
				(start 165.2016 -16.641318)
				(mid 165.205501 -16.660841)
				(end 165.216586 -16.677386)
			)
			(arc
				(start 165.491414 -16.952214)
				(mid 165.507948 -16.963325)
				(end 165.527482 -16.9672)
			)
		)
		(stroke
			(width 0)
			(type solid)
		)
		(fill yes)
		(layer "B.Cu")
		(net "GND")
	)
	(gr_poly
		(pts
			(arc
				(start 285.754318 -144.4244)
				(mid 285.773841 -144.420499)
				(end 285.790386 -144.409414)
			)
			(arc
				(start 286.522414 -143.677386)
				(mid 286.533525 -143.660852)
				(end 286.5374 -143.641318)
			)
			(arc
				(start 286.5374 -134.463282)
				(mid 286.533499 -134.443759)
				(end 286.522414 -134.427214)
			)
			(arc
				(start 286.018986 -133.923786)
				(mid 286.002452 -133.912675)
				(end 285.982918 -133.9088)
			)
			(arc
				(start 279.294082 -133.9088)
				(mid 279.274559 -133.912701)
				(end 279.258014 -133.923786)
			)
			(arc
				(start 278.779986 -134.401814)
				(mid 278.768875 -134.418348)
				(end 278.765 -134.437882)
			)
			(arc
				(start 278.765 -143.793718)
				(mid 278.768901 -143.813241)
				(end 278.779986 -143.829786)
			)
			(arc
				(start 279.359614 -144.409414)
				(mid 279.376148 -144.420525)
				(end 279.395682 -144.4244)
			)
		)
		(stroke
			(width 0)
			(type solid)
		)
		(fill yes)
		(layer "B.Cu")
		(net "GND")
	)
	(gr_poly
		(pts
			(arc
				(start 302.23841 -46.456092)
				(mid 302.257904 -46.452308)
				(end 302.274478 -46.44136)
			)
			(arc
				(start 302.359314 -46.356524)
				(mid 302.370425 -46.33999)
				(end 302.3743 -46.320456)
			)
			(arc
				(start 302.3743 -38.540182)
				(mid 302.370399 -38.520659)
				(end 302.359314 -38.504114)
			)
			(arc
				(start 302.313086 -38.457886)
				(mid 302.296552 -38.446775)
				(end 302.277018 -38.4429)
			)
			(arc
				(start 298.940982 -38.4429)
				(mid 298.921459 -38.446801)
				(end 298.904914 -38.457886)
			)
			(arc
				(start 298.769786 -38.593014)
				(mid 298.758675 -38.609548)
				(end 298.7548 -38.629082)
			)
			(arc
				(start 298.7548 -46.333918)
				(mid 298.758701 -46.353441)
				(end 298.769786 -46.369986)
			)
			(arc
				(start 298.840906 -46.441106)
				(mid 298.85744 -46.452217)
				(end 298.876974 -46.456092)
			)
		)
		(stroke
			(width 0)
			(type solid)
		)
		(fill yes)
		(layer "B.Cu")
		(net "P52V_1_FUSE_1")
	)
	(gr_poly
		(pts
			(arc
				(start 63.04788 -69.497702)
				(mid 63.659656 -68.927327)
				(end 64.470026 -68.720208)
			)
			(arc
				(start 64.470026 -68.720208)
				(mid 65.114688 -68.848047)
				(end 65.661794 -69.212206)
			)
			(xy 66.802 -68.072) (xy 66.802 -66.548) (xy 66.294 -66.04) (xy 64.2874 -66.04) (xy 64.0588 -66.2686)
			(xy 64.0588 -67.703446)
			(arc
				(start 63.89243 -67.869816)
				(mid 63.628942 -68.562566)
				(end 62.97168 -68.90512)
			)
			(xy 62.7126 -69.1642) (xy 62.7126 -69.3928) (xy 62.817502 -69.497702)
		)
		(stroke
			(width 0)
			(type solid)
		)
		(fill yes)
		(layer "B.Cu")
		(net "P12V_BRICK")
	)
	(gr_poly
		(pts
			(arc
				(start 36.627816 -59.333638)
				(mid 36.694471 -59.326991)
				(end 36.76142 -59.324748)
			)
			(arc
				(start 38.033452 -59.324748)
				(mid 38.100401 -59.326989)
				(end 38.167056 -59.333638)
			)
			(xy 38.170358 -59.333892)
			(arc
				(start 38.95344 -59.333892)
				(mid 38.972963 -59.329991)
				(end 38.989508 -59.318906)
			)
			(arc
				(start 39.5097 -58.798714)
				(mid 39.526234 -58.787603)
				(end 39.545768 -58.783728)
			)
			(arc
				(start 39.8272 -58.783728)
				(mid 39.863121 -58.768849)
				(end 39.878 -58.732928)
			)
			(arc
				(start 39.878 -55.753508)
				(mid 39.863121 -55.717587)
				(end 39.8272 -55.702708)
			)
			(arc
				(start 38.678866 -55.702708)
				(mid 38.647815 -55.713107)
				(end 38.62959 -55.7403)
			)
			(arc
				(start 38.62959 -55.7403)
				(mid 38.261036 -56.023439)
				(end 37.892482 -55.7403)
			)
			(arc
				(start 37.892482 -55.7403)
				(mid 37.874238 -55.713131)
				(end 37.843206 -55.702708)
			)
			(arc
				(start 36.4998 -55.702708)
				(mid 36.463879 -55.717587)
				(end 36.449 -55.753508)
			)
			(arc
				(start 36.449 -59.2709)
				(mid 36.452901 -59.290423)
				(end 36.463986 -59.306968)
			)
			(arc
				(start 36.476178 -59.31916)
				(mid 36.492624 -59.330086)
				(end 36.511992 -59.333892)
			)
			(xy 36.624514 -59.333892)
		)
		(stroke
			(width 0)
			(type solid)
		)
		(fill yes)
		(layer "B.Cu")
		(net "P12V_HPDB")
	)
	(gr_poly
		(pts
			(xy 0.703834 -134.260844)
			(arc
				(start 0.708406 -134.241794)
				(mid 0.843816 -133.753171)
				(end 1.011936 -133.274816)
			)
			(xy 1.015492 -133.265926)
			(arc
				(start 1.015492 -131.729988)
				(mid 1.596724 -130.326643)
				(end 2.999994 -129.745232)
			)
			(xy 3.852672 -129.745232) (xy 3.866896 -129.740914)
			(arc
				(start 3.873246 -129.73685)
				(mid 4.125576 -129.577591)
				(end 4.38404 -129.428494)
			)
			(xy 4.399534 -129.420112) (xy 4.41325 -129.388362)
			(arc
				(start 4.384294 -129.276094)
				(mid 4.366188 -129.248572)
				(end 4.335018 -129.237994)
			)
			(arc
				(start 2.999994 -129.237994)
				(mid 1.237888 -129.967882)
				(end 0.508 -131.729988)
			)
			(arc
				(start 0.508 -134.218172)
				(mid 0.520873 -134.251715)
				(end 0.552704 -134.268464)
			)
			(xy 0.672338 -134.282688)
		)
		(stroke
			(width 0)
			(type solid)
		)
		(fill yes)
		(layer "B.Cu")
		(net "GND")
	)
	(gr_poly
		(pts
			(arc
				(start 3.99288 -18.562066)
				(mid 4.023458 -18.551833)
				(end 4.041648 -18.525236)
			)
			(xy 4.073144 -18.414746) (xy 4.060952 -18.38325)
			(arc
				(start 4.046474 -18.374106)
				(mid 3.813488 -18.223547)
				(end 3.586226 -18.06448)
			)
			(xy 3.579622 -18.059654) (xy 3.564382 -18.054828)
			(arc
				(start 2.999994 -18.054828)
				(mid 1.596829 -17.473671)
				(end 1.015492 -16.07058)
			)
			(xy 1.015492 -14.734286)
			(arc
				(start 1.011936 -14.725396)
				(mid 0.843824 -14.247038)
				(end 0.708406 -13.758418)
			)
			(xy 0.703834 -13.739368) (xy 0.672338 -13.717524)
			(arc
				(start 0.552704 -13.731748)
				(mid 0.52079 -13.748422)
				(end 0.508 -13.78204)
			)
			(arc
				(start 0.508 -16.070072)
				(mid 1.237888 -17.832178)
				(end 2.999994 -18.562066)
			)
		)
		(stroke
			(width 0)
			(type solid)
		)
		(fill yes)
		(layer "B.Cu")
		(net "GND")
	)
	(gr_poly
		(pts
			(arc
				(start 294.339518 -124.079)
				(mid 294.359041 -124.075099)
				(end 294.375586 -124.064014)
			)
			(arc
				(start 295.412414 -123.027186)
				(mid 295.423525 -123.010652)
				(end 295.4274 -122.991118)
			)
			(arc
				(start 295.4274 -119.413782)
				(mid 295.431301 -119.394259)
				(end 295.442386 -119.377714)
			)
			(arc
				(start 295.843452 -118.976648)
				(mid 295.860959 -118.965299)
				(end 295.881552 -118.961916)
			)
			(arc
				(start 297.564302 -118.961916)
				(mid 297.583825 -118.958015)
				(end 297.60037 -118.94693)
			)
			(arc
				(start 298.943014 -117.604286)
				(mid 298.954125 -117.587752)
				(end 298.958 -117.568218)
			)
			(arc
				(start 298.958 -97.430082)
				(mid 298.954099 -97.410559)
				(end 298.943014 -97.394014)
			)
			(arc
				(start 298.591986 -97.042986)
				(mid 298.575452 -97.031875)
				(end 298.555918 -97.028)
			)
			(arc
				(start 280.818082 -97.028)
				(mid 280.798559 -97.031901)
				(end 280.782014 -97.042986)
			)
			(arc
				(start 279.999186 -97.825814)
				(mid 279.988075 -97.842348)
				(end 279.9842 -97.861882)
			)
			(arc
				(start 279.9842 -100.508562)
				(mid 279.987112 -100.525262)
				(end 279.995376 -100.540058)
			)
			(arc
				(start 279.995376 -100.540058)
				(mid 280.303313 -101.098363)
				(end 280.409904 -101.727)
			)
			(xy 280.409904 -102.53599)
			(arc
				(start 280.41219 -102.543356)
				(mid 280.486678 -102.869316)
				(end 280.511758 -103.20274)
			)
			(arc
				(start 280.511758 -103.20274)
				(mid 280.508674 -103.321142)
				(end 280.499312 -103.439214)
			)
			(xy 280.498804 -103.442008)
			(arc
				(start 280.498804 -103.964994)
				(mid 280.369234 -104.712801)
				(end 279.99563 -105.373424)
			)
			(arc
				(start 279.99563 -105.373424)
				(mid 279.987147 -105.388566)
				(end 279.9842 -105.405682)
			)
			(arc
				(start 279.9842 -123.295918)
				(mid 279.988101 -123.315441)
				(end 279.999186 -123.331986)
			)
			(arc
				(start 280.731214 -124.064014)
				(mid 280.747748 -124.075125)
				(end 280.767282 -124.079)
			)
		)
		(stroke
			(width 0)
			(type solid)
		)
		(fill yes)
		(layer "B.Cu")
		(net "P52V_HS1_DRAIN_1")
	)
	(gr_poly
		(pts
			(arc
				(start 36.0172 -146.49196)
				(mid 36.053121 -146.477081)
				(end 36.068 -146.44116)
			)
			(arc
				(start 36.068 -146.035268)
				(mid 36.053121 -145.999347)
				(end 36.0172 -145.984468)
			)
			(arc
				(start 4.99999 -145.984468)
				(mid 2.182524 -144.817436)
				(end 1.015492 -141.99997)
			)
			(xy 1.015492 -138.734292)
			(arc
				(start 1.011936 -138.725402)
				(mid 0.843824 -138.247044)
				(end 0.708406 -137.758424)
			)
			(xy 0.703834 -137.739374) (xy 0.672338 -137.71753)
			(arc
				(start 0.552704 -137.731754)
				(mid 0.52079 -137.748428)
				(end 0.508 -137.782046)
			)
			(arc
				(start 0.508 -141.99997)
				(mid 1.823673 -145.176287)
				(end 4.99999 -146.49196)
			)
		)
		(stroke
			(width 0)
			(type solid)
		)
		(fill yes)
		(layer "B.Cu")
		(net "GND")
	)
	(gr_poly
		(pts
			(xy 264.824718 -38.6842) (xy 264.834787 -38.683773) (xy 264.853386 -38.676054) (xy 264.860786 -38.669214)
			(xy 264.932414 -38.597586) (xy 264.939268 -38.590191) (xy 264.94701 -38.571592) (xy 264.9474 -38.561518)
			(xy 264.9474 -38.146482) (xy 264.947827 -38.136413) (xy 264.955546 -38.117814) (xy 264.962386 -38.110414)
			(xy 265.999214 -37.073586) (xy 266.006068 -37.066191) (xy 266.01381 -37.047592) (xy 266.0142 -37.037518)
			(xy 266.0142 -36.520882) (xy 266.013773 -36.510813) (xy 266.006054 -36.492214) (xy 265.999214 -36.484814)
			(xy 265.778488 -36.264088) (xy 265.77036 -36.257484) (xy 265.748359 -36.242625) (xy 265.708301 -36.207783)
			(xy 265.673462 -36.167724) (xy 265.6586 -36.145724) (xy 265.655806 -36.141406) (xy 265.597386 -36.082986)
			(xy 265.590532 -36.075591) (xy 265.58279 -36.056992) (xy 265.5824 -36.046918) (xy 265.5824 -35.657282)
			(xy 265.582827 -35.647213) (xy 265.590546 -35.628614) (xy 265.597386 -35.621214) (xy 265.771884 -35.446716)
			(xy 265.797284 -35.446716) (xy 266.067032 -35.176968) (xy 266.067032 -31.675832) (xy 266.0142 -31.623)
			(xy 263.8552 -31.623) (xy 263.271 -32.2072) (xy 263.271 -36.233354) (xy 263.374124 -36.336478) (xy 263.387078 -36.336478)
			(xy 263.814814 -36.764214) (xy 263.821668 -36.771609) (xy 263.82941 -36.790208) (xy 263.8298 -36.800282)
			(xy 263.8298 -37.049198) (xy 264.702526 -37.049198) (xy 264.702526 -36.989262) (xy 264.710349 -36.92984)
			(xy 264.725862 -36.871947) (xy 264.748798 -36.816574) (xy 264.778765 -36.764668) (xy 264.815252 -36.717118)
			(xy 264.857632 -36.674738) (xy 264.905182 -36.638251) (xy 264.957088 -36.608284) (xy 265.012461 -36.585348)
			(xy 265.070354 -36.569835) (xy 265.129776 -36.562012) (xy 265.189712 -36.562012) (xy 265.249134 -36.569835)
			(xy 265.307027 -36.585348) (xy 265.3624 -36.608284) (xy 265.414306 -36.638251) (xy 265.461856 -36.674738)
			(xy 265.504236 -36.717118) (xy 265.540723 -36.764668) (xy 265.57069 -36.816574) (xy 265.593626 -36.871947)
			(xy 265.609139 -36.92984) (xy 265.616962 -36.989262) (xy 265.617452 -37.01923) (xy 265.616962 -37.049198)
			(xy 265.609139 -37.10862) (xy 265.593626 -37.166513) (xy 265.57069 -37.221886) (xy 265.540723 -37.273792)
			(xy 265.504236 -37.321342) (xy 265.461856 -37.363722) (xy 265.414306 -37.400209) (xy 265.3624 -37.430176)
			(xy 265.307027 -37.453112) (xy 265.249134 -37.468625) (xy 265.189712 -37.476448) (xy 265.129776 -37.476448)
			(xy 265.070354 -37.468625) (xy 265.012461 -37.453112) (xy 264.957088 -37.430176) (xy 264.905182 -37.400209)
			(xy 264.857632 -37.363722) (xy 264.815252 -37.321342) (xy 264.778765 -37.273792) (xy 264.748798 -37.221886)
			(xy 264.725862 -37.166513) (xy 264.710349 -37.10862) (xy 264.702526 -37.049198) (xy 263.8298 -37.049198)
			(xy 263.8298 -38.205918) (xy 263.830227 -38.215987) (xy 263.837946 -38.234586) (xy 263.844786 -38.241986)
			(xy 264.272014 -38.669214) (xy 264.279409 -38.676068) (xy 264.298008 -38.68381) (xy 264.308082 -38.6842)
		)
		(stroke
			(width 0)
			(type solid)
		)
		(fill yes)
		(layer "B.Cu")
		(net "P52V_HS1_INTVCC")
	)
	(gr_poly
		(pts
			(arc
				(start 298.086526 -95.693992)
				(mid 298.106049 -95.690091)
				(end 298.122594 -95.679006)
			)
			(arc
				(start 298.917614 -94.883986)
				(mid 298.928725 -94.867452)
				(end 298.9326 -94.847918)
			)
			(arc
				(start 298.9326 -89.124028)
				(mid 298.926679 -89.100479)
				(end 298.910502 -89.082372)
			)
			(arc
				(start 298.910502 -89.082372)
				(mid 298.712634 -88.705436)
				(end 298.910502 -88.3285)
			)
			(arc
				(start 298.910502 -88.3285)
				(mid 298.926675 -88.310391)
				(end 298.9326 -88.286844)
			)
			(arc
				(start 298.9326 -83.611974)
				(mid 298.924063 -83.583787)
				(end 298.901358 -83.564984)
			)
			(xy 298.88688 -83.558888) (xy 298.856908 -83.564984)
			(arc
				(start 298.578016 -83.84413)
				(mid 298.421275 -83.948861)
				(end 298.236386 -83.985608)
			)
			(arc
				(start 295.92778 -83.985608)
				(mid 295.444672 -83.5025)
				(end 295.92778 -83.019392)
			)
			(arc
				(start 298.015406 -83.019392)
				(mid 298.034763 -83.015559)
				(end 298.05122 -83.00466)
			)
			(arc
				(start 298.917614 -82.138012)
				(mid 298.928676 -82.121595)
				(end 298.9326 -82.102198)
			)
			(arc
				(start 298.9326 -61.717682)
				(mid 298.928699 -61.698159)
				(end 298.917614 -61.681614)
			)
			(arc
				(start 298.083986 -60.847986)
				(mid 298.067452 -60.836875)
				(end 298.047918 -60.833)
			)
			(arc
				(start 279.539446 -60.833)
				(mid 279.519923 -60.836901)
				(end 279.503378 -60.847986)
			)
			(arc
				(start 279.013666 -61.337698)
				(mid 279.002555 -61.354232)
				(end 278.99868 -61.373766)
			)
			(arc
				(start 278.99868 -84.5058)
				(mid 279.002224 -84.524189)
				(end 279.012142 -84.54009)
			)
			(arc
				(start 279.012142 -84.54009)
				(mid 279.450584 -85.241946)
				(end 279.603708 -86.0552)
			)
			(arc
				(start 279.603708 -86.0552)
				(mid 279.5942 -86.260667)
				(end 279.565862 -86.464394)
			)
			(arc
				(start 279.565862 -86.464394)
				(mid 279.565015 -86.475487)
				(end 279.566624 -86.486492)
			)
			(arc
				(start 279.566624 -86.486492)
				(mid 279.613355 -86.726042)
				(end 279.629108 -86.9696)
			)
			(arc
				(start 279.629108 -87.7824)
				(mid 279.623499 -87.928243)
				(end 279.606756 -88.07323)
			)
			(arc
				(start 279.606756 -88.07323)
				(mid 279.609965 -88.100414)
				(end 279.626822 -88.121998)
			)
			(arc
				(start 279.626822 -88.121998)
				(mid 280.203055 -88.798115)
				(end 280.410158 -89.662)
			)
			(xy 280.410158 -90.17) (xy 280.410158 -90.19159) (xy 280.409904 -90.192098) (xy 280.409904 -90.42781)
			(arc
				(start 280.41219 -90.435176)
				(mid 280.486678 -90.761136)
				(end 280.511758 -91.09456)
			)
			(arc
				(start 280.511758 -91.09456)
				(mid 280.508674 -91.212962)
				(end 280.499312 -91.331034)
			)
			(xy 280.498804 -91.333828)
			(arc
				(start 280.498804 -91.899994)
				(mid 280.363698 -92.663165)
				(end 279.974802 -93.33357)
			)
			(arc
				(start 279.974802 -93.33357)
				(mid 279.965219 -93.350944)
				(end 279.963118 -93.370654)
			)
			(arc
				(start 279.963118 -93.370654)
				(mid 279.968295 -93.452115)
				(end 279.969976 -93.533722)
			)
			(arc
				(start 279.969976 -94.346522)
				(mid 279.864211 -94.97274)
				(end 279.558496 -95.5294)
			)
			(xy 279.549352 -95.541084) (xy 279.54605 -95.569532)
			(arc
				(start 279.592532 -95.66529)
				(mid 279.611266 -95.686208)
				(end 279.638252 -95.693992)
			)
		)
		(stroke
			(width 0)
			(type solid)
		)
		(fill yes)
		(layer "B.Cu")
		(net "P52V_HS1_DRAIN_2")
	)
	(gr_poly
		(pts
			(arc
				(start 10.879328 -116.229384)
				(mid 10.903825 -116.223087)
				(end 10.922254 -116.205762)
			)
			(arc
				(start 10.967974 -116.133118)
				(mid 10.975912 -116.109154)
				(end 10.971276 -116.08435)
			)
			(arc
				(start 10.971276 -116.08435)
				(mid 10.411929 -115.450247)
				(end 9.59993 -115.2144)
			)
			(arc
				(start 2.999994 -115.2144)
				(mid 1.596739 -114.633153)
				(end 1.015492 -113.229898)
			)
			(arc
				(start 1.015492 -34.569908)
				(mid 1.596724 -33.166563)
				(end 2.999994 -32.585152)
			)
			(arc
				(start 9.600184 -32.585152)
				(mid 10.671454 -32.141312)
				(end 11.115294 -31.070042)
			)
			(xy 11.115548 -28.039568) (xy 11.115548 -19.569938) (xy 11.115294 -19.569938)
			(arc
				(start 11.115294 -19.550888)
				(mid 11.100237 -19.515294)
				(end 11.064494 -19.500596)
			)
			(arc
				(start 10.658602 -19.500596)
				(mid 10.622681 -19.515475)
				(end 10.607802 -19.551396)
			)
			(xy 10.607802 -19.552412) (xy 10.608056 -19.569938)
			(arc
				(start 10.608056 -31.070042)
				(mid 10.312783 -31.782641)
				(end 9.600184 -32.077914)
			)
			(arc
				(start 2.999994 -32.077914)
				(mid 1.237888 -32.807802)
				(end 0.508 -34.569908)
			)
			(arc
				(start 0.508 -113.229898)
				(mid 1.237888 -114.992004)
				(end 2.999994 -115.721892)
			)
			(arc
				(start 9.59993 -115.721892)
				(mid 10.093358 -115.850938)
				(end 10.460482 -116.205)
			)
			(arc
				(start 10.460482 -116.205)
				(mid 10.479002 -116.222897)
				(end 10.503916 -116.229384)
			)
		)
		(stroke
			(width 0)
			(type solid)
		)
		(fill yes)
		(layer "B.Cu")
		(net "GND")
	)
	(gr_poly
		(pts
			(arc
				(start 323.000116 -146.49196)
				(mid 326.176433 -145.176287)
				(end 327.492106 -141.99997)
			)
			(arc
				(start 327.492106 -4.99999)
				(mid 326.176433 -1.823673)
				(end 323.000116 -0.508)
			)
			(arc
				(start 4.99999 -0.508)
				(mid 1.823673 -1.823673)
				(end 0.508 -4.99999)
			)
			(arc
				(start 0.508 -10.218166)
				(mid 0.520873 -10.251709)
				(end 0.552704 -10.268458)
			)
			(xy 0.672338 -10.282682) (xy 0.703834 -10.260838)
			(arc
				(start 0.708406 -10.241788)
				(mid 0.843816 -9.753165)
				(end 1.011936 -9.27481)
			)
			(xy 1.015492 -9.26592)
			(arc
				(start 1.015492 -4.99999)
				(mid 2.182524 -2.182524)
				(end 4.99999 -1.015492)
			)
			(arc
				(start 323.000116 -1.015492)
				(mid 325.817582 -2.182524)
				(end 326.984614 -4.99999)
			)
			(arc
				(start 326.984614 -141.99997)
				(mid 325.817582 -144.817436)
				(end 323.000116 -145.984468)
			)
			(arc
				(start 236.7788 -145.984468)
				(mid 236.742879 -145.999347)
				(end 236.728 -146.035268)
			)
			(arc
				(start 236.728 -146.44116)
				(mid 236.742879 -146.477081)
				(end 236.7788 -146.49196)
			)
		)
		(stroke
			(width 0)
			(type solid)
		)
		(fill yes)
		(layer "B.Cu")
		(net "GND")
	)
	(gr_poly
		(pts
			(xy 319.477136 -121.699782) (xy 319.487203 -121.699352) (xy 319.505796 -121.691626) (xy 319.513204 -121.684796)
			(xy 320.406014 -120.791986) (xy 320.412868 -120.784591) (xy 320.42061 -120.765992) (xy 320.421 -120.755918)
			(xy 320.421 -77.089) (xy 320.0527 -76.7207) (xy 319.673986 -76.341986) (xy 319.666591 -76.335132)
			(xy 319.647992 -76.32739) (xy 319.637918 -76.327) (xy 308.463696 -76.327) (xy 308.453626 -76.326576)
			(xy 308.435023 -76.318861) (xy 308.427628 -76.312014) (xy 305.957986 -73.842372) (xy 305.951135 -73.834976)
			(xy 305.943397 -73.816377) (xy 305.943 -73.806304) (xy 305.943 -57.5056) (xy 302.1584 -53.721) (xy 300.1264 -51.689)
			(xy 296.291 -51.689) (xy 295.91 -52.07) (xy 295.91 -53.086) (xy 295.275 -53.721) (xy 294.259 -53.721)
			(xy 285.93542 -53.721) (xy 285.8389 -53.81752) (xy 285.8389 -57.5183) (xy 286.1818 -57.8612) (xy 298.5008 -57.8612)
			(xy 300.838108 -60.198508) (xy 300.838108 -80.98028) (xy 300.863508 -80.98028) (xy 300.863508 -81.79054)
			(xy 300.863939 -81.800607) (xy 300.871664 -81.8192) (xy 300.878494 -81.826608) (xy 302.056546 -83.004406)
			(xy 302.063947 -83.011245) (xy 302.082545 -83.018961) (xy 302.092614 -83.019392) (xy 303.126394 -83.019392)
			(xy 303.158026 -83.019887) (xy 303.22075 -83.028144) (xy 303.281859 -83.044517) (xy 303.340308 -83.068727)
			(xy 303.395098 -83.100359) (xy 303.445289 -83.138872) (xy 303.490024 -83.183606) (xy 303.528538 -83.233797)
			(xy 303.56017 -83.288586) (xy 303.584381 -83.347035) (xy 303.600755 -83.408144) (xy 303.609013 -83.470868)
			(xy 303.609013 -83.534132) (xy 303.600755 -83.596856) (xy 303.584381 -83.657965) (xy 303.56017 -83.716414)
			(xy 303.528538 -83.771203) (xy 303.490024 -83.821394) (xy 303.445289 -83.866128) (xy 303.395098 -83.904641)
			(xy 303.340308 -83.936273) (xy 303.281859 -83.960483) (xy 303.22075 -83.976856) (xy 303.158026 -83.985113)
			(xy 303.126394 -83.985608) (xy 301.0408 -83.985608) (xy 300.863508 -84.1629) (xy 300.863508 -84.9122)
			(xy 300.838108 -84.9122) (xy 300.838108 -93.04528) (xy 300.863508 -93.04528) (xy 300.863508 -101.556221)
			(xy 306.253885 -101.556221) (xy 306.253885 -101.353711) (xy 306.261836 -101.151357) (xy 306.277724 -100.949472)
			(xy 306.301527 -100.748365) (xy 306.333206 -100.548349) (xy 306.372714 -100.34973) (xy 306.419989 -100.152815)
			(xy 306.474959 -99.957908) (xy 306.537538 -99.76531) (xy 306.60763 -99.575317) (xy 306.685127 -99.388222)
			(xy 306.76991 -99.204314) (xy 306.861847 -99.023876) (xy 306.960798 -98.847187) (xy 307.066609 -98.674519)
			(xy 307.179118 -98.506138) (xy 307.29815 -98.342304) (xy 307.423523 -98.18327) (xy 307.555042 -98.02928)
			(xy 307.692506 -97.880572) (xy 307.835702 -97.737376) (xy 307.98441 -97.599912) (xy 308.1384 -97.468393)
			(xy 308.297434 -97.34302) (xy 308.461268 -97.223988) (xy 308.629649 -97.111479) (xy 308.802317 -97.005668)
			(xy 308.979006 -96.906717) (xy 309.159444 -96.81478) (xy 309.343352 -96.729997) (xy 309.530447 -96.6525)
			(xy 309.72044 -96.582408) (xy 309.913038 -96.519829) (xy 310.107945 -96.464859) (xy 310.30486 -96.417584)
			(xy 310.503479 -96.378076) (xy 310.703495 -96.346397) (xy 310.904602 -96.322594) (xy 311.106487 -96.306706)
			(xy 311.308841 -96.298755) (xy 311.511351 -96.298755) (xy 311.713705 -96.306706) (xy 311.91559 -96.322594)
			(xy 312.116697 -96.346397) (xy 312.316713 -96.378076) (xy 312.515332 -96.417584) (xy 312.712247 -96.464859)
			(xy 312.907154 -96.519829) (xy 313.099752 -96.582408) (xy 313.289745 -96.6525) (xy 313.47684 -96.729997)
			(xy 313.660748 -96.81478) (xy 313.841186 -96.906717) (xy 314.017875 -97.005668) (xy 314.190543 -97.111479)
			(xy 314.358924 -97.223988) (xy 314.522758 -97.34302) (xy 314.681792 -97.468393) (xy 314.835782 -97.599912)
			(xy 314.98449 -97.737376) (xy 315.127686 -97.880572) (xy 315.26515 -98.02928) (xy 315.396669 -98.18327)
			(xy 315.522042 -98.342304) (xy 315.641074 -98.506138) (xy 315.753583 -98.674519) (xy 315.859394 -98.847187)
			(xy 315.958345 -99.023876) (xy 316.050282 -99.204314) (xy 316.135065 -99.388222) (xy 316.212562 -99.575317)
			(xy 316.282654 -99.76531) (xy 316.345233 -99.957908) (xy 316.400203 -100.152815) (xy 316.447478 -100.34973)
			(xy 316.486986 -100.548349) (xy 316.518665 -100.748365) (xy 316.542468 -100.949472) (xy 316.558356 -101.151357)
			(xy 316.566307 -101.353711) (xy 316.566804 -101.454966) (xy 316.566307 -101.556221) (xy 316.558356 -101.758575)
			(xy 316.542468 -101.96046) (xy 316.518665 -102.161567) (xy 316.486986 -102.361583) (xy 316.447478 -102.560202)
			(xy 316.400203 -102.757117) (xy 316.345233 -102.952024) (xy 316.282654 -103.144622) (xy 316.212562 -103.334615)
			(xy 316.135065 -103.52171) (xy 316.050282 -103.705618) (xy 315.958345 -103.886056) (xy 315.859394 -104.062745)
			(xy 315.753583 -104.235413) (xy 315.641074 -104.403794) (xy 315.522042 -104.567628) (xy 315.396669 -104.726662)
			(xy 315.26515 -104.880652) (xy 315.127686 -105.02936) (xy 314.98449 -105.172556) (xy 314.835782 -105.31002)
			(xy 314.681792 -105.441539) (xy 314.522758 -105.566912) (xy 314.358924 -105.685944) (xy 314.190543 -105.798453)
			(xy 314.017875 -105.904264) (xy 313.841186 -106.003215) (xy 313.660748 -106.095152) (xy 313.47684 -106.179935)
			(xy 313.289745 -106.257432) (xy 313.099752 -106.327524) (xy 312.907154 -106.390103) (xy 312.712247 -106.445073)
			(xy 312.515332 -106.492348) (xy 312.316713 -106.531856) (xy 312.116697 -106.563535) (xy 311.91559 -106.587338)
			(xy 311.713705 -106.603226) (xy 311.511351 -106.611177) (xy 311.308841 -106.611177) (xy 311.106487 -106.603226)
			(xy 310.904602 -106.587338) (xy 310.703495 -106.563535) (xy 310.503479 -106.531856) (xy 310.30486 -106.492348)
			(xy 310.107945 -106.445073) (xy 309.913038 -106.390103) (xy 309.72044 -106.327524) (xy 309.530447 -106.257432)
			(xy 309.343352 -106.179935) (xy 309.159444 -106.095152) (xy 308.979006 -106.003215) (xy 308.802317 -105.904264)
			(xy 308.629649 -105.798453) (xy 308.461268 -105.685944) (xy 308.297434 -105.566912) (xy 308.1384 -105.441539)
			(xy 307.98441 -105.31002) (xy 307.835702 -105.172556) (xy 307.692506 -105.02936) (xy 307.555042 -104.880652)
			(xy 307.423523 -104.726662) (xy 307.29815 -104.567628) (xy 307.179118 -104.403794) (xy 307.066609 -104.235413)
			(xy 306.960798 -104.062745) (xy 306.861847 -103.886056) (xy 306.76991 -103.705618) (xy 306.685127 -103.52171)
			(xy 306.60763 -103.334615) (xy 306.537538 -103.144622) (xy 306.474959 -102.952024) (xy 306.419989 -102.757117)
			(xy 306.372714 -102.560202) (xy 306.333206 -102.361583) (xy 306.301527 -102.161567) (xy 306.277724 -101.96046)
			(xy 306.261836 -101.758575) (xy 306.253885 -101.556221) (xy 300.863508 -101.556221) (xy 300.863508 -117.94744)
			(xy 300.863939 -117.957507) (xy 300.871664 -117.9761) (xy 300.878494 -117.983508) (xy 302.094646 -119.199406)
			(xy 302.102047 -119.206245) (xy 302.120645 -119.213961) (xy 302.130714 -119.214392) (xy 303.23536 -119.214392)
			(xy 303.266994 -119.214885) (xy 303.329721 -119.223138) (xy 303.390834 -119.239508) (xy 303.449287 -119.263716)
			(xy 303.50408 -119.295347) (xy 303.554275 -119.33386) (xy 303.599014 -119.378595) (xy 303.637531 -119.428787)
			(xy 303.669166 -119.483577) (xy 303.693379 -119.542028) (xy 303.709754 -119.60314) (xy 303.718013 -119.665866)
			(xy 303.718013 -119.729134) (xy 303.709754 -119.79186) (xy 303.693379 -119.852972) (xy 303.669166 -119.911423)
			(xy 303.637531 -119.966213) (xy 303.599014 -120.016405) (xy 303.554275 -120.06114) (xy 303.50408 -120.099653)
			(xy 303.449287 -120.131284) (xy 303.390834 -120.155492) (xy 303.329721 -120.171862) (xy 303.266994 -120.180115)
			(xy 303.23536 -120.180608) (xy 300.99 -120.180608) (xy 300.863508 -120.3071) (xy 300.863508 -121.231914)
			(xy 301.31639 -121.684796) (xy 301.323788 -121.691645) (xy 301.342386 -121.699383) (xy 301.352458 -121.699782)
		)
		(stroke
			(width 0)
			(type solid)
		)
		(fill yes)
		(layer "B.Cu")
		(net "P52V_1")
	)
	(gr_poly
		(pts
			(xy 319.265808 -69.263006) (xy 319.275878 -69.262582) (xy 319.294481 -69.254866) (xy 319.301876 -69.24802)
			(xy 323.149214 -65.400682) (xy 323.156067 -65.393287) (xy 323.163808 -65.374688) (xy 323.1642 -65.364614)
			(xy 323.1642 -6.473698) (xy 323.163776 -6.463628) (xy 323.156061 -6.445024) (xy 323.149214 -6.43763)
			(xy 320.990214 -4.27863) (xy 320.982812 -4.271794) (xy 320.964214 -4.264086) (xy 320.954146 -4.263644)
			(xy 278.609298 -4.263644) (xy 278.599229 -4.264069) (xy 278.580629 -4.271789) (xy 278.57323 -4.27863)
			(xy 278.248618 -4.603242) (xy 278.241776 -4.610642) (xy 278.234054 -4.62924) (xy 278.233632 -4.63931)
			(xy 278.233632 -14.741906) (xy 278.234057 -14.751975) (xy 278.241776 -14.770575) (xy 278.248618 -14.777974)
			(xy 283.787342 -20.316698) (xy 283.794743 -20.323538) (xy 283.813341 -20.331258) (xy 283.82341 -20.331684)
			(xy 285.1531 -20.331684) (xy 285.163171 -20.332107) (xy 285.181777 -20.339819) (xy 285.189168 -20.34667)
			(xy 286.930084 -22.087586) (xy 286.933702 -22.091019) (xy 286.942021 -22.096517) (xy 286.946594 -22.098508)
			(xy 287.629346 -22.381464) (xy 287.634032 -22.383268) (xy 287.643884 -22.385198) (xy 287.648904 -22.385274)
			(xy 290.163504 -22.385274) (xy 290.173573 -22.38485) (xy 290.192174 -22.377131) (xy 290.199572 -22.370288)
			(xy 290.812474 -21.757386) (xy 290.819872 -21.750542) (xy 290.838472 -21.742821) (xy 290.848542 -21.7424)
			(xy 297.849036 -21.7424) (xy 297.859103 -21.74283) (xy 297.877698 -21.750553) (xy 297.885104 -21.757386)
			(xy 298.435014 -22.307296) (xy 298.44187 -22.31469) (xy 298.44962 -22.333289) (xy 298.45 -22.343364)
			(xy 298.45 -29.363924) (xy 298.450428 -29.373992) (xy 298.458148 -29.39259) (xy 298.464986 -29.399992)
			(xy 299.09897 -30.03423) (xy 299.148228 -30.084266) (xy 299.240762 -30.18989) (xy 299.283882 -30.245304)
			(xy 299.290882 -30.253478) (xy 299.309788 -30.263705) (xy 299.320458 -30.265116) (xy 299.348978 -30.26765)
			(xy 299.404844 -30.280184) (xy 299.45821 -30.300924) (xy 299.507878 -30.329406) (xy 299.552733 -30.36499)
			(xy 299.591767 -30.406877) (xy 299.624104 -30.454126) (xy 299.649018 -30.505676) (xy 299.665949 -30.56037)
			(xy 299.674518 -30.616981) (xy 299.675042 -30.645608) (xy 299.674623 -30.671067) (xy 299.667848 -30.721533)
			(xy 299.654408 -30.770646) (xy 299.634541 -30.817528) (xy 299.621956 -30.839664) (xy 299.616866 -30.849197)
			(xy 299.614489 -30.870655) (xy 299.617384 -30.881066) (xy 299.63734 -30.944386) (xy 299.67025 -31.07302)
			(xy 299.695053 -31.20346) (xy 299.711651 -31.335196) (xy 299.719979 -31.467712) (xy 299.720508 -31.5341)
			(xy 299.720508 -34.37636) (xy 299.720921 -34.386386) (xy 299.728584 -34.404915) (xy 299.742758 -34.419098)
			(xy 299.761282 -34.426773) (xy 299.771308 -34.42716) (xy 303.193196 -34.42716) (xy 303.203265 -34.427584)
			(xy 303.221865 -34.435304) (xy 303.229264 -34.442146) (xy 304.74031 -35.953192) (xy 304.747167 -35.960586)
			(xy 304.754919 -35.979185) (xy 304.755296 -35.98926) (xy 304.755296 -44.304966) (xy 306.277779 -44.304966)
			(xy 306.281786 -44.102206) (xy 306.2938 -43.899762) (xy 306.313802 -43.697951) (xy 306.341762 -43.497087)
			(xy 306.377635 -43.297485) (xy 306.421366 -43.099456) (xy 306.472887 -42.90331) (xy 306.532116 -42.709352)
			(xy 306.598961 -42.517885) (xy 306.673319 -42.329208) (xy 306.755072 -42.143617) (xy 306.844094 -41.9614)
			(xy 306.940245 -41.782842) (xy 307.043375 -41.608223) (xy 307.153323 -41.437814) (xy 307.269918 -41.271881)
			(xy 307.392977 -41.110685) (xy 307.522308 -40.954476) (xy 307.65771 -40.803498) (xy 307.79897 -40.657988)
			(xy 307.945869 -40.518172) (xy 308.098177 -40.384268) (xy 308.255656 -40.256486) (xy 308.418061 -40.135026)
			(xy 308.585137 -40.020076) (xy 308.756623 -39.911817) (xy 308.932253 -39.810417) (xy 309.111752 -39.716034)
			(xy 309.29484 -39.628817) (xy 309.48123 -39.548901) (xy 309.670632 -39.476411) (xy 309.862749 -39.411461)
			(xy 310.057283 -39.35415) (xy 310.253929 -39.30457) (xy 310.45238 -39.262798) (xy 310.652327 -39.228898)
			(xy 310.853457 -39.202924) (xy 311.055456 -39.184916) (xy 311.258008 -39.174903) (xy 311.460798 -39.172899)
			(xy 311.663509 -39.178909) (xy 311.865825 -39.192922) (xy 312.067428 -39.214918) (xy 312.268006 -39.24486)
			(xy 312.467244 -39.282704) (xy 312.664831 -39.328389) (xy 312.860459 -39.381845) (xy 313.053822 -39.442987)
			(xy 313.244619 -39.511721) (xy 313.432552 -39.587938) (xy 313.617327 -39.671521) (xy 313.798655 -39.762339)
			(xy 313.976255 -39.860249) (xy 314.149847 -39.965099) (xy 314.319161 -40.076726) (xy 314.483934 -40.194954)
			(xy 314.643907 -40.319599) (xy 314.79883 -40.450468) (xy 314.948463 -40.587354) (xy 315.092571 -40.730045)
			(xy 315.230929 -40.878318) (xy 315.363321 -41.031942) (xy 315.489541 -41.190675) (xy 315.609391 -41.354272)
			(xy 315.722685 -41.522475) (xy 315.829245 -41.695023) (xy 315.928905 -41.871646) (xy 316.021509 -42.052069)
			(xy 316.106913 -42.236009) (xy 316.184984 -42.423179) (xy 316.255599 -42.613288) (xy 316.318649 -42.806038)
			(xy 316.374035 -43.001129) (xy 316.421669 -43.198255) (xy 316.461479 -43.397109) (xy 316.493402 -43.597381)
			(xy 316.517388 -43.798757) (xy 316.533399 -44.000924) (xy 316.541411 -44.203566) (xy 316.541912 -44.304966)
			(xy 316.541411 -44.406366) (xy 316.533399 -44.609008) (xy 316.517388 -44.811175) (xy 316.493402 -45.012551)
			(xy 316.461479 -45.212823) (xy 316.421669 -45.411677) (xy 316.374035 -45.608803) (xy 316.318649 -45.803894)
			(xy 316.255599 -45.996644) (xy 316.184984 -46.186753) (xy 316.106913 -46.373923) (xy 316.021509 -46.557863)
			(xy 315.928905 -46.738286) (xy 315.829245 -46.914909) (xy 315.722685 -47.087457) (xy 315.609391 -47.25566)
			(xy 315.489541 -47.419257) (xy 315.363321 -47.57799) (xy 315.230929 -47.731614) (xy 315.092571 -47.879887)
			(xy 314.948463 -48.022578) (xy 314.79883 -48.159464) (xy 314.643907 -48.290333) (xy 314.483934 -48.414978)
			(xy 314.319161 -48.533206) (xy 314.149847 -48.644833) (xy 313.976255 -48.749683) (xy 313.798655 -48.847593)
			(xy 313.617327 -48.938411) (xy 313.432552 -49.021994) (xy 313.244619 -49.098211) (xy 313.053822 -49.166945)
			(xy 312.860459 -49.228087) (xy 312.664831 -49.281543) (xy 312.467244 -49.327228) (xy 312.268006 -49.365072)
			(xy 312.067428 -49.395014) (xy 311.865825 -49.41701) (xy 311.663509 -49.431023) (xy 311.460798 -49.437033)
			(xy 311.258008 -49.435029) (xy 311.055456 -49.425016) (xy 310.853457 -49.407008) (xy 310.652327 -49.381034)
			(xy 310.45238 -49.347134) (xy 310.253929 -49.305362) (xy 310.057283 -49.255782) (xy 309.862749 -49.198471)
			(xy 309.670632 -49.133521) (xy 309.48123 -49.061031) (xy 309.29484 -48.981115) (xy 309.111752 -48.893898)
			(xy 308.932253 -48.799515) (xy 308.756623 -48.698115) (xy 308.585137 -48.589856) (xy 308.418061 -48.474906)
			(xy 308.255656 -48.353446) (xy 308.098177 -48.225664) (xy 307.945869 -48.09176) (xy 307.79897 -47.951944)
			(xy 307.65771 -47.806434) (xy 307.522308 -47.655456) (xy 307.392977 -47.499247) (xy 307.269918 -47.338051)
			(xy 307.153323 -47.172118) (xy 307.043375 -47.001709) (xy 306.940245 -46.82709) (xy 306.844094 -46.648532)
			(xy 306.755072 -46.466315) (xy 306.673319 -46.280724) (xy 306.598961 -46.092047) (xy 306.532116 -45.90058)
			(xy 306.472887 -45.706622) (xy 306.421366 -45.510476) (xy 306.377635 -45.312447) (xy 306.341762 -45.112845)
			(xy 306.313802 -44.911981) (xy 306.2938 -44.71017) (xy 306.281786 -44.507726) (xy 306.277779 -44.304966)
			(xy 304.755296 -44.304966) (xy 304.755296 -49.741074) (xy 304.755733 -49.751138) (xy 304.763466 -49.769724)
			(xy 304.770282 -49.777142) (xy 309.60314 -54.61) (xy 309.609993 -54.617396) (xy 309.617737 -54.635994)
			(xy 309.618126 -54.646068) (xy 309.618126 -54.75605) (xy 309.618564 -54.766082) (xy 309.62614 -54.784656)
			(xy 309.632858 -54.792118) (xy 309.67807 -54.83733) (xy 309.723056 -54.882972) (xy 309.808063 -54.978893)
			(xy 309.887123 -55.079772) (xy 309.959947 -55.18524) (xy 310.026271 -55.294913) (xy 310.085851 -55.40839)
			(xy 310.138471 -55.525258) (xy 310.183938 -55.64509) (xy 310.222087 -55.767449) (xy 310.252778 -55.891888)
			(xy 310.275899 -56.017953) (xy 310.291367 -56.145183) (xy 310.299124 -56.273116) (xy 310.299608 -56.3372)
			(xy 310.299608 -68.748402) (xy 310.300032 -68.758472) (xy 310.307748 -68.777075) (xy 310.314594 -68.78447)
			(xy 310.778144 -69.24802) (xy 310.785541 -69.254868) (xy 310.80414 -69.262599) (xy 310.814212 -69.263006)
		)
		(stroke
			(width 0)
			(type solid)
		)
		(fill yes)
		(layer "B.Cu")
		(net "GND")
	)
	(gr_poly
		(pts
			(xy 274.630896 -143.819626) (xy 274.640967 -143.819204) (xy 274.659575 -143.811494) (xy 274.666964 -143.80464)
			(xy 274.965922 -143.505682) (xy 274.972774 -143.498286) (xy 274.980514 -143.479687) (xy 274.980908 -143.469614)
			(xy 274.980908 -108.737908) (xy 273.873468 -107.630468) (xy 269.489936 -107.630468) (xy 269.439176 -107.629971)
			(xy 269.33798 -107.621868) (xy 269.237754 -107.605711) (xy 269.139139 -107.581604) (xy 269.042762 -107.5497)
			(xy 268.949241 -107.510203) (xy 268.859172 -107.463365) (xy 268.77313 -107.409485) (xy 268.691665 -107.348907)
			(xy 268.615296 -107.282019) (xy 268.544512 -107.209246) (xy 268.479764 -107.131054) (xy 268.421466 -107.047942)
			(xy 268.36999 -106.960441) (xy 268.325664 -106.869109) (xy 268.288772 -106.77453) (xy 268.25955 -106.677307)
			(xy 268.238183 -106.578061) (xy 268.224808 -106.477427) (xy 268.219512 -106.376045) (xy 268.222326 -106.274564)
			(xy 268.233234 -106.173632) (xy 268.252166 -106.073894) (xy 268.279001 -105.975985) (xy 268.313567 -105.880531)
			(xy 268.355645 -105.788142) (xy 268.404965 -105.699407) (xy 268.461212 -105.614894) (xy 268.524027 -105.535141)
			(xy 268.593009 -105.460658) (xy 268.667718 -105.391921) (xy 268.707362 -105.360216) (xy 272.061178 -102.0064)
			(xy 274.7772 -102.0064) (xy 274.838922 -101.944678) (xy 274.838922 -96.327722) (xy 274.654772 -96.143572)
			(xy 274.59825 -96.153292) (xy 274.484028 -96.163721) (xy 274.42668 -96.1644) (xy 274.426172 -96.1644)
			(xy 274.376294 -96.163909) (xy 274.276844 -96.15608) (xy 274.178316 -96.140473) (xy 274.081315 -96.117183)
			(xy 273.986441 -96.086355) (xy 273.894279 -96.048178) (xy 273.805395 -96.002888) (xy 273.720339 -95.950764)
			(xy 273.639635 -95.892127) (xy 273.56378 -95.827339) (xy 273.493242 -95.7568) (xy 273.428455 -95.680943)
			(xy 273.36982 -95.600238) (xy 273.317698 -95.51518) (xy 273.27241 -95.426296) (xy 273.234235 -95.334132)
			(xy 273.203409 -95.239258) (xy 273.180121 -95.142257) (xy 273.164516 -95.043728) (xy 273.156689 -94.944279)
			(xy 273.156172 -94.8944) (xy 273.156172 -94.644972) (xy 272.6182 -94.107) (xy 271.018 -94.107) (xy 270.985488 -94.074488)
			(xy 270.937224 -94.065837) (xy 270.84209 -94.042051) (xy 270.749074 -94.010999) (xy 270.658731 -93.972865)
			(xy 270.571597 -93.927877) (xy 270.488193 -93.876303) (xy 270.409015 -93.81845) (xy 270.334535 -93.754662)
			(xy 270.265196 -93.68532) (xy 270.201412 -93.610836) (xy 270.143562 -93.531655) (xy 270.091992 -93.448249)
			(xy 270.047008 -93.361113) (xy 270.008879 -93.270767) (xy 269.977831 -93.17775) (xy 269.95405 -93.082615)
			(xy 269.945358 -93.034358) (xy 269.524226 -92.613226) (xy 269.475215 -92.60802) (xy 269.378134 -92.590959)
			(xy 269.282669 -92.566423) (xy 269.189392 -92.534559) (xy 269.098867 -92.49556) (xy 269.011638 -92.449659)
			(xy 268.928231 -92.397134) (xy 268.849146 -92.3383) (xy 268.774861 -92.273512) (xy 268.705823 -92.20316)
			(xy 268.642447 -92.127667) (xy 268.585114 -92.047488) (xy 268.534171 -91.963105) (xy 268.489923 -91.875026)
			(xy 268.452636 -91.783782) (xy 268.422536 -91.689921) (xy 268.399804 -91.59401) (xy 268.384576 -91.496625)
			(xy 268.376945 -91.398352) (xy 268.3764 -91.349068) (xy 268.376925 -91.297368) (xy 268.385335 -91.194312)
			(xy 268.402098 -91.09228) (xy 268.427102 -90.991949) (xy 268.460182 -90.893984) (xy 268.501118 -90.799033)
			(xy 268.54964 -90.707726) (xy 268.605425 -90.620666) (xy 268.668106 -90.538431) (xy 268.737265 -90.461565)
			(xy 268.812446 -90.390577) (xy 268.893151 -90.325938) (xy 268.978844 -90.268076) (xy 269.068959 -90.217373)
			(xy 269.162898 -90.174166) (xy 269.26004 -90.138741) (xy 269.35974 -90.111332) (xy 269.410434 -90.101166)
			(xy 269.5702 -89.9414) (xy 274.7772 -89.9414) (xy 274.838922 -89.879678) (xy 274.838922 -85.079078)
			(xy 274.980908 -84.937092) (xy 274.980908 -61.31179) (xy 274.980484 -61.30172) (xy 274.972767 -61.283118)
			(xy 274.965922 -61.275722) (xy 263.958324 -50.268124) (xy 263.939782 -50.260504) (xy 263.929368 -50.260758)
			(xy 263.910064 -50.260758) (xy 263.842524 -50.260247) (xy 263.707689 -50.252089) (xy 263.573594 -50.235805)
			(xy 263.440726 -50.211454) (xy 263.30957 -50.179126) (xy 263.180606 -50.138938) (xy 263.054304 -50.091037)
			(xy 262.931124 -50.035597) (xy 262.811516 -49.972821) (xy 262.695917 -49.902939) (xy 262.584747 -49.826204)
			(xy 262.478414 -49.742897) (xy 262.377304 -49.653322) (xy 262.281788 -49.557806) (xy 262.192212 -49.456697)
			(xy 262.108904 -49.350364) (xy 262.032169 -49.239195) (xy 261.962286 -49.123596) (xy 261.899509 -49.003989)
			(xy 261.844069 -48.880809) (xy 261.796167 -48.754507) (xy 261.755978 -48.625543) (xy 261.723649 -48.494388)
			(xy 261.699297 -48.36152) (xy 261.683012 -48.227425) (xy 261.674854 -48.09259) (xy 261.674356 -48.02505)
			(xy 261.674356 -48.005746) (xy 261.67461 -47.98441) (xy 261.6708 -47.9806) (xy 261.6708 -46.172882)
			(xy 261.670373 -46.162813) (xy 261.662654 -46.144214) (xy 261.655814 -46.136814) (xy 261.355586 -45.836586)
			(xy 261.348191 -45.829732) (xy 261.329592 -45.82199) (xy 261.319518 -45.8216) (xy 257.856482 -45.8216)
			(xy 257.846413 -45.822027) (xy 257.827814 -45.829746) (xy 257.820414 -45.836586) (xy 257.393186 -46.263814)
			(xy 257.386332 -46.271209) (xy 257.37859 -46.289808) (xy 257.3782 -46.299882) (xy 257.3782 -53.825394)
			(xy 257.378432 -53.832663) (xy 257.382569 -53.846599) (xy 257.386328 -53.852826) (xy 257.451805 -53.955475)
			(xy 257.57687 -54.164411) (xy 257.695087 -54.377297) (xy 257.806332 -54.593907) (xy 257.910487 -54.814014)
			(xy 258.007444 -55.037386) (xy 258.097099 -55.263788) (xy 258.179357 -55.49298) (xy 258.254134 -55.724721)
			(xy 258.321349 -55.958767) (xy 258.380932 -56.194872) (xy 258.43282 -56.432786) (xy 258.476958 -56.672259)
			(xy 258.5133 -56.913038) (xy 258.541807 -57.154871) (xy 258.56245 -57.397501) (xy 258.575207 -57.640673)
			(xy 258.580064 -57.884131) (xy 258.577016 -58.127619) (xy 258.566067 -58.370879) (xy 258.547227 -58.613656)
			(xy 258.520517 -58.855694) (xy 258.485965 -59.096737) (xy 258.443608 -59.336531) (xy 258.393489 -59.574824)
			(xy 258.335662 -59.811365) (xy 258.270188 -60.045904) (xy 258.197136 -60.278195) (xy 258.116582 -60.507992)
			(xy 258.028612 -60.735053) (xy 257.933318 -60.959139) (xy 257.830801 -61.180014) (xy 257.721169 -61.397445)
			(xy 257.604537 -61.611203) (xy 257.481028 -61.821063) (xy 257.350773 -62.026803) (xy 257.213908 -62.228207)
			(xy 257.070578 -62.425062) (xy 256.920934 -62.617161) (xy 256.765133 -62.804302) (xy 256.603341 -62.986288)
			(xy 256.435726 -63.162926) (xy 256.262467 -63.33403) (xy 256.083745 -63.49942) (xy 255.899749 -63.658922)
			(xy 255.710672 -63.812368) (xy 255.516715 -63.959596) (xy 255.318081 -64.100451) (xy 255.11498 -64.234784)
			(xy 254.907626 -64.362454) (xy 254.696236 -64.483327) (xy 254.481035 -64.597274) (xy 254.262249 -64.704176)
			(xy 254.040108 -64.803921) (xy 253.814847 -64.896402) (xy 253.586702 -64.981524) (xy 253.355915 -65.059195)
			(xy 253.122729 -65.129334) (xy 252.887388 -65.191867) (xy 252.650142 -65.246729) (xy 252.41124 -65.293861)
			(xy 252.170935 -65.333214) (xy 251.929478 -65.364746) (xy 251.687125 -65.388424) (xy 251.444132 -65.404224)
			(xy 251.200753 -65.412127) (xy 251.079 -65.41262) (xy 245.453408 -65.41262) (xy 245.44342 -65.413156)
			(xy 245.424988 -65.42087) (xy 245.417594 -65.427606) (xy 244.362986 -66.482214) (xy 244.356132 -66.489609)
			(xy 244.34839 -66.508208) (xy 244.348 -66.518282) (xy 244.348 -70.148598) (xy 268.375965 -70.148598)
			(xy 268.381364 -70.047288) (xy 268.394828 -69.946732) (xy 268.416273 -69.847571) (xy 268.445561 -69.750437)
			(xy 268.482506 -69.655949) (xy 268.526872 -69.564711) (xy 268.578376 -69.477303) (xy 268.63669 -69.394283)
			(xy 268.701441 -69.31618) (xy 268.772218 -69.243493) (xy 268.848569 -69.176684) (xy 268.930006 -69.116181)
			(xy 269.016012 -69.062367) (xy 269.106037 -69.015588) (xy 269.199507 -68.97614) (xy 269.295827 -68.944276)
			(xy 269.394381 -68.920198) (xy 269.494543 -68.90406) (xy 269.595673 -68.895966) (xy 269.6464 -68.895468)
			(xy 269.697315 -68.89599) (xy 269.798818 -68.904153) (xy 269.899343 -68.92041) (xy 269.948914 -68.932044)
			(xy 269.93821 -68.872679) (xy 269.926764 -68.752586) (xy 269.926054 -68.692268) (xy 269.926631 -68.641544)
			(xy 269.934727 -68.54042) (xy 269.950867 -68.440264) (xy 269.974946 -68.341714) (xy 270.006811 -68.245401)
			(xy 270.046258 -68.151936) (xy 270.093038 -68.061918) (xy 270.14685 -67.975918) (xy 270.207353 -67.894486)
			(xy 270.274159 -67.818141) (xy 270.346844 -67.74737) (xy 270.424944 -67.682623) (xy 270.507961 -67.624314)
			(xy 270.595366 -67.572815) (xy 270.6866 -67.528454) (xy 270.781084 -67.491513) (xy 270.878213 -67.462228)
			(xy 270.977369 -67.440787) (xy 271.07792 -67.427325) (xy 271.179225 -67.421929) (xy 271.280637 -67.424632)
			(xy 271.38151 -67.435418) (xy 271.481201 -67.454218) (xy 271.579074 -67.480913) (xy 271.674505 -67.515331)
			(xy 271.766886 -67.557253) (xy 271.855627 -67.606412) (xy 271.940164 -67.662495) (xy 272.019956 -67.725144)
			(xy 272.094495 -67.79396) (xy 272.163306 -67.868504) (xy 272.22595 -67.9483) (xy 272.282028 -68.03284)
			(xy 272.331182 -68.121584) (xy 272.373099 -68.213968) (xy 272.407511 -68.309401) (xy 272.434199 -68.407275)
			(xy 272.452993 -68.506967) (xy 272.463773 -68.607841) (xy 272.46647 -68.709253) (xy 272.461068 -68.810557)
			(xy 272.4476 -68.911108) (xy 272.426152 -69.010262) (xy 272.396862 -69.10739) (xy 272.359915 -69.201871)
			(xy 272.315548 -69.293103) (xy 272.264043 -69.380504) (xy 272.20573 -69.463518) (xy 272.140978 -69.541614)
			(xy 272.070202 -69.614294) (xy 271.993853 -69.681096) (xy 271.912418 -69.741594) (xy 271.826415 -69.795401)
			(xy 271.736393 -69.842175) (xy 271.642926 -69.881617) (xy 271.546611 -69.913476) (xy 271.44806 -69.937549)
			(xy 271.347903 -69.953682) (xy 271.246778 -69.961772) (xy 271.196054 -69.962268) (xy 271.145139 -69.961754)
			(xy 271.043635 -69.953588) (xy 270.943111 -69.937328) (xy 270.89354 -69.925692) (xy 270.904234 -69.985059)
			(xy 270.915687 -70.10515) (xy 270.9164 -70.165468) (xy 270.915936 -70.216195) (xy 270.907844 -70.317325)
			(xy 270.891709 -70.417487) (xy 270.867633 -70.516043) (xy 270.835771 -70.612363) (xy 270.796326 -70.705834)
			(xy 270.749549 -70.79586) (xy 270.695737 -70.881867) (xy 270.635236 -70.963306) (xy 270.568429 -71.039659)
			(xy 270.495744 -71.110437) (xy 270.417643 -71.175191) (xy 270.334624 -71.233507) (xy 270.247217 -71.285013)
			(xy 270.15598 -71.329381) (xy 270.061493 -71.366328) (xy 269.96436 -71.395619) (xy 269.865199 -71.417066)
			(xy 269.764644 -71.430533) (xy 269.663334 -71.435935) (xy 269.561917 -71.433236) (xy 269.461038 -71.422453)
			(xy 269.361341 -71.403657) (xy 269.263461 -71.376966) (xy 269.168024 -71.34255) (xy 269.075636 -71.30063)
			(xy 268.986887 -71.251471) (xy 268.902344 -71.195389) (xy 268.822545 -71.13274) (xy 268.747999 -71.063924)
			(xy 268.679181 -70.98938) (xy 268.61653 -70.909582) (xy 268.560445 -70.82504) (xy 268.511285 -70.736293)
			(xy 268.469362 -70.643906) (xy 268.434944 -70.548469) (xy 268.40825 -70.45059) (xy 268.389451 -70.350894)
			(xy 268.378667 -70.250015) (xy 268.375965 -70.148598) (xy 244.348 -70.148598) (xy 244.348 -82.213598)
			(xy 268.375965 -82.213598) (xy 268.381364 -82.112288) (xy 268.394828 -82.011732) (xy 268.416273 -81.912571)
			(xy 268.445561 -81.815437) (xy 268.482506 -81.720949) (xy 268.526872 -81.629711) (xy 268.578376 -81.542303)
			(xy 268.63669 -81.459283) (xy 268.701441 -81.38118) (xy 268.772218 -81.308493) (xy 268.848569 -81.241684)
			(xy 268.930006 -81.181181) (xy 269.016012 -81.127367) (xy 269.106037 -81.080588) (xy 269.199507 -81.04114)
			(xy 269.295827 -81.009276) (xy 269.394381 -80.985198) (xy 269.494543 -80.96906) (xy 269.595673 -80.960966)
			(xy 269.6464 -80.960468) (xy 269.647162 -80.960468) (xy 269.696947 -80.960954) (xy 269.796208 -80.968782)
			(xy 269.89455 -80.984369) (xy 269.943072 -80.99552) (xy 269.932488 -80.936527) (xy 269.92117 -80.817199)
			(xy 269.920466 -80.757268) (xy 269.921031 -80.706544) (xy 269.929127 -80.60542) (xy 269.945267 -80.505264)
			(xy 269.969345 -80.406715) (xy 270.00121 -80.310402) (xy 270.040658 -80.216937) (xy 270.087437 -80.126919)
			(xy 270.141249 -80.040919) (xy 270.201752 -79.959487) (xy 270.268558 -79.883142) (xy 270.341243 -79.812371)
			(xy 270.419343 -79.747625) (xy 270.502359 -79.689316) (xy 270.589763 -79.637816) (xy 270.680998 -79.593455)
			(xy 270.775481 -79.556514) (xy 270.87261 -79.527229) (xy 270.971766 -79.505787) (xy 271.072316 -79.492325)
			(xy 271.173621 -79.486929) (xy 271.275033 -79.489632) (xy 271.375905 -79.500418) (xy 271.475596 -79.519217)
			(xy 271.573469 -79.545911) (xy 271.6689 -79.580329) (xy 271.761281 -79.622251) (xy 271.850023 -79.671409)
			(xy 271.934559 -79.727492) (xy 272.014351 -79.790141) (xy 272.088891 -79.858956) (xy 272.157702 -79.933499)
			(xy 272.220347 -80.013294) (xy 272.276425 -80.097834) (xy 272.325579 -80.186578) (xy 272.367496 -80.278961)
			(xy 272.401909 -80.374394) (xy 272.428597 -80.472268) (xy 272.447392 -80.57196) (xy 272.458173 -80.672833)
			(xy 272.46087 -80.774245) (xy 272.455469 -80.875549) (xy 272.442001 -80.976099) (xy 272.420554 -81.075254)
			(xy 272.391265 -81.172382) (xy 272.354319 -81.266863) (xy 272.309952 -81.358095) (xy 272.258449 -81.445496)
			(xy 272.200135 -81.52851) (xy 272.135385 -81.606606) (xy 272.06461 -81.679287) (xy 271.988261 -81.74609)
			(xy 271.906826 -81.806588) (xy 271.820824 -81.860396) (xy 271.730803 -81.90717) (xy 271.637337 -81.946613)
			(xy 271.541021 -81.978473) (xy 271.442471 -82.002546) (xy 271.342315 -82.01868) (xy 271.24119 -82.026772)
			(xy 271.190466 -82.027268) (xy 271.189704 -82.027268) (xy 271.13992 -82.026769) (xy 271.040659 -82.018946)
			(xy 270.942317 -82.003364) (xy 270.893794 -81.992216) (xy 270.904369 -82.051211) (xy 270.915693 -82.170537)
			(xy 270.9164 -82.230468) (xy 270.915936 -82.281195) (xy 270.907844 -82.382325) (xy 270.891709 -82.482487)
			(xy 270.867633 -82.581043) (xy 270.835771 -82.677363) (xy 270.796326 -82.770834) (xy 270.749549 -82.86086)
			(xy 270.695737 -82.946867) (xy 270.635236 -83.028306) (xy 270.568429 -83.104659) (xy 270.495744 -83.175437)
			(xy 270.417643 -83.240191) (xy 270.334624 -83.298507) (xy 270.247217 -83.350013) (xy 270.15598 -83.394381)
			(xy 270.061493 -83.431328) (xy 269.96436 -83.460619) (xy 269.865199 -83.482066) (xy 269.764644 -83.495533)
			(xy 269.663334 -83.500935) (xy 269.561917 -83.498236) (xy 269.461038 -83.487453) (xy 269.361341 -83.468657)
			(xy 269.263461 -83.441966) (xy 269.168024 -83.40755) (xy 269.075636 -83.36563) (xy 268.986887 -83.316471)
			(xy 268.902344 -83.260389) (xy 268.822545 -83.19774) (xy 268.747999 -83.128924) (xy 268.679181 -83.05438)
			(xy 268.61653 -82.974582) (xy 268.560445 -82.89004) (xy 268.511285 -82.801293) (xy 268.469362 -82.708906)
			(xy 268.434944 -82.613469) (xy 268.40825 -82.51559) (xy 268.389451 -82.415894) (xy 268.378667 -82.315015)
			(xy 268.375965 -82.213598) (xy 244.348 -82.213598) (xy 244.348 -95.362776) (xy 244.337078 -95.387922)
			(xy 243.3828 -96.3422) (xy 212.84692 -96.3422) (xy 211.627212 -97.561908) (xy 197.104 -97.561908)
			(xy 196.088 -98.577908) (xy 196.088 -114.681) (xy 196.596 -115.189) (xy 223.549718 -115.189) (xy 223.559787 -115.189427)
			(xy 223.578386 -115.197146) (xy 223.585786 -115.203986) (xy 224.267014 -115.885214) (xy 224.273868 -115.892609)
			(xy 224.28161 -115.911208) (xy 224.282 -115.921282) (xy 224.282 -118.408598) (xy 268.375965 -118.408598)
			(xy 268.381364 -118.307288) (xy 268.394828 -118.206732) (xy 268.416273 -118.107571) (xy 268.445561 -118.010437)
			(xy 268.482506 -117.915949) (xy 268.526872 -117.824711) (xy 268.578376 -117.737303) (xy 268.63669 -117.654283)
			(xy 268.701441 -117.57618) (xy 268.772218 -117.503493) (xy 268.848569 -117.436684) (xy 268.930006 -117.376181)
			(xy 269.016012 -117.322367) (xy 269.106037 -117.275588) (xy 269.199507 -117.23614) (xy 269.295827 -117.204276)
			(xy 269.394381 -117.180198) (xy 269.494543 -117.16406) (xy 269.595673 -117.155966) (xy 269.6464 -117.155468)
			(xy 269.647416 -117.155468) (xy 269.700342 -117.156033) (xy 269.805824 -117.164898) (xy 269.910203 -117.182505)
			(xy 269.961614 -117.195092) (xy 269.952651 -117.151383) (xy 269.940127 -117.063034) (xy 269.933828 -116.974024)
			(xy 269.93342 -116.929408) (xy 269.933889 -116.878683) (xy 269.941983 -116.777555) (xy 269.958119 -116.677396)
			(xy 269.982196 -116.578843) (xy 270.014058 -116.482526) (xy 270.053504 -116.389058) (xy 270.100282 -116.299035)
			(xy 270.154093 -116.213031) (xy 270.214594 -116.131595) (xy 270.2814 -116.055246) (xy 270.354085 -115.98447)
			(xy 270.432184 -115.919719) (xy 270.515201 -115.861405) (xy 270.602606 -115.809902) (xy 270.693842 -115.765536)
			(xy 270.788326 -115.72859) (xy 270.885457 -115.699301) (xy 270.984615 -115.677856) (xy 271.085169 -115.66439)
			(xy 271.186476 -115.658989) (xy 271.28789 -115.661689) (xy 271.388767 -115.672472) (xy 271.488461 -115.691268)
			(xy 271.586338 -115.717959) (xy 271.681773 -115.752374) (xy 271.774158 -115.794294) (xy 271.862904 -115.843451)
			(xy 271.947445 -115.899532) (xy 272.027242 -115.96218) (xy 272.101786 -116.030994) (xy 272.170602 -116.105537)
			(xy 272.233251 -116.185333) (xy 272.289334 -116.269872) (xy 272.338493 -116.358617) (xy 272.380415 -116.451001)
			(xy 272.414832 -116.546436) (xy 272.441525 -116.644312) (xy 272.460324 -116.744006) (xy 272.471109 -116.844882)
			(xy 272.473811 -116.946296) (xy 272.468413 -117.047604) (xy 272.454949 -117.148157) (xy 272.433506 -117.247316)
			(xy 272.404219 -117.344447) (xy 272.367276 -117.438933) (xy 272.322912 -117.530169) (xy 272.27141 -117.617575)
			(xy 272.213098 -117.700593) (xy 272.148349 -117.778695) (xy 272.077575 -117.851381) (xy 272.001227 -117.918188)
			(xy 271.919792 -117.978691) (xy 271.833789 -118.032504) (xy 271.743767 -118.079284) (xy 271.6503 -118.118732)
			(xy 271.553984 -118.150597) (xy 271.455432 -118.174675) (xy 271.355273 -118.190814) (xy 271.254145 -118.19891)
			(xy 271.20342 -118.199408) (xy 271.202404 -118.199408) (xy 271.149478 -118.198839) (xy 271.043996 -118.189977)
			(xy 270.939617 -118.172371) (xy 270.888206 -118.159784) (xy 270.897165 -118.203493) (xy 270.909691 -118.291842)
			(xy 270.915992 -118.380852) (xy 270.9164 -118.425468) (xy 270.915936 -118.476195) (xy 270.907844 -118.577325)
			(xy 270.891709 -118.677487) (xy 270.867633 -118.776043) (xy 270.835771 -118.872363) (xy 270.796326 -118.965834)
			(xy 270.749549 -119.05586) (xy 270.695737 -119.141867) (xy 270.635236 -119.223306) (xy 270.568429 -119.299659)
			(xy 270.495744 -119.370437) (xy 270.417643 -119.435191) (xy 270.334624 -119.493507) (xy 270.247217 -119.545013)
			(xy 270.15598 -119.589381) (xy 270.061493 -119.626328) (xy 269.96436 -119.655619) (xy 269.865199 -119.677066)
			(xy 269.764644 -119.690533) (xy 269.663334 -119.695935) (xy 269.561917 -119.693236) (xy 269.461038 -119.682453)
			(xy 269.361341 -119.663657) (xy 269.263461 -119.636966) (xy 269.168024 -119.60255) (xy 269.075636 -119.56063)
			(xy 268.986887 -119.511471) (xy 268.902344 -119.455389) (xy 268.822545 -119.39274) (xy 268.747999 -119.323924)
			(xy 268.679181 -119.24938) (xy 268.61653 -119.169582) (xy 268.560445 -119.08504) (xy 268.511285 -118.996293)
			(xy 268.469362 -118.903906) (xy 268.434944 -118.808469) (xy 268.40825 -118.71059) (xy 268.389451 -118.610894)
			(xy 268.378667 -118.510015) (xy 268.375965 -118.408598) (xy 224.282 -118.408598) (xy 224.282 -134.344918)
			(xy 224.282427 -134.354987) (xy 224.290146 -134.373586) (xy 224.296986 -134.380986) (xy 224.902014 -134.986014)
			(xy 224.909409 -134.992868) (xy 224.928008 -135.00061) (xy 224.938082 -135.001) (xy 231.753918 -135.001)
			(xy 231.763987 -135.000573) (xy 231.782586 -134.992854) (xy 231.789986 -134.986014) (xy 236.586014 -130.189986)
			(xy 236.593409 -130.183132) (xy 236.612008 -130.17539) (xy 236.622082 -130.175) (xy 265.027918 -130.175)
			(xy 265.037987 -130.175427) (xy 265.056586 -130.183146) (xy 265.063986 -130.189986) (xy 265.347598 -130.473598)
			(xy 268.375965 -130.473598) (xy 268.381364 -130.372288) (xy 268.394828 -130.271732) (xy 268.416273 -130.172571)
			(xy 268.445561 -130.075437) (xy 268.482506 -129.980949) (xy 268.526872 -129.889711) (xy 268.578376 -129.802303)
			(xy 268.63669 -129.719283) (xy 268.701441 -129.64118) (xy 268.772218 -129.568493) (xy 268.848569 -129.501684)
			(xy 268.930006 -129.441181) (xy 269.016012 -129.387367) (xy 269.106037 -129.340588) (xy 269.199507 -129.30114)
			(xy 269.295827 -129.269276) (xy 269.394381 -129.245198) (xy 269.494543 -129.22906) (xy 269.595673 -129.220966)
			(xy 269.6464 -129.220468) (xy 269.646908 -129.220468) (xy 269.693391 -129.220894) (xy 269.786107 -129.227703)
			(xy 269.878077 -129.241278) (xy 269.968807 -129.261544) (xy 270.01343 -129.27457) (xy 269.998964 -129.219615)
			(xy 269.978743 -129.107782) (xy 269.968593 -128.994589) (xy 269.967964 -128.937766) (xy 269.968533 -128.887042)
			(xy 269.97663 -128.785918) (xy 269.992769 -128.685762) (xy 270.016848 -128.587214) (xy 270.048713 -128.4909)
			(xy 270.088161 -128.397437) (xy 270.13494 -128.307418) (xy 270.188752 -128.221419) (xy 270.249254 -128.139987)
			(xy 270.316061 -128.063642) (xy 270.388746 -127.992871) (xy 270.466845 -127.928125) (xy 270.549862 -127.869816)
			(xy 270.637266 -127.818317) (xy 270.7285 -127.773956) (xy 270.822983 -127.737015) (xy 270.920112 -127.707731)
			(xy 271.019268 -127.686289) (xy 271.119819 -127.672827) (xy 271.221123 -127.667431) (xy 271.322534 -127.670134)
			(xy 271.423407 -127.68092) (xy 271.523098 -127.69972) (xy 271.62097 -127.726414) (xy 271.716401 -127.760831)
			(xy 271.808782 -127.802753) (xy 271.897523 -127.851912) (xy 271.982059 -127.907995) (xy 272.061852 -127.970643)
			(xy 272.136391 -128.039459) (xy 272.205202 -128.114002) (xy 272.267846 -128.193797) (xy 272.323924 -128.278337)
			(xy 272.373078 -128.367081) (xy 272.414995 -128.459464) (xy 272.449407 -128.554896) (xy 272.476096 -128.652771)
			(xy 272.49489 -128.752462) (xy 272.505671 -128.853335) (xy 272.508368 -128.954747) (xy 272.502966 -129.056051)
			(xy 272.489499 -129.156601) (xy 272.468052 -129.255756) (xy 272.438762 -129.352883) (xy 272.401816 -129.447364)
			(xy 272.35745 -129.538596) (xy 272.305946 -129.625997) (xy 272.247633 -129.70901) (xy 272.182882 -129.787106)
			(xy 272.112107 -129.859787) (xy 272.035758 -129.92659) (xy 271.954323 -129.987087) (xy 271.868321 -130.040895)
			(xy 271.7783 -130.087669) (xy 271.684834 -130.127112) (xy 271.588519 -130.158971) (xy 271.489969 -130.183045)
			(xy 271.389812 -130.199179) (xy 271.288688 -130.20727) (xy 271.237964 -130.207766) (xy 271.237456 -130.207766)
			(xy 271.190973 -130.207351) (xy 271.098256 -130.200539) (xy 271.006286 -130.186961) (xy 270.915556 -130.166691)
			(xy 270.870934 -130.153664) (xy 270.885385 -130.208622) (xy 270.905612 -130.320454) (xy 270.915768 -130.433645)
			(xy 270.9164 -130.490468) (xy 270.915936 -130.541195) (xy 270.907844 -130.642325) (xy 270.891709 -130.742487)
			(xy 270.867633 -130.841043) (xy 270.835771 -130.937363) (xy 270.796326 -131.030834) (xy 270.749549 -131.12086)
			(xy 270.695737 -131.206867) (xy 270.635236 -131.288306) (xy 270.568429 -131.364659) (xy 270.495744 -131.435437)
			(xy 270.417643 -131.500191) (xy 270.334624 -131.558507) (xy 270.247217 -131.610013) (xy 270.15598 -131.654381)
			(xy 270.061493 -131.691328) (xy 269.96436 -131.720619) (xy 269.865199 -131.742066) (xy 269.764644 -131.755533)
			(xy 269.663334 -131.760935) (xy 269.561917 -131.758236) (xy 269.461038 -131.747453) (xy 269.361341 -131.728657)
			(xy 269.263461 -131.701966) (xy 269.168024 -131.66755) (xy 269.075636 -131.62563) (xy 268.986887 -131.576471)
			(xy 268.902344 -131.520389) (xy 268.822545 -131.45774) (xy 268.747999 -131.388924) (xy 268.679181 -131.31438)
			(xy 268.61653 -131.234582) (xy 268.560445 -131.15004) (xy 268.511285 -131.061293) (xy 268.469362 -130.968906)
			(xy 268.434944 -130.873469) (xy 268.40825 -130.77559) (xy 268.389451 -130.675894) (xy 268.378667 -130.575015)
			(xy 268.375965 -130.473598) (xy 265.347598 -130.473598) (xy 269.352014 -134.478014) (xy 269.358868 -134.485409)
			(xy 269.36661 -134.504008) (xy 269.367 -134.514082) (xy 269.367 -143.179038) (xy 269.36743 -143.189105)
			(xy 269.375154 -143.207699) (xy 269.381986 -143.215106) (xy 269.97152 -143.80464) (xy 269.978917 -143.81149)
			(xy 269.997515 -143.819226) (xy 270.007588 -143.819626)
		)
		(stroke
			(width 0)
			(type solid)
		)
		(fill yes)
		(layer "B.Cu")
		(net "P52V_HS")
	)
	(gr_poly
		(pts
			(xy 42.3926 -65.659) (xy 61.065918 -65.659) (xy 61.075987 -65.659427) (xy 61.094586 -65.667146) (xy 61.101986 -65.673986)
			(xy 61.148214 -65.720214) (xy 61.155609 -65.727068) (xy 61.174208 -65.73481) (xy 61.184282 -65.7352)
			(xy 62.208918 -65.7352) (xy 62.218987 -65.734773) (xy 62.237586 -65.727054) (xy 62.244986 -65.720214)
			(xy 62.951106 -65.014094) (xy 62.957951 -65.006695) (xy 62.965682 -64.988097) (xy 62.966092 -64.978026)
			(xy 62.966092 -43.79595) (xy 62.966503 -43.786672) (xy 62.973156 -43.76935) (xy 62.979046 -43.762168)
			(xy 62.986158 -43.754294) (xy 62.98946 -43.744388) (xy 62.990619 -43.740553) (xy 62.991893 -43.732645)
			(xy 62.992 -43.72864) (xy 62.992 -42.921682) (xy 62.992427 -42.911613) (xy 63.000146 -42.893014)
			(xy 63.006986 -42.885614) (xy 64.247014 -41.645586) (xy 64.254409 -41.638732) (xy 64.273008 -41.63099)
			(xy 64.283082 -41.6306) (xy 96.204532 -41.6306) (xy 96.2146 -41.630171) (xy 96.233196 -41.622448)
			(xy 96.2406 -41.615614) (xy 96.784414 -41.0718) (xy 96.79127 -41.064406) (xy 96.799018 -41.045807)
			(xy 96.7994 -41.035732) (xy 96.7994 -2.840482) (xy 96.798973 -2.830413) (xy 96.791254 -2.811814)
			(xy 96.784414 -2.804414) (xy 95.493586 -1.513586) (xy 95.486191 -1.506732) (xy 95.467592 -1.49899)
			(xy 95.457518 -1.4986) (xy 4.313682 -1.4986) (xy 4.303613 -1.499027) (xy 4.285014 -1.506746) (xy 4.277614 -1.513586)
			(xy 1.767586 -4.023614) (xy 1.760732 -4.031009) (xy 1.75299 -4.049608) (xy 1.7526 -4.059682) (xy 1.7526 -7.525512)
			(xy 1.753073 -7.536192) (xy 1.761769 -7.555703) (xy 1.777651 -7.569988) (xy 1.787652 -7.573772) (xy 1.8796 -7.60349)
			(xy 1.891334 -7.606544) (xy 1.915217 -7.602572) (xy 1.92532 -7.59587) (xy 1.931416 -7.591552) (xy 1.936242 -7.585202)
			(xy 1.936496 -7.584694) (xy 2.008562 -7.486566) (xy 2.158213 -7.294488) (xy 2.31402 -7.107368) (xy 2.475817 -6.925403)
			(xy 2.643435 -6.748786) (xy 2.816697 -6.577701) (xy 2.99542 -6.41233) (xy 3.179416 -6.252847) (xy 3.368492 -6.09942)
			(xy 3.562447 -5.952209) (xy 3.761078 -5.811372) (xy 3.964175 -5.677055) (xy 4.171525 -5.5494) (xy 4.382908 -5.428542)
			(xy 4.598103 -5.314609) (xy 4.816882 -5.20772) (xy 5.039015 -5.107987) (xy 5.264267 -5.015517) (xy 5.492402 -4.930406)
			(xy 5.72318 -4.852744) (xy 5.956356 -4.782613) (xy 6.191685 -4.720086) (xy 6.42892 -4.665231) (xy 6.66781 -4.618104)
			(xy 6.908104 -4.578755) (xy 7.149549 -4.547225) (xy 7.391889 -4.523549) (xy 7.634871 -4.50775) (xy 7.878237 -4.499845)
			(xy 7.999984 -4.499356) (xy 30.000194 -4.499356) (xy 30.122889 -4.499858) (xy 30.368148 -4.507886)
			(xy 30.613013 -4.523932) (xy 30.857221 -4.547979) (xy 31.100513 -4.58) (xy 31.342627 -4.619963) (xy 31.583305 -4.667823)
			(xy 31.822288 -4.72353) (xy 32.059321 -4.787024) (xy 32.294151 -4.858237) (xy 32.526525 -4.937094)
			(xy 32.756196 -5.023509) (xy 32.982918 -5.11739) (xy 33.206447 -5.218636) (xy 33.426545 -5.32714)
			(xy 33.642976 -5.442785) (xy 33.855509 -5.565448) (xy 34.063916 -5.694997) (xy 34.267974 -5.831293)
			(xy 34.467465 -5.97419) (xy 34.662174 -6.123537) (xy 34.851895 -6.279172) (xy 35.036423 -6.44093)
			(xy 35.215562 -6.608637) (xy 35.267726 -6.660777) (xy 51.968134 -6.660777) (xy 51.968134 -6.547223)
			(xy 51.976055 -6.433947) (xy 51.991858 -6.321499) (xy 52.015467 -6.210428) (xy 52.046767 -6.101273)
			(xy 52.085604 -5.994568) (xy 52.13179 -5.890833) (xy 52.1851 -5.790571) (xy 52.245274 -5.694273)
			(xy 52.312019 -5.602407) (xy 52.385009 -5.51542) (xy 52.46389 -5.433737) (xy 52.548276 -5.357755)
			(xy 52.637757 -5.287845) (xy 52.731897 -5.224347) (xy 52.830237 -5.16757) (xy 52.932297 -5.117792)
			(xy 53.037582 -5.075254) (xy 53.145577 -5.040164) (xy 53.255757 -5.012693) (xy 53.367585 -4.992975)
			(xy 53.480516 -4.981105) (xy 53.594 -4.977143) (xy 53.707484 -4.981105) (xy 53.820415 -4.992975)
			(xy 53.932243 -5.012693) (xy 54.042423 -5.040164) (xy 54.150418 -5.075254) (xy 54.255703 -5.117792)
			(xy 54.357763 -5.16757) (xy 54.456103 -5.224347) (xy 54.550243 -5.287845) (xy 54.639724 -5.357755)
			(xy 54.72411 -5.433737) (xy 54.802991 -5.51542) (xy 54.875981 -5.602407) (xy 54.942726 -5.694273)
			(xy 55.0029 -5.790571) (xy 55.05621 -5.890833) (xy 55.102396 -5.994568) (xy 55.141233 -6.101273)
			(xy 55.172533 -6.210428) (xy 55.196142 -6.321499) (xy 55.211945 -6.433947) (xy 55.219866 -6.547223)
			(xy 55.220362 -6.604) (xy 55.219866 -6.660777) (xy 55.211945 -6.774053) (xy 55.196142 -6.886501)
			(xy 55.172533 -6.997572) (xy 55.141233 -7.106727) (xy 55.102396 -7.213432) (xy 55.05621 -7.317167)
			(xy 55.0029 -7.417429) (xy 54.942726 -7.513727) (xy 54.875981 -7.605593) (xy 54.802991 -7.69258)
			(xy 54.72411 -7.774263) (xy 54.639724 -7.850245) (xy 54.550243 -7.920155) (xy 54.456103 -7.983653)
			(xy 54.357763 -8.04043) (xy 54.255703 -8.090208) (xy 54.150418 -8.132746) (xy 54.042423 -8.167836)
			(xy 53.932243 -8.195307) (xy 53.820415 -8.215025) (xy 53.707484 -8.226895) (xy 53.594 -8.230858)
			(xy 53.480516 -8.226895) (xy 53.367585 -8.215025) (xy 53.255757 -8.195307) (xy 53.145577 -8.167836)
			(xy 53.037582 -8.132746) (xy 52.932297 -8.090208) (xy 52.830237 -8.04043) (xy 52.731897 -7.983653)
			(xy 52.637757 -7.920155) (xy 52.548276 -7.850245) (xy 52.46389 -7.774263) (xy 52.385009 -7.69258)
			(xy 52.312019 -7.605593) (xy 52.245274 -7.513727) (xy 52.1851 -7.417429) (xy 52.13179 -7.317167)
			(xy 52.085604 -7.213432) (xy 52.046767 -7.106727) (xy 52.015467 -6.997572) (xy 51.991858 -6.886501)
			(xy 51.976055 -6.774053) (xy 51.968134 -6.660777) (xy 35.267726 -6.660777) (xy 35.389119 -6.782113)
			(xy 35.556909 -6.961174) (xy 35.718753 -7.145627) (xy 35.874476 -7.335276) (xy 36.023913 -7.529916)
			(xy 36.166904 -7.72934) (xy 36.303294 -7.933335) (xy 36.43294 -8.141681) (xy 36.555701 -8.354157)
			(xy 36.671447 -8.570534) (xy 36.780053 -8.790582) (xy 36.881404 -9.014064) (xy 36.97539 -9.240742)
			(xy 37.061912 -9.470373) (xy 37.140876 -9.702711) (xy 37.212198 -9.937507) (xy 37.275803 -10.174511)
			(xy 37.331621 -10.413468) (xy 37.379593 -10.654123) (xy 37.419668 -10.896219) (xy 37.451802 -11.139496)
			(xy 37.475962 -11.383694) (xy 37.492122 -11.628551) (xy 37.500264 -11.873806) (xy 37.500379 -12.119196)
			(xy 37.492468 -12.364458) (xy 37.476539 -12.609331) (xy 37.452609 -12.853551) (xy 37.420703 -13.096858)
			(xy 37.380856 -13.338991) (xy 37.333111 -13.579692) (xy 37.277517 -13.818701) (xy 37.214136 -14.055765)
			(xy 37.143035 -14.290628) (xy 37.064289 -14.52304) (xy 36.977984 -14.752752) (xy 36.884211 -14.979519)
			(xy 36.78307 -15.203096) (xy 36.674671 -15.423246) (xy 36.559129 -15.639732) (xy 36.436568 -15.852323)
			(xy 36.307119 -16.060792) (xy 36.17092 -16.264915) (xy 36.028117 -16.464473) (xy 35.878863 -16.659254)
			(xy 35.723319 -16.849049) (xy 35.561649 -17.033654) (xy 35.394027 -17.212873) (xy 35.220633 -17.386513)
			(xy 35.041653 -17.554388) (xy 34.857277 -17.716319) (xy 34.667702 -17.872133) (xy 34.473133 -18.021663)
			(xy 34.273777 -18.164748) (xy 34.069848 -18.301236) (xy 33.861563 -18.430981) (xy 33.649146 -18.553843)
			(xy 33.432823 -18.669692) (xy 33.212828 -18.778403) (xy 32.989394 -18.87986) (xy 32.762761 -18.973955)
			(xy 32.648144 -19.017742) (xy 32.639508 -19.021806) (xy 32.634903 -19.024782) (xy 32.626964 -19.032342)
			(xy 32.62376 -19.036792) (xy 32.6136 -19.052032) (xy 32.6136 -25.59157) (xy 42.354235 -25.59157)
			(xy 42.354235 -25.46243) (xy 42.362185 -25.333535) (xy 42.378055 -25.205375) (xy 42.401784 -25.078434)
			(xy 42.433283 -24.953195) (xy 42.472432 -24.830132) (xy 42.519083 -24.709713) (xy 42.573058 -24.592394)
			(xy 42.634153 -24.47862) (xy 42.702136 -24.368823) (xy 42.77675 -24.26342) (xy 42.857711 -24.16281)
			(xy 42.944711 -24.067375) (xy 43.037422 -23.977476) (xy 43.135492 -23.893455) (xy 43.238547 -23.815631)
			(xy 43.346198 -23.744299) (xy 43.458037 -23.679729) (xy 43.573638 -23.622167) (xy 43.692563 -23.57183)
			(xy 43.814362 -23.52891) (xy 43.938572 -23.493569) (xy 44.064721 -23.465942) (xy 44.192333 -23.446133)
			(xy 44.320922 -23.434217) (xy 44.45 -23.430241) (xy 44.579078 -23.434217) (xy 44.707667 -23.446133)
			(xy 44.835279 -23.465942) (xy 44.961428 -23.493569) (xy 45.085638 -23.52891) (xy 45.207437 -23.57183)
			(xy 45.326362 -23.622167) (xy 45.441963 -23.679729) (xy 45.553802 -23.744299) (xy 45.661453 -23.815631)
			(xy 45.764508 -23.893455) (xy 45.862578 -23.977476) (xy 45.955289 -24.067375) (xy 46.042289 -24.16281)
			(xy 46.12325 -24.26342) (xy 46.197864 -24.368823) (xy 46.265847 -24.47862) (xy 46.326942 -24.592394)
			(xy 46.380917 -24.709713) (xy 46.427568 -24.830132) (xy 46.466717 -24.953195) (xy 46.498216 -25.078434)
			(xy 46.521945 -25.205375) (xy 46.537815 -25.333535) (xy 46.545765 -25.46243) (xy 46.546262 -25.527)
			(xy 46.545765 -25.59157) (xy 46.537815 -25.720465) (xy 46.521945 -25.848625) (xy 46.498216 -25.975566)
			(xy 46.466717 -26.100805) (xy 46.427568 -26.223868) (xy 46.380917 -26.344287) (xy 46.326942 -26.461606)
			(xy 46.265847 -26.57538) (xy 46.197864 -26.685177) (xy 46.12325 -26.79058) (xy 46.042289 -26.89119)
			(xy 45.955289 -26.986625) (xy 45.862578 -27.076524) (xy 45.764508 -27.160545) (xy 45.661453 -27.238369)
			(xy 45.553802 -27.309701) (xy 45.441963 -27.374271) (xy 45.326362 -27.431833) (xy 45.207437 -27.48217)
			(xy 45.085638 -27.52509) (xy 44.961428 -27.560431) (xy 44.835279 -27.588058) (xy 44.707667 -27.607867)
			(xy 44.579078 -27.619783) (xy 44.45 -27.62376) (xy 44.320922 -27.619783) (xy 44.192333 -27.607867)
			(xy 44.064721 -27.588058) (xy 43.938572 -27.560431) (xy 43.814362 -27.52509) (xy 43.692563 -27.48217)
			(xy 43.573638 -27.431833) (xy 43.458037 -27.374271) (xy 43.346198 -27.309701) (xy 43.238547 -27.238369)
			(xy 43.135492 -27.160545) (xy 43.037422 -27.076524) (xy 42.944711 -26.986625) (xy 42.857711 -26.89119)
			(xy 42.77675 -26.79058) (xy 42.702136 -26.685177) (xy 42.634153 -26.57538) (xy 42.573058 -26.461606)
			(xy 42.519083 -26.344287) (xy 42.472432 -26.223868) (xy 42.433283 -26.100805) (xy 42.401784 -25.975566)
			(xy 42.378055 -25.848625) (xy 42.362185 -25.720465) (xy 42.354235 -25.59157) (xy 32.6136 -25.59157)
			(xy 32.6136 -31.557976) (xy 32.6009 -31.570676) (xy 12.248642 -31.570676) (xy 11.9634 -31.855918)
			(xy 11.962973 -31.865987) (xy 11.955254 -31.884586) (xy 11.948414 -31.891986) (xy 10.815232 -33.025168)
			(xy 59.677545 -33.025168) (xy 59.677545 -32.854812) (xy 59.68553 -32.684644) (xy 59.701482 -32.515037)
			(xy 59.725367 -32.346365) (xy 59.757131 -32.178997) (xy 59.796706 -32.013302) (xy 59.844003 -31.849644)
			(xy 59.89892 -31.688383) (xy 59.961335 -31.529873) (xy 60.031111 -31.374463) (xy 60.108094 -31.222495)
			(xy 60.192116 -31.074301) (xy 60.282992 -30.930209) (xy 60.380522 -30.790535) (xy 60.484492 -30.655586)
			(xy 60.594673 -30.525658) (xy 60.710822 -30.401038) (xy 60.832686 -30.281999) (xy 60.959994 -30.168803)
			(xy 61.092469 -30.061698) (xy 61.229819 -29.960921) (xy 61.371741 -29.866692) (xy 61.517923 -29.779219)
			(xy 61.668046 -29.698694) (xy 61.821777 -29.625294) (xy 61.97878 -29.55918) (xy 62.13871 -29.500498)
			(xy 62.301214 -29.449377) (xy 62.465935 -29.405929) (xy 62.632513 -29.37025) (xy 62.800579 -29.342418)
			(xy 62.969765 -29.322494) (xy 63.139699 -29.310522) (xy 63.310008 -29.306529) (xy 63.480317 -29.310522)
			(xy 63.650251 -29.322494) (xy 63.819437 -29.342418) (xy 63.987503 -29.37025) (xy 64.154081 -29.405929)
			(xy 64.318802 -29.449377) (xy 64.481306 -29.500498) (xy 64.641236 -29.55918) (xy 64.798239 -29.625294)
			(xy 64.95197 -29.698694) (xy 65.102093 -29.779219) (xy 65.248275 -29.866692) (xy 65.390197 -29.960921)
			(xy 65.527547 -30.061698) (xy 65.660022 -30.168803) (xy 65.78733 -30.281999) (xy 65.909194 -30.401038)
			(xy 66.025343 -30.525658) (xy 66.135524 -30.655586) (xy 66.239494 -30.790535) (xy 66.337024 -30.930209)
			(xy 66.4279 -31.074301) (xy 66.511922 -31.222495) (xy 66.588905 -31.374463) (xy 66.658681 -31.529873)
			(xy 66.721096 -31.688383) (xy 66.776013 -31.849644) (xy 66.82331 -32.013302) (xy 66.862885 -32.178997)
			(xy 66.894649 -32.346365) (xy 66.918534 -32.515037) (xy 66.934486 -32.684644) (xy 66.942471 -32.854812)
			(xy 66.94297 -32.93999) (xy 66.942471 -33.025168) (xy 66.934486 -33.195336) (xy 66.918534 -33.364943)
			(xy 66.894649 -33.533615) (xy 66.862885 -33.700983) (xy 66.82331 -33.866678) (xy 66.776013 -34.030336)
			(xy 66.721096 -34.191597) (xy 66.658681 -34.350107) (xy 66.588905 -34.505517) (xy 66.511922 -34.657485)
			(xy 66.4279 -34.805679) (xy 66.337024 -34.949771) (xy 66.239494 -35.089445) (xy 66.135524 -35.224394)
			(xy 66.025343 -35.354322) (xy 65.909194 -35.478942) (xy 65.78733 -35.597981) (xy 65.660022 -35.711177)
			(xy 65.527547 -35.818282) (xy 65.390197 -35.919059) (xy 65.248275 -36.013288) (xy 65.102093 -36.100761)
			(xy 64.95197 -36.181286) (xy 64.798239 -36.254686) (xy 64.641236 -36.3208) (xy 64.481306 -36.379482)
			(xy 64.318802 -36.430603) (xy 64.154081 -36.474051) (xy 63.987503 -36.50973) (xy 63.819437 -36.537562)
			(xy 63.650251 -36.557486) (xy 63.480317 -36.569458) (xy 63.310008 -36.573452) (xy 63.139699 -36.569458)
			(xy 62.969765 -36.557486) (xy 62.800579 -36.537562) (xy 62.632513 -36.50973) (xy 62.465935 -36.474051)
			(xy 62.301214 -36.430603) (xy 62.13871 -36.379482) (xy 61.97878 -36.3208) (xy 61.821777 -36.254686)
			(xy 61.668046 -36.181286) (xy 61.517923 -36.100761) (xy 61.371741 -36.013288) (xy 61.229819 -35.919059)
			(xy 61.092469 -35.818282) (xy 60.959994 -35.711177) (xy 60.832686 -35.597981) (xy 60.710822 -35.478942)
			(xy 60.594673 -35.354322) (xy 60.484492 -35.224394) (xy 60.380522 -35.089445) (xy 60.282992 -34.949771)
			(xy 60.192116 -34.805679) (xy 60.108094 -34.657485) (xy 60.031111 -34.505517) (xy 59.961335 -34.350107)
			(xy 59.89892 -34.191597) (xy 59.844003 -34.030336) (xy 59.796706 -33.866678) (xy 59.757131 -33.700983)
			(xy 59.725367 -33.533615) (xy 59.701482 -33.364943) (xy 59.68553 -33.195336) (xy 59.677545 -33.025168)
			(xy 10.815232 -33.025168) (xy 10.505186 -33.335214) (xy 10.497791 -33.342068) (xy 10.479192 -33.34981)
			(xy 10.469118 -33.3502) (xy 3.196082 -33.3502) (xy 3.186013 -33.350627) (xy 3.167414 -33.358346)
			(xy 3.160014 -33.365186) (xy 2.250186 -34.275014) (xy 2.243332 -34.282409) (xy 2.23559 -34.301008)
			(xy 2.2352 -34.311082) (xy 2.2352 -54.399942) (xy 3.445769 -54.399942) (xy 3.44979 -54.286063) (xy 3.461835 -54.17275)
			(xy 3.481842 -54.06057) (xy 3.509713 -53.950081) (xy 3.545308 -53.841832) (xy 3.58845 -53.736365)
			(xy 3.638924 -53.634203) (xy 3.696479 -53.535856) (xy 3.760827 -53.441813) (xy 3.831649 -53.352544)
			(xy 3.908592 -53.268494) (xy 3.991272 -53.19008) (xy 4.079277 -53.117693) (xy 4.172169 -53.051695)
			(xy 4.269485 -52.992413) (xy 4.37074 -52.940144) (xy 4.47543 -52.895147) (xy 4.583033 -52.857648)
			(xy 4.693014 -52.827831) (xy 4.804823 -52.805847) (xy 4.917905 -52.791805) (xy 5.031696 -52.785774)
			(xy 5.145629 -52.787785) (xy 5.259136 -52.797828) (xy 5.371652 -52.815853) (xy 5.482616 -52.841769)
			(xy 5.591475 -52.875448) (xy 5.697688 -52.916722) (xy 5.800725 -52.965385) (xy 5.900072 -53.021195)
			(xy 5.995236 -53.083874) (xy 6.085741 -53.15311) (xy 6.171136 -53.228557) (xy 6.250997 -53.30984)
			(xy 6.324926 -53.396554) (xy 6.392553 -53.488267) (xy 6.453543 -53.584521) (xy 6.507591 -53.684838)
			(xy 6.554428 -53.788718) (xy 6.593821 -53.895642) (xy 6.625574 -54.00508) (xy 6.649528 -54.116484)
			(xy 6.665563 -54.2293) (xy 6.673601 -54.342967) (xy 6.674104 -54.399942) (xy 6.673601 -54.456917)
			(xy 6.665563 -54.570584) (xy 6.649528 -54.6834) (xy 6.625574 -54.794804) (xy 6.593821 -54.904242)
			(xy 6.554428 -55.011166) (xy 6.507591 -55.115046) (xy 6.453543 -55.215363) (xy 6.392553 -55.311617)
			(xy 6.324926 -55.40333) (xy 6.250997 -55.490044) (xy 6.171136 -55.571327) (xy 6.085741 -55.646774)
			(xy 5.995236 -55.71601) (xy 5.900072 -55.778689) (xy 5.800725 -55.834499) (xy 5.697688 -55.883162)
			(xy 5.591475 -55.924436) (xy 5.482616 -55.958115) (xy 5.371652 -55.984031) (xy 5.259136 -56.002056)
			(xy 5.145629 -56.012099) (xy 5.031696 -56.01411) (xy 4.917905 -56.008079) (xy 4.804823 -55.994037)
			(xy 4.693014 -55.972053) (xy 4.583033 -55.942236) (xy 4.47543 -55.904737) (xy 4.37074 -55.85974)
			(xy 4.269485 -55.807471) (xy 4.172169 -55.748189) (xy 4.079277 -55.682191) (xy 3.991272 -55.609804)
			(xy 3.908592 -55.53139) (xy 3.831649 -55.44734) (xy 3.760827 -55.358071) (xy 3.696479 -55.264028)
			(xy 3.638924 -55.165681) (xy 3.58845 -55.063519) (xy 3.545308 -54.958052) (xy 3.509713 -54.849803)
			(xy 3.481842 -54.739314) (xy 3.461835 -54.627134) (xy 3.44979 -54.513821) (xy 3.445769 -54.399942)
			(xy 2.2352 -54.399942) (xy 2.2352 -59.7662) (xy 35.306 -59.7662) (xy 35.306 -55.2958) (xy 35.9156 -54.6862)
			(xy 39.497 -54.6862) (xy 40.4622 -53.721) (xy 40.4622 -52.4764) (xy 44.196 -48.7426) (xy 46.9138 -48.7426)
			(xy 48.9204 -50.7492) (xy 51.6128 -50.7492) (xy 52.197 -51.3334) (xy 52.197 -53.6448) (xy 51.3842 -54.4576)
			(xy 46.2788 -54.4576) (xy 45.8724 -54.864) (xy 43.815 -54.864) (xy 43.60418 -55.07482) (xy 46.328582 -55.07482)
			(xy 46.332653 -55.019198) (xy 46.344779 -54.964761) (xy 46.364702 -54.91267) (xy 46.391998 -54.864035)
			(xy 46.426084 -54.819892) (xy 46.466233 -54.781183) (xy 46.511591 -54.748732) (xy 46.561191 -54.723231)
			(xy 46.613975 -54.705224) (xy 46.668818 -54.695094) (xy 46.724552 -54.693057) (xy 46.779989 -54.699157)
			(xy 46.833946 -54.713263) (xy 46.885275 -54.735075) (xy 46.932881 -54.764129) (xy 46.975749 -54.799804)
			(xy 47.012966 -54.841341) (xy 47.043739 -54.887854) (xy 47.067411 -54.938351) (xy 47.083479 -54.991758)
			(xy 47.091599 -55.046934) (xy 47.092108 -55.07482) (xy 47.091599 -55.102706) (xy 47.083479 -55.157882)
			(xy 47.067411 -55.211289) (xy 47.043739 -55.261786) (xy 47.012966 -55.308299) (xy 46.975749 -55.349836)
			(xy 46.932881 -55.385511) (xy 46.885275 -55.414565) (xy 46.833946 -55.436377) (xy 46.779989 -55.450483)
			(xy 46.724552 -55.456583) (xy 46.668818 -55.454546) (xy 46.613975 -55.444416) (xy 46.561191 -55.426409)
			(xy 46.511591 -55.400908) (xy 46.466233 -55.368457) (xy 46.426084 -55.329748) (xy 46.391998 -55.285605)
			(xy 46.364702 -55.23697) (xy 46.344779 -55.184879) (xy 46.332653 -55.130442) (xy 46.328582 -55.07482)
			(xy 43.60418 -55.07482) (xy 43.3578 -55.3212) (xy 43.3578 -55.598818) (xy 44.240686 -55.598818) (xy 44.240686 -55.538882)
			(xy 44.248509 -55.47946) (xy 44.264022 -55.421567) (xy 44.286958 -55.366194) (xy 44.316925 -55.314288)
			(xy 44.353412 -55.266738) (xy 44.395792 -55.224358) (xy 44.443342 -55.187871) (xy 44.495248 -55.157904)
			(xy 44.550621 -55.134968) (xy 44.608514 -55.119455) (xy 44.667936 -55.111632) (xy 44.727872 -55.111632)
			(xy 44.787294 -55.119455) (xy 44.845187 -55.134968) (xy 44.90056 -55.157904) (xy 44.952466 -55.187871)
			(xy 45.000016 -55.224358) (xy 45.042396 -55.266738) (xy 45.078883 -55.314288) (xy 45.10885 -55.366194)
			(xy 45.131786 -55.421567) (xy 45.147299 -55.47946) (xy 45.155122 -55.538882) (xy 45.155612 -55.56885)
			(xy 45.155122 -55.598818) (xy 45.147299 -55.65824) (xy 45.131786 -55.716133) (xy 45.10885 -55.771506)
			(xy 45.078883 -55.823412) (xy 45.042396 -55.870962) (xy 45.000016 -55.913342) (xy 44.952466 -55.949829)
			(xy 44.90056 -55.979796) (xy 44.845187 -56.002732) (xy 44.787294 -56.018245) (xy 44.727872 -56.026068)
			(xy 44.667936 -56.026068) (xy 44.608514 -56.018245) (xy 44.550621 -56.002732) (xy 44.495248 -55.979796)
			(xy 44.443342 -55.949829) (xy 44.395792 -55.913342) (xy 44.353412 -55.870962) (xy 44.316925 -55.823412)
			(xy 44.286958 -55.771506) (xy 44.264022 -55.716133) (xy 44.248509 -55.65824) (xy 44.240686 -55.598818)
			(xy 43.3578 -55.598818) (xy 43.3578 -57.954672) (xy 43.705018 -57.954672) (xy 43.705582 -57.923116)
			(xy 43.71427 -57.860605) (xy 43.731463 -57.79988) (xy 43.756835 -57.742093) (xy 43.789905 -57.688339)
			(xy 43.830047 -57.639638) (xy 43.876498 -57.596913) (xy 43.928378 -57.560975) (xy 43.984704 -57.532504)
			(xy 44.044406 -57.512042) (xy 44.106354 -57.499975) (xy 44.137834 -57.497726) (xy 44.150158 -57.496286)
			(xy 44.171399 -57.483536) (xy 44.178474 -57.473342) (xy 44.228512 -57.390792) (xy 44.230036 -57.365646)
			(xy 44.224702 -57.354216) (xy 44.213961 -57.329411) (xy 44.198814 -57.277524) (xy 44.191151 -57.224016)
			(xy 44.190666 -57.19699) (xy 44.190666 -57.196482) (xy 44.191161 -57.169231) (xy 44.198919 -57.115285)
			(xy 44.214275 -57.062992) (xy 44.236917 -57.013417) (xy 44.266382 -56.967568) (xy 44.302073 -56.926378)
			(xy 44.343261 -56.890687) (xy 44.38911 -56.861221) (xy 44.438685 -56.838578) (xy 44.490978 -56.823221)
			(xy 44.544923 -56.815462) (xy 44.572174 -56.814974) (xy 44.601346 -56.815572) (xy 44.659011 -56.824452)
			(xy 44.714651 -56.84201) (xy 44.766969 -56.867835) (xy 44.814745 -56.901326) (xy 44.856863 -56.941701)
			(xy 44.892342 -56.988018) (xy 44.920355 -57.039198) (xy 44.930822 -57.066434) (xy 44.934632 -57.077102)
			(xy 45.072046 -57.214262) (xy 45.091726 -57.234808) (xy 45.124673 -57.281186) (xy 45.149468 -57.332388)
			(xy 45.165425 -57.386994) (xy 45.169328 -57.415176) (xy 45.169328 -57.41543) (xy 45.170885 -57.424517)
			(xy 45.179458 -57.440821) (xy 45.193221 -57.453064) (xy 45.210413 -57.459677) (xy 45.21962 -57.460134)
			(xy 46.324266 -57.460134) (xy 46.338928 -57.460553) (xy 46.367474 -57.467263) (xy 46.393735 -57.480312)
			(xy 46.405292 -57.489344) (xy 46.405546 -57.489598) (xy 46.412505 -57.494813) (xy 46.428862 -57.500673)
			(xy 46.43755 -57.501028) (xy 46.65345 -57.501028) (xy 46.663519 -57.500595) (xy 46.682118 -57.492882)
			(xy 46.689518 -57.486042) (xy 46.714664 -57.460896) (xy 46.721366 -57.453499) (xy 46.728961 -57.435059)
			(xy 46.728956 -57.415116) (xy 46.721352 -57.39668) (xy 46.714664 -57.389268) (xy 46.440852 -57.115456)
			(xy 46.42993 -57.115456) (xy 46.421155 -57.11584) (xy 46.404653 -57.121811) (xy 46.397672 -57.12714)
			(xy 46.386158 -57.136065) (xy 46.360063 -57.148996) (xy 46.331715 -57.155665) (xy 46.317154 -57.156096)
			(xy 45.859446 -57.156096) (xy 45.842776 -57.155517) (xy 45.810569 -57.1469) (xy 45.781675 -57.130265)
			(xy 45.758052 -57.106738) (xy 45.74921 -57.092596) (xy 45.685202 -57.092596) (xy 45.685202 -56.457088)
			(xy 45.74921 -56.457088) (xy 45.758021 -56.44292) (xy 45.781643 -56.419374) (xy 45.810546 -56.402731)
			(xy 45.842769 -56.394124) (xy 45.859446 -56.393588) (xy 46.3169 -56.393588) (xy 46.331502 -56.394024)
			(xy 46.359939 -56.40067) (xy 46.386129 -56.413592) (xy 46.397672 -56.422544) (xy 46.40453 -56.428132)
			(xy 46.42104 -56.434228) (xy 46.582838 -56.434228) (xy 46.609538 -56.43478) (xy 46.662274 -56.443178)
			(xy 46.713055 -56.459698) (xy 46.760637 -56.483938) (xy 46.803857 -56.515302) (xy 46.823122 -56.533796)
			(xy 47.243746 -56.954674) (xy 47.2502 -56.960626) (xy 47.266043 -56.968161) (xy 47.274734 -56.969406)
			(xy 47.274988 -56.969406) (xy 47.30555 -56.972805) (xy 47.365455 -56.986687) (xy 47.422961 -57.008465)
			(xy 47.477033 -57.037748) (xy 47.526698 -57.074007) (xy 47.571059 -57.11659) (xy 47.609319 -57.16473)
			(xy 47.640789 -57.21756) (xy 47.664901 -57.274127) (xy 47.681221 -57.333414) (xy 47.689455 -57.394352)
			(xy 47.689455 -57.455844) (xy 47.681221 -57.516783) (xy 47.664902 -57.57607) (xy 47.64079 -57.632637)
			(xy 47.609321 -57.685467) (xy 47.571062 -57.733607) (xy 47.5267 -57.77619) (xy 47.477036 -57.81245)
			(xy 47.422964 -57.841733) (xy 47.365458 -57.863512) (xy 47.305554 -57.877394) (xy 47.274988 -57.880758)
			(xy 47.274734 -57.880758) (xy 47.266034 -57.881971) (xy 47.250185 -57.889515) (xy 47.243746 -57.89549)
			(xy 47.056802 -58.082688) (xy 47.037548 -58.101193) (xy 46.99432 -58.132544) (xy 46.946734 -58.156776)
			(xy 46.895953 -58.173295) (xy 46.843217 -58.181698) (xy 46.816518 -58.182256) (xy 46.43755 -58.182256)
			(xy 46.428867 -58.182644) (xy 46.412509 -58.188484) (xy 46.405546 -58.193686) (xy 46.405292 -58.19394)
			(xy 46.393707 -58.20293) (xy 46.367452 -58.215967) (xy 46.338922 -58.222703) (xy 46.324266 -58.22315)
			(xy 45.68698 -58.22315) (xy 45.676977 -58.22367) (xy 45.658494 -58.231327) (xy 45.644344 -58.245469)
			(xy 45.636676 -58.263947) (xy 45.63618 -58.27395) (xy 45.63618 -58.832242) (xy 45.636572 -58.841016)
			(xy 45.642537 -58.857519) (xy 45.647864 -58.8645) (xy 45.667699 -58.889231) (xy 45.701062 -58.943136)
			(xy 45.726658 -59.001135) (xy 45.743995 -59.062113) (xy 45.75274 -59.124902) (xy 45.753274 -59.1566)
			(xy 45.752839 -59.18657) (xy 45.745015 -59.245998) (xy 45.7295 -59.303897) (xy 45.706561 -59.359274)
			(xy 45.676589 -59.411184) (xy 45.640098 -59.458737) (xy 45.597712 -59.50112) (xy 45.550156 -59.537608)
			(xy 45.498244 -59.567576) (xy 45.442864 -59.590511) (xy 45.384965 -59.606021) (xy 45.325536 -59.613841)
			(xy 45.295566 -59.614308) (xy 45.264817 -59.613803) (xy 45.203874 -59.605564) (xy 45.144583 -59.589239)
			(xy 45.088012 -59.565121) (xy 45.03518 -59.533646) (xy 44.987038 -59.49538) (xy 44.944453 -59.451012)
			(xy 44.908193 -59.401342) (xy 44.878911 -59.347263) (xy 44.857133 -59.289751) (xy 44.843252 -59.22984)
			(xy 44.83989 -59.199272) (xy 44.83989 -59.199018) (xy 44.838672 -59.19032) (xy 44.83113 -59.174471)
			(xy 44.825158 -59.16803) (xy 44.589954 -58.93308) (xy 44.5714 -58.913754) (xy 44.539916 -58.870411)
			(xy 44.515597 -58.822679) (xy 44.499043 -58.77173) (xy 44.49066 -58.718819) (xy 44.490132 -58.692034)
			(xy 44.490132 -58.466228) (xy 44.489413 -58.45355) (xy 44.477284 -58.431282) (xy 44.467018 -58.42381)
			(xy 44.384976 -58.370216) (xy 44.359576 -58.368184) (xy 44.347892 -58.373264) (xy 44.347384 -58.373264)
			(xy 44.318174 -58.38559) (xy 44.257208 -58.402986) (xy 44.194425 -58.411805) (xy 44.162726 -58.41238)
			(xy 44.132756 -58.411915) (xy 44.07333 -58.404094) (xy 44.015432 -58.388582) (xy 43.960055 -58.365646)
			(xy 43.908146 -58.335678) (xy 43.860593 -58.299189) (xy 43.818209 -58.256806) (xy 43.781721 -58.209252)
			(xy 43.751753 -58.157343) (xy 43.728817 -58.101966) (xy 43.713306 -58.044068) (xy 43.705485 -57.984642)
			(xy 43.705018 -57.954672) (xy 43.3578 -57.954672) (xy 43.3578 -59.563) (xy 43.120564 -59.800236)
			(xy 42.347388 -59.800236) (xy 42.304892 -59.812238) (xy 42.218573 -59.830894) (xy 42.131147 -59.843381)
			(xy 42.043056 -59.849636) (xy 41.9989 -59.85002) (xy 41.998138 -59.85002) (xy 41.946895 -59.849474)
			(xy 41.844758 -59.841015) (xy 41.743661 -59.824199) (xy 41.693846 -59.812174) (xy 41.687696 -59.810815)
			(xy 41.675104 -59.810815) (xy 41.668954 -59.812174) (xy 41.619141 -59.82421) (xy 41.518044 -59.841039)
			(xy 41.415906 -59.849489) (xy 41.364662 -59.85002) (xy 41.3639 -59.85002) (xy 41.319745 -59.849616)
			(xy 41.231657 -59.843347) (xy 41.144233 -59.83086) (xy 41.057912 -59.812218) (xy 41.015412 -59.800236)
			(xy 39.945564 -59.800236) (xy 39.3954 -60.3504) (xy 35.8902 -60.3504) (xy 35.306 -59.7662) (xy 2.2352 -59.7662)
			(xy 2.2352 -60.422024) (xy 40.1871 -60.422024) (xy 40.1871 -60.362088) (xy 40.194923 -60.302666)
			(xy 40.210436 -60.244773) (xy 40.233372 -60.1894) (xy 40.263339 -60.137494) (xy 40.299826 -60.089944)
			(xy 40.342206 -60.047564) (xy 40.389756 -60.011077) (xy 40.441662 -59.98111) (xy 40.497035 -59.958174)
			(xy 40.554928 -59.942661) (xy 40.61435 -59.934838) (xy 40.674286 -59.934838) (xy 40.733708 -59.942661)
			(xy 40.791601 -59.958174) (xy 40.846974 -59.98111) (xy 40.89888 -60.011077) (xy 40.94643 -60.047564)
			(xy 40.98881 -60.089944) (xy 41.025297 -60.137494) (xy 41.055264 -60.1894) (xy 41.0782 -60.244773)
			(xy 41.093713 -60.302666) (xy 41.101536 -60.362088) (xy 41.102026 -60.392056) (xy 41.101536 -60.422024)
			(xy 41.093713 -60.481446) (xy 41.0782 -60.539339) (xy 41.055264 -60.594712) (xy 41.025297 -60.646618)
			(xy 41.005656 -60.672214) (xy 41.724054 -60.672214) (xy 41.724054 -60.612278) (xy 41.731877 -60.552856)
			(xy 41.74739 -60.494963) (xy 41.770326 -60.43959) (xy 41.800293 -60.387684) (xy 41.83678 -60.340134)
			(xy 41.87916 -60.297754) (xy 41.92671 -60.261267) (xy 41.978616 -60.2313) (xy 42.033989 -60.208364)
			(xy 42.091882 -60.192851) (xy 42.151304 -60.185028) (xy 42.21124 -60.185028) (xy 42.270662 -60.192851)
			(xy 42.328555 -60.208364) (xy 42.383928 -60.2313) (xy 42.435834 -60.261267) (xy 42.483384 -60.297754)
			(xy 42.525764 -60.340134) (xy 42.562251 -60.387684) (xy 42.592218 -60.43959) (xy 42.615154 -60.494963)
			(xy 42.630667 -60.552856) (xy 42.63849 -60.612278) (xy 42.63898 -60.642246) (xy 42.63849 -60.672214)
			(xy 42.630667 -60.731636) (xy 42.615154 -60.789529) (xy 42.592218 -60.844902) (xy 42.562251 -60.896808)
			(xy 42.525764 -60.944358) (xy 42.483384 -60.986738) (xy 42.435834 -61.023225) (xy 42.383928 -61.053192)
			(xy 42.328555 -61.076128) (xy 42.270662 -61.091641) (xy 42.21124 -61.099464) (xy 42.151304 -61.099464)
			(xy 42.091882 -61.091641) (xy 42.033989 -61.076128) (xy 41.978616 -61.053192) (xy 41.92671 -61.023225)
			(xy 41.87916 -60.986738) (xy 41.83678 -60.944358) (xy 41.800293 -60.896808) (xy 41.770326 -60.844902)
			(xy 41.74739 -60.789529) (xy 41.731877 -60.731636) (xy 41.724054 -60.672214) (xy 41.005656 -60.672214)
			(xy 40.98881 -60.694168) (xy 40.94643 -60.736548) (xy 40.89888 -60.773035) (xy 40.846974 -60.803002)
			(xy 40.791601 -60.825938) (xy 40.733708 -60.841451) (xy 40.674286 -60.849274) (xy 40.61435 -60.849274)
			(xy 40.554928 -60.841451) (xy 40.497035 -60.825938) (xy 40.441662 -60.803002) (xy 40.389756 -60.773035)
			(xy 40.342206 -60.736548) (xy 40.299826 -60.694168) (xy 40.263339 -60.646618) (xy 40.233372 -60.594712)
			(xy 40.210436 -60.539339) (xy 40.194923 -60.481446) (xy 40.1871 -60.422024) (xy 2.2352 -60.422024)
			(xy 2.2352 -62.203768) (xy 38.440356 -62.203768) (xy 38.440356 -62.119072) (xy 38.448407 -62.034758)
			(xy 38.464436 -61.951592) (xy 38.488297 -61.870325) (xy 38.519776 -61.791695) (xy 38.558587 -61.716414)
			(xy 38.604377 -61.645162) (xy 38.656733 -61.578586) (xy 38.715181 -61.517288) (xy 38.779191 -61.461823)
			(xy 38.848183 -61.412694) (xy 38.921533 -61.370345) (xy 38.998576 -61.335161) (xy 39.078615 -61.307459)
			(xy 39.160924 -61.287491) (xy 39.244759 -61.275438) (xy 39.32936 -61.271408) (xy 39.413961 -61.275438)
			(xy 39.497796 -61.287491) (xy 39.580105 -61.307459) (xy 39.660144 -61.335161) (xy 39.737187 -61.370345)
			(xy 39.810537 -61.412694) (xy 39.879529 -61.461823) (xy 39.943539 -61.517288) (xy 40.001987 -61.578586)
			(xy 40.054343 -61.645162) (xy 40.100133 -61.716414) (xy 40.138944 -61.791695) (xy 40.170423 -61.870325)
			(xy 40.194284 -61.951592) (xy 40.210313 -62.034758) (xy 40.218364 -62.119072) (xy 40.218868 -62.16142)
			(xy 40.218364 -62.203768) (xy 40.210313 -62.288082) (xy 40.194284 -62.371248) (xy 40.170423 -62.452515)
			(xy 40.138944 -62.531145) (xy 40.100133 -62.606426) (xy 40.054343 -62.677678) (xy 40.001987 -62.744254)
			(xy 39.943539 -62.805552) (xy 39.879529 -62.861017) (xy 39.810537 -62.910146) (xy 39.737187 -62.952495)
			(xy 39.660144 -62.987679) (xy 39.646593 -62.992369) (xy 40.853342 -62.992369) (xy 40.853342 -62.892571)
			(xy 40.861172 -62.79308) (xy 40.876784 -62.694511) (xy 40.900081 -62.59747) (xy 40.930921 -62.502556)
			(xy 40.969112 -62.410354) (xy 41.014419 -62.321433) (xy 41.066564 -62.236341) (xy 41.125224 -62.155603)
			(xy 41.190038 -62.079716) (xy 41.260606 -62.009148) (xy 41.336493 -61.944334) (xy 41.417231 -61.885674)
			(xy 41.502323 -61.833529) (xy 41.591244 -61.788222) (xy 41.683446 -61.750031) (xy 41.77836 -61.719191)
			(xy 41.875401 -61.695894) (xy 41.97397 -61.680282) (xy 42.073461 -61.672452) (xy 42.12336 -61.671962)
			(xy 42.123614 -61.671962) (xy 42.173729 -61.672445) (xy 42.273646 -61.680344) (xy 42.372631 -61.696091)
			(xy 42.470066 -61.719588) (xy 42.565348 -61.75069) (xy 42.611802 -61.769498) (xy 42.621274 -61.772988)
			(xy 42.641446 -61.772988) (xy 42.650918 -61.769498) (xy 42.697371 -61.750687) (xy 42.792653 -61.719586)
			(xy 42.890089 -61.69609) (xy 42.989074 -61.680345) (xy 43.088991 -61.672448) (xy 43.139106 -61.671962)
			(xy 43.13936 -61.671962) (xy 43.189259 -61.672452) (xy 43.28875 -61.680282) (xy 43.387319 -61.695894)
			(xy 43.48436 -61.719191) (xy 43.579274 -61.750031) (xy 43.671476 -61.788222) (xy 43.760397 -61.833529)
			(xy 43.845489 -61.885674) (xy 43.926227 -61.944334) (xy 44.002114 -62.009148) (xy 44.072682 -62.079716)
			(xy 44.137496 -62.155603) (xy 44.196156 -62.236341) (xy 44.248301 -62.321433) (xy 44.293608 -62.410354)
			(xy 44.331799 -62.502556) (xy 44.362639 -62.59747) (xy 44.385936 -62.694511) (xy 44.401548 -62.79308)
			(xy 44.409378 -62.892571) (xy 44.409378 -62.992369) (xy 44.401548 -63.09186) (xy 44.385936 -63.190429)
			(xy 44.362639 -63.28747) (xy 44.331799 -63.382384) (xy 44.293608 -63.474586) (xy 44.248301 -63.563507)
			(xy 44.196156 -63.648599) (xy 44.137496 -63.729337) (xy 44.072682 -63.805224) (xy 44.002114 -63.875792)
			(xy 43.926227 -63.940606) (xy 43.845489 -63.999266) (xy 43.760397 -64.051411) (xy 43.671476 -64.096718)
			(xy 43.579274 -64.134909) (xy 43.48436 -64.165749) (xy 43.387319 -64.189046) (xy 43.28875 -64.204658)
			(xy 43.189259 -64.212488) (xy 43.13936 -64.212978) (xy 43.139106 -64.212978) (xy 43.088992 -64.212485)
			(xy 42.989074 -64.204588) (xy 42.89009 -64.188843) (xy 42.792654 -64.165348) (xy 42.697372 -64.134249)
			(xy 42.650918 -64.115442) (xy 42.641446 -64.111952) (xy 42.621274 -64.111952) (xy 42.611802 -64.115442)
			(xy 42.565348 -64.134249) (xy 42.470066 -64.16535) (xy 42.37263 -64.188847) (xy 42.273646 -64.204593)
			(xy 42.173729 -64.212492) (xy 42.123614 -64.212978) (xy 42.12336 -64.212978) (xy 42.073461 -64.212488)
			(xy 41.97397 -64.204658) (xy 41.875401 -64.189046) (xy 41.77836 -64.165749) (xy 41.683446 -64.134909)
			(xy 41.591244 -64.096718) (xy 41.502323 -64.051411) (xy 41.417231 -63.999266) (xy 41.336493 -63.940606)
			(xy 41.260606 -63.875792) (xy 41.190038 -63.805224) (xy 41.125224 -63.729337) (xy 41.066564 -63.648599)
			(xy 41.014419 -63.563507) (xy 40.969112 -63.474586) (xy 40.930921 -63.382384) (xy 40.900081 -63.28747)
			(xy 40.876784 -63.190429) (xy 40.861172 -63.09186) (xy 40.853342 -62.992369) (xy 39.646593 -62.992369)
			(xy 39.580105 -63.015381) (xy 39.497796 -63.035349) (xy 39.413961 -63.047402) (xy 39.32936 -63.051433)
			(xy 39.244759 -63.047402) (xy 39.160924 -63.035349) (xy 39.078615 -63.015381) (xy 38.998576 -62.987679)
			(xy 38.921533 -62.952495) (xy 38.848183 -62.910146) (xy 38.779191 -62.861017) (xy 38.715181 -62.805552)
			(xy 38.656733 -62.744254) (xy 38.604377 -62.677678) (xy 38.558587 -62.606426) (xy 38.519776 -62.531145)
			(xy 38.488297 -62.452515) (xy 38.464436 -62.371248) (xy 38.448407 -62.288082) (xy 38.440356 -62.203768)
			(xy 2.2352 -62.203768) (xy 2.2352 -65.466468) (xy 3.356864 -66.588132) (xy 23.73884 -66.588132) (xy 26.59507 -63.731902)
			(xy 26.75255 -63.574422) (xy 31.595822 -63.574422) (xy 31.753302 -63.731902) (xy 32.1056 -64.0842)
			(xy 33.6804 -65.659) (xy 33.655 -65.659) (xy 34.6964 -66.7004) (xy 41.3512 -66.7004)
		)
		(stroke
			(width 0)
			(type solid)
		)
		(fill yes)
		(layer "B.Cu")
		(net "GND")
	)
	(gr_poly
		(pts
			(xy 77.398118 -74.3458) (xy 77.408187 -74.345373) (xy 77.426786 -74.337654) (xy 77.434186 -74.330814)
			(xy 77.455014 -74.309986) (xy 77.462409 -74.303132) (xy 77.481008 -74.29539) (xy 77.491082 -74.295)
			(xy 78.972918 -74.295) (xy 78.982987 -74.294573) (xy 79.001586 -74.286854) (xy 79.008986 -74.280014)
			(xy 79.995014 -73.293986) (xy 80.001868 -73.286591) (xy 80.00961 -73.267992) (xy 80.01 -73.257918)
			(xy 80.01 -68.093082) (xy 80.010427 -68.083013) (xy 80.018146 -68.064414) (xy 80.024986 -68.057014)
			(xy 83.840828 -64.241172) (xy 175.661574 -64.241172) (xy 176.126902 -63.775844) (xy 178.7906 -63.775844)
			(xy 179.052982 -63.513462) (xy 179.052982 -63.25616) (xy 179.031712 -63.207197) (xy 178.996502 -63.106408)
			(xy 178.969871 -63.003021) (xy 178.952006 -62.897765) (xy 178.943033 -62.791381) (xy 178.942492 -62.738)
			(xy 178.942492 -62.737492) (xy 178.943061 -62.683927) (xy 178.952103 -62.577179) (xy 178.970097 -62.471571)
			(xy 178.996915 -62.367852) (xy 179.01412 -62.317122) (xy 179.01412 -62.282832) (xy 178.995774 -62.230604)
			(xy 178.967149 -62.123663) (xy 178.947938 -62.014637) (xy 178.938288 -61.904353) (xy 178.937666 -61.849)
			(xy 178.938147 -61.799727) (xy 178.945791 -61.701477) (xy 178.961024 -61.604114) (xy 178.983755 -61.508225)
			(xy 179.013847 -61.414385) (xy 179.05112 -61.323159) (xy 179.095349 -61.235095) (xy 179.146268 -61.150723)
			(xy 179.203572 -61.070549) (xy 179.266916 -60.995057) (xy 179.335918 -60.9247) (xy 179.410164 -60.8599)
			(xy 179.489208 -60.801049) (xy 179.572574 -60.748498) (xy 179.659762 -60.702565) (xy 179.750246 -60.663525)
			(xy 179.796694 -60.647072) (xy 179.83073 -60.60313) (xy 179.834745 -60.558544) (xy 179.848261 -60.47004)
			(xy 179.867982 -60.382709) (xy 179.880514 -60.339732) (xy 179.8828 -60.325) (xy 179.880514 -60.310268)
			(xy 179.867555 -60.26573) (xy 179.847382 -60.175185) (xy 179.83387 -60.083408) (xy 179.827092 -59.990891)
			(xy 179.826666 -59.944508) (xy 179.826666 -59.944) (xy 179.827156 -59.894101) (xy 179.834986 -59.79461)
			(xy 179.850598 -59.696041) (xy 179.873895 -59.599) (xy 179.904735 -59.504086) (xy 179.942926 -59.411884)
			(xy 179.988233 -59.322963) (xy 180.040378 -59.237871) (xy 180.099038 -59.157133) (xy 180.163852 -59.081246)
			(xy 180.23442 -59.010678) (xy 180.310307 -58.945864) (xy 180.391045 -58.887204) (xy 180.476137 -58.835059)
			(xy 180.565058 -58.789752) (xy 180.65726 -58.751561) (xy 180.752174 -58.720721) (xy 180.849215 -58.697424)
			(xy 180.947784 -58.681812) (xy 181.047275 -58.673982) (xy 181.147073 -58.673982) (xy 181.246564 -58.681812)
			(xy 181.345133 -58.697424) (xy 181.442174 -58.720721) (xy 181.537088 -58.751561) (xy 181.62929 -58.789752)
			(xy 181.718211 -58.835059) (xy 181.803303 -58.887204) (xy 181.884041 -58.945864) (xy 181.959928 -59.010678)
			(xy 182.030496 -59.081246) (xy 182.09531 -59.157133) (xy 182.15397 -59.237871) (xy 182.206115 -59.322963)
			(xy 182.251422 -59.411884) (xy 182.289613 -59.504086) (xy 182.320453 -59.599) (xy 182.34375 -59.696041)
			(xy 182.359362 -59.79461) (xy 182.367192 -59.894101) (xy 182.367682 -59.944) (xy 182.367682 -59.944508)
			(xy 182.367249 -59.99089) (xy 182.360464 -60.083407) (xy 182.346952 -60.175182) (xy 182.326786 -60.265729)
			(xy 182.313834 -60.310268) (xy 182.311548 -60.325) (xy 182.313834 -60.339732) (xy 182.326792 -60.38427)
			(xy 182.346965 -60.474815) (xy 182.360476 -60.566592) (xy 182.367254 -60.659109) (xy 182.367682 -60.705492)
			(xy 182.367682 -60.706) (xy 182.367201 -60.755274) (xy 182.359557 -60.853525) (xy 182.344325 -60.950888)
			(xy 182.321594 -61.046778) (xy 182.291502 -61.140619) (xy 182.25423 -61.231847) (xy 182.210002 -61.319912)
			(xy 182.159083 -61.404286) (xy 182.101781 -61.484461) (xy 182.038438 -61.559955) (xy 181.969437 -61.630315)
			(xy 181.895191 -61.695116) (xy 181.858403 -61.722508) (xy 186.04992 -61.722508) (xy 186.04992 -60.198)
			(xy 186.050435 -60.181304) (xy 186.059068 -60.149047) (xy 186.075747 -60.120118) (xy 186.099338 -60.096485)
			(xy 186.128237 -60.079755) (xy 186.160479 -60.071065) (xy 186.177174 -60.070492) (xy 187.701174 -60.070492)
			(xy 187.717837 -60.071011) (xy 187.750032 -60.079622) (xy 187.778905 -60.096265) (xy 187.802492 -60.119809)
			(xy 187.819188 -60.148651) (xy 187.827859 -60.18083) (xy 187.828428 -60.197492) (xy 187.828428 -61.722)
			(xy 187.828411 -61.722508) (xy 197.22592 -61.722508) (xy 197.22592 -60.198) (xy 197.226435 -60.181304)
			(xy 197.235068 -60.149047) (xy 197.251747 -60.120118) (xy 197.275338 -60.096485) (xy 197.304237 -60.079755)
			(xy 197.336479 -60.071065) (xy 197.353174 -60.070492) (xy 198.877174 -60.070492) (xy 198.893837 -60.071011)
			(xy 198.926032 -60.079622) (xy 198.954905 -60.096265) (xy 198.978492 -60.119809) (xy 198.995188 -60.148651)
			(xy 199.003859 -60.18083) (xy 199.004428 -60.197492) (xy 199.004428 -61.722) (xy 199.004411 -61.722508)
			(xy 208.40192 -61.722508) (xy 208.40192 -60.198) (xy 208.402435 -60.181304) (xy 208.411068 -60.149047)
			(xy 208.427747 -60.120118) (xy 208.451338 -60.096485) (xy 208.480237 -60.079755) (xy 208.512479 -60.071065)
			(xy 208.529174 -60.070492) (xy 210.053174 -60.070492) (xy 210.069837 -60.071011) (xy 210.102032 -60.079622)
			(xy 210.130905 -60.096265) (xy 210.154492 -60.119809) (xy 210.171188 -60.148651) (xy 210.179859 -60.18083)
			(xy 210.180428 -60.197492) (xy 210.180428 -61.722) (xy 210.179866 -61.738692) (xy 210.171237 -61.770942)
			(xy 210.154565 -61.799866) (xy 210.130984 -61.823498) (xy 210.102096 -61.840231) (xy 210.069865 -61.84893)
			(xy 210.053174 -61.849508) (xy 208.529174 -61.849508) (xy 208.512508 -61.849035) (xy 208.480312 -61.840411)
			(xy 208.45144 -61.823757) (xy 208.427854 -61.800205) (xy 208.411159 -61.771357) (xy 208.402489 -61.739173)
			(xy 208.40192 -61.722508) (xy 199.004411 -61.722508) (xy 199.003866 -61.738692) (xy 198.995237 -61.770942)
			(xy 198.978565 -61.799866) (xy 198.954984 -61.823498) (xy 198.926096 -61.840231) (xy 198.893865 -61.84893)
			(xy 198.877174 -61.849508) (xy 197.353174 -61.849508) (xy 197.336508 -61.849035) (xy 197.304312 -61.840411)
			(xy 197.27544 -61.823757) (xy 197.251854 -61.800205) (xy 197.235159 -61.771357) (xy 197.226489 -61.739173)
			(xy 197.22592 -61.722508) (xy 187.828411 -61.722508) (xy 187.827866 -61.738692) (xy 187.819237 -61.770942)
			(xy 187.802565 -61.799866) (xy 187.778984 -61.823498) (xy 187.750096 -61.840231) (xy 187.717865 -61.84893)
			(xy 187.701174 -61.849508) (xy 186.177174 -61.849508) (xy 186.160508 -61.849035) (xy 186.128312 -61.840411)
			(xy 186.09944 -61.823757) (xy 186.075854 -61.800205) (xy 186.059159 -61.771357) (xy 186.050489 -61.739173)
			(xy 186.04992 -61.722508) (xy 181.858403 -61.722508) (xy 181.816148 -61.753971) (xy 181.732783 -61.806524)
			(xy 181.645596 -61.85246) (xy 181.555112 -61.891503) (xy 181.508654 -61.907928) (xy 181.474618 -61.95187)
			(xy 181.469646 -62.005987) (xy 181.451623 -62.113165) (xy 181.424509 -62.218412) (xy 181.407054 -62.269878)
			(xy 181.407054 -62.304168) (xy 181.425401 -62.356395) (xy 181.454026 -62.463336) (xy 181.473237 -62.572363)
			(xy 181.482888 -62.682647) (xy 181.483508 -62.738) (xy 181.483508 -62.738254) (xy 181.483064 -62.786383)
			(xy 181.475778 -62.882365) (xy 181.461244 -62.977519) (xy 181.439546 -63.071299) (xy 181.410809 -63.163167)
			(xy 181.375197 -63.252595) (xy 181.354476 -63.296038) (xy 181.354476 -63.569596) (xy 181.560724 -63.775844)
			(xy 181.63413 -63.775844) (xy 181.676169 -63.767588) (xy 181.761073 -63.756066) (xy 181.846559 -63.750292)
			(xy 181.8894 -63.749936) (xy 181.941993 -63.750466) (xy 182.046819 -63.759162) (xy 182.150567 -63.776495)
			(xy 182.252528 -63.802346) (xy 182.352002 -63.836537) (xy 182.448308 -63.878835) (xy 182.540788 -63.928951)
			(xy 182.628809 -63.98654) (xy 182.711767 -64.051209) (xy 182.789094 -64.122516) (xy 182.860262 -64.199971)
			(xy 182.892954 -64.241172) (xy 213.308692 -64.241172) (xy 213.599014 -63.95085) (xy 213.605862 -63.943453)
			(xy 213.613592 -63.924854) (xy 213.614 -63.914782) (xy 213.614 -48.265842) (xy 213.613566 -48.255777)
			(xy 213.605837 -48.237187) (xy 213.599014 -48.229774) (xy 212.99424 -47.625) (xy 212.986832 -47.61831)
			(xy 212.968396 -47.610713) (xy 212.958426 -47.610268) (xy 207.7974 -47.610268) (xy 207.749272 -47.609757)
			(xy 207.653382 -47.601365) (xy 207.558589 -47.584645) (xy 207.465614 -47.559724) (xy 207.375166 -47.526792)
			(xy 207.287934 -47.4861) (xy 207.204582 -47.437958) (xy 207.125744 -47.382732) (xy 207.052022 -47.320842)
			(xy 207.01762 -47.28718) (xy 201.86142 -42.13098) (xy 201.827745 -42.096592) (xy 201.765863 -42.022863)
			(xy 201.710643 -41.944021) (xy 201.662505 -41.860666) (xy 201.621816 -41.773432) (xy 201.588884 -41.682984)
			(xy 201.563962 -41.59001) (xy 201.547238 -41.495218) (xy 201.538839 -41.399328) (xy 201.538332 -41.3512)
			(xy 201.538332 -21.727414) (xy 201.537843 -21.717453) (xy 201.530254 -21.69903) (xy 201.5236 -21.6916)
			(xy 200.039986 -20.207986) (xy 200.032591 -20.201132) (xy 200.013992 -20.19339) (xy 200.003918 -20.193)
			(xy 100.020882 -20.193) (xy 100.010813 -20.193427) (xy 99.992214 -20.201146) (xy 99.984814 -20.207986)
			(xy 98.363786 -21.829014) (xy 98.356932 -21.836409) (xy 98.34919 -21.855008) (xy 98.3488 -21.865082)
			(xy 98.3488 -32.93999) (xy 130.161799 -32.93999) (xy 130.165806 -32.755097) (xy 130.177818 -32.57055)
			(xy 130.197813 -32.386697) (xy 130.225754 -32.203883) (xy 130.261587 -32.022451) (xy 130.305247 -31.842742)
			(xy 130.35665 -31.665092) (xy 130.415701 -31.489836) (xy 130.482288 -31.317303) (xy 130.556286 -31.147816)
			(xy 130.637557 -30.981693) (xy 130.725948 -30.819247) (xy 130.821293 -30.660783) (xy 130.923413 -30.506597)
			(xy 131.032116 -30.35698) (xy 131.147199 -30.212212) (xy 131.268444 -30.072566) (xy 131.395625 -29.938302)
			(xy 131.528503 -29.809674) (xy 131.666828 -29.686923) (xy 131.810341 -29.570279) (xy 131.958771 -29.459962)
			(xy 132.111842 -29.356177) (xy 132.269264 -29.259121) (xy 132.430743 -29.168976) (xy 132.595975 -29.08591)
			(xy 132.764651 -29.01008) (xy 132.936453 -28.941628) (xy 133.111059 -28.880682) (xy 133.288141 -28.827357)
			(xy 133.467367 -28.781754) (xy 133.6484 -28.743956) (xy 133.830901 -28.714037) (xy 134.014526 -28.692051)
			(xy 134.198932 -28.678041) (xy 134.383771 -28.672031) (xy 134.568697 -28.674035) (xy 134.753363 -28.684047)
			(xy 134.937421 -28.702049) (xy 135.120527 -28.728008) (xy 135.302337 -28.761874) (xy 135.482509 -28.803585)
			(xy 135.660705 -28.85306) (xy 135.83659 -28.910209) (xy 136.009835 -28.974923) (xy 136.180114 -29.047081)
			(xy 136.347107 -29.126548) (xy 136.510501 -29.213174) (xy 136.669989 -29.306797) (xy 136.825272 -29.40724)
			(xy 136.976058 -29.514316) (xy 137.122064 -29.627824) (xy 137.263015 -29.747549) (xy 137.398649 -29.873268)
			(xy 137.528708 -30.004745) (xy 137.652951 -30.141732) (xy 137.771143 -30.283973) (xy 137.883062 -30.4312)
			(xy 137.988498 -30.583137) (xy 138.087254 -30.739498) (xy 138.179143 -30.899991) (xy 138.263994 -31.064314)
			(xy 138.341647 -31.232158) (xy 138.411956 -31.403209) (xy 138.47479 -31.577144) (xy 138.53003 -31.753639)
			(xy 138.577572 -31.93236) (xy 138.617328 -32.112973) (xy 138.649223 -32.295139) (xy 138.673197 -32.478515)
			(xy 138.689204 -32.662758) (xy 138.697215 -32.847522) (xy 138.697716 -32.93999) (xy 138.697215 -33.032458)
			(xy 138.689204 -33.217222) (xy 138.673197 -33.401465) (xy 138.649223 -33.584841) (xy 138.617328 -33.767007)
			(xy 138.577572 -33.94762) (xy 138.53003 -34.126341) (xy 138.47479 -34.302836) (xy 138.411956 -34.476771)
			(xy 138.341647 -34.647822) (xy 138.263994 -34.815666) (xy 138.179143 -34.979989) (xy 138.087254 -35.140482)
			(xy 137.988498 -35.296843) (xy 137.883062 -35.44878) (xy 137.771143 -35.596007) (xy 137.652951 -35.738248)
			(xy 137.528708 -35.875235) (xy 137.398649 -36.006712) (xy 137.263015 -36.132431) (xy 137.122064 -36.252156)
			(xy 136.976058 -36.365664) (xy 136.825272 -36.47274) (xy 136.669989 -36.573183) (xy 136.510501 -36.666806)
			(xy 136.347107 -36.753432) (xy 136.180114 -36.832899) (xy 136.009835 -36.905057) (xy 135.83659 -36.969771)
			(xy 135.660705 -37.02692) (xy 135.482509 -37.076395) (xy 135.302337 -37.118106) (xy 135.120527 -37.151972)
			(xy 134.937421 -37.177931) (xy 134.753363 -37.195933) (xy 134.568697 -37.205945) (xy 134.383771 -37.207949)
			(xy 134.198932 -37.201939) (xy 134.014526 -37.187929) (xy 133.830901 -37.165943) (xy 133.6484 -37.136024)
			(xy 133.467367 -37.098226) (xy 133.288141 -37.052623) (xy 133.111059 -36.999298) (xy 132.936453 -36.938352)
			(xy 132.764651 -36.8699) (xy 132.595975 -36.79407) (xy 132.430743 -36.711004) (xy 132.269264 -36.620859)
			(xy 132.111842 -36.523803) (xy 131.958771 -36.420018) (xy 131.810341 -36.309701) (xy 131.666828 -36.193057)
			(xy 131.528503 -36.070306) (xy 131.395625 -35.941678) (xy 131.268444 -35.807414) (xy 131.147199 -35.667768)
			(xy 131.032116 -35.523) (xy 130.923413 -35.373383) (xy 130.821293 -35.219197) (xy 130.725948 -35.060733)
			(xy 130.637557 -34.898287) (xy 130.556286 -34.732164) (xy 130.482288 -34.562677) (xy 130.415701 -34.390144)
			(xy 130.35665 -34.214888) (xy 130.305247 -34.037238) (xy 130.261587 -33.857529) (xy 130.225754 -33.676097)
			(xy 130.197813 -33.493283) (xy 130.177818 -33.30943) (xy 130.165806 -33.124883) (xy 130.161799 -32.93999)
			(xy 98.3488 -32.93999) (xy 98.3488 -37.949632) (xy 164.656777 -37.949632) (xy 164.660784 -37.764739)
			(xy 164.672796 -37.580192) (xy 164.692791 -37.396339) (xy 164.720732 -37.213525) (xy 164.756565 -37.032093)
			(xy 164.800225 -36.852384) (xy 164.851628 -36.674734) (xy 164.910679 -36.499478) (xy 164.977266 -36.326945)
			(xy 165.051264 -36.157458) (xy 165.132535 -35.991335) (xy 165.220926 -35.828889) (xy 165.316271 -35.670425)
			(xy 165.418391 -35.516239) (xy 165.527094 -35.366622) (xy 165.642177 -35.221854) (xy 165.763422 -35.082208)
			(xy 165.890603 -34.947944) (xy 166.023481 -34.819316) (xy 166.161806 -34.696565) (xy 166.305319 -34.579921)
			(xy 166.453749 -34.469604) (xy 166.60682 -34.365819) (xy 166.764242 -34.268763) (xy 166.925721 -34.178618)
			(xy 167.090953 -34.095552) (xy 167.259629 -34.019722) (xy 167.431431 -33.95127) (xy 167.606037 -33.890324)
			(xy 167.783119 -33.836999) (xy 167.962345 -33.791396) (xy 168.143378 -33.753598) (xy 168.325879 -33.723679)
			(xy 168.509504 -33.701693) (xy 168.69391 -33.687683) (xy 168.878749 -33.681673) (xy 169.063675 -33.683677)
			(xy 169.248341 -33.693689) (xy 169.432399 -33.711691) (xy 169.615505 -33.73765) (xy 169.797315 -33.771516)
			(xy 169.977487 -33.813227) (xy 170.155683 -33.862702) (xy 170.331568 -33.919851) (xy 170.504813 -33.984565)
			(xy 170.675092 -34.056723) (xy 170.842085 -34.13619) (xy 171.005479 -34.222816) (xy 171.164967 -34.316439)
			(xy 171.32025 -34.416882) (xy 171.471036 -34.523958) (xy 171.617042 -34.637466) (xy 171.757993 -34.757191)
			(xy 171.893627 -34.88291) (xy 172.023686 -35.014387) (xy 172.147929 -35.151374) (xy 172.266121 -35.293615)
			(xy 172.37804 -35.440842) (xy 172.483476 -35.592779) (xy 172.582232 -35.74914) (xy 172.674121 -35.909633)
			(xy 172.758972 -36.073956) (xy 172.836625 -36.2418) (xy 172.906934 -36.412851) (xy 172.969768 -36.586786)
			(xy 173.025008 -36.763281) (xy 173.07255 -36.942002) (xy 173.112306 -37.122615) (xy 173.144201 -37.304781)
			(xy 173.168175 -37.488157) (xy 173.184182 -37.6724) (xy 173.192193 -37.857164) (xy 173.192694 -37.949632)
			(xy 173.192193 -38.0421) (xy 173.184182 -38.226864) (xy 173.168175 -38.411107) (xy 173.144201 -38.594483)
			(xy 173.112306 -38.776649) (xy 173.07255 -38.957262) (xy 173.025008 -39.135983) (xy 172.969768 -39.312478)
			(xy 172.906934 -39.486413) (xy 172.836625 -39.657464) (xy 172.758972 -39.825308) (xy 172.674121 -39.989631)
			(xy 172.582232 -40.150124) (xy 172.483476 -40.306485) (xy 172.37804 -40.458422) (xy 172.266121 -40.605649)
			(xy 172.147929 -40.74789) (xy 172.023686 -40.884877) (xy 171.893627 -41.016354) (xy 171.757993 -41.142073)
			(xy 171.617042 -41.261798) (xy 171.471036 -41.375306) (xy 171.32025 -41.482382) (xy 171.164967 -41.582825)
			(xy 171.005479 -41.676448) (xy 170.842085 -41.763074) (xy 170.675092 -41.842541) (xy 170.504813 -41.914699)
			(xy 170.331568 -41.979413) (xy 170.155683 -42.036562) (xy 169.977487 -42.086037) (xy 169.797315 -42.127748)
			(xy 169.615505 -42.161614) (xy 169.432399 -42.187573) (xy 169.248341 -42.205575) (xy 169.063675 -42.215587)
			(xy 168.878749 -42.217591) (xy 168.69391 -42.211581) (xy 168.509504 -42.197571) (xy 168.325879 -42.175585)
			(xy 168.143378 -42.145666) (xy 167.962345 -42.107868) (xy 167.783119 -42.062265) (xy 167.606037 -42.00894)
			(xy 167.431431 -41.947994) (xy 167.259629 -41.879542) (xy 167.090953 -41.803712) (xy 166.925721 -41.720646)
			(xy 166.764242 -41.630501) (xy 166.60682 -41.533445) (xy 166.453749 -41.42966) (xy 166.305319 -41.319343)
			(xy 166.161806 -41.202699) (xy 166.023481 -41.079948) (xy 165.890603 -40.95132) (xy 165.763422 -40.817056)
			(xy 165.642177 -40.67741) (xy 165.527094 -40.532642) (xy 165.418391 -40.383025) (xy 165.316271 -40.228839)
			(xy 165.220926 -40.070375) (xy 165.132535 -39.907929) (xy 165.051264 -39.741806) (xy 164.977266 -39.572319)
			(xy 164.910679 -39.399786) (xy 164.851628 -39.22453) (xy 164.800225 -39.04688) (xy 164.756565 -38.867171)
			(xy 164.720732 -38.685739) (xy 164.692791 -38.502925) (xy 164.672796 -38.319072) (xy 164.660784 -38.134525)
			(xy 164.656777 -37.949632) (xy 98.3488 -37.949632) (xy 98.3488 -40.923718) (xy 98.348373 -40.933787)
			(xy 98.340654 -40.952386) (xy 98.333814 -40.959786) (xy 96.306386 -42.987214) (xy 96.298991 -42.994068)
			(xy 96.280392 -43.00181) (xy 96.270318 -43.0022) (xy 65.197482 -43.0022) (xy 65.187413 -43.002627)
			(xy 65.168814 -43.010346) (xy 65.161414 -43.017186) (xy 63.997586 -44.181014) (xy 63.990732 -44.188409)
			(xy 63.98299 -44.207008) (xy 63.9826 -44.217082) (xy 63.9826 -52.324) (xy 74.167492 -52.324) (xy 74.168018 -52.272603)
			(xy 74.176356 -52.170147) (xy 74.192953 -52.068701) (xy 74.20483 -52.018692) (xy 74.206124 -52.012663)
			(xy 74.206124 -52.000337) (xy 74.20483 -51.994308) (xy 74.192966 -51.944297) (xy 74.176373 -51.842851)
			(xy 74.168025 -51.740397) (xy 74.167492 -51.689) (xy 74.168047 -51.635909) (xy 74.176921 -51.530098)
			(xy 74.194598 -51.425398) (xy 74.220954 -51.322539) (xy 74.255807 -51.222239) (xy 74.298912 -51.1252)
			(xy 74.323956 -51.078384) (xy 74.327752 -51.070769) (xy 74.330572 -51.054) (xy 74.327752 -51.037231)
			(xy 74.323956 -51.029616) (xy 74.298918 -50.982797) (xy 74.255824 -50.885755) (xy 74.220978 -50.785455)
			(xy 74.194622 -50.682597) (xy 74.17694 -50.577899) (xy 74.168055 -50.47209) (xy 74.167492 -50.419)
			(xy 74.168018 -50.367603) (xy 74.176356 -50.265147) (xy 74.192953 -50.163701) (xy 74.20483 -50.113692)
			(xy 74.206124 -50.107663) (xy 74.206124 -50.095337) (xy 74.20483 -50.089308) (xy 74.192966 -50.039297)
			(xy 74.176373 -49.937851) (xy 74.168025 -49.835397) (xy 74.167492 -49.784) (xy 74.167982 -49.734101)
			(xy 74.175812 -49.63461) (xy 74.191424 -49.536041) (xy 74.214721 -49.439) (xy 74.245561 -49.344086)
			(xy 74.283752 -49.251884) (xy 74.329059 -49.162963) (xy 74.381204 -49.077871) (xy 74.439864 -48.997133)
			(xy 74.504678 -48.921246) (xy 74.575246 -48.850678) (xy 74.651133 -48.785864) (xy 74.731871 -48.727204)
			(xy 74.816963 -48.675059) (xy 74.905884 -48.629752) (xy 74.998086 -48.591561) (xy 75.093 -48.560721)
			(xy 75.190041 -48.537424) (xy 75.28861 -48.521812) (xy 75.388101 -48.513982) (xy 75.487899 -48.513982)
			(xy 75.58739 -48.521812) (xy 75.685959 -48.537424) (xy 75.783 -48.560721) (xy 75.877914 -48.591561)
			(xy 75.970116 -48.629752) (xy 76.059037 -48.675059) (xy 76.144129 -48.727204) (xy 76.224867 -48.785864)
			(xy 76.300754 -48.850678) (xy 76.371322 -48.921246) (xy 76.436136 -48.997133) (xy 76.494796 -49.077871)
			(xy 76.546941 -49.162963) (xy 76.592248 -49.251884) (xy 76.630439 -49.344086) (xy 76.661279 -49.439)
			(xy 76.684576 -49.536041) (xy 76.700188 -49.63461) (xy 76.708018 -49.734101) (xy 76.708508 -49.784)
			(xy 76.707982 -49.835397) (xy 76.699644 -49.937853) (xy 76.683047 -50.039299) (xy 76.67117 -50.089308)
			(xy 76.669876 -50.095337) (xy 76.669876 -50.107663) (xy 76.67117 -50.113692) (xy 76.683034 -50.163703)
			(xy 76.699627 -50.265149) (xy 76.707975 -50.367603) (xy 76.708508 -50.419) (xy 76.707953 -50.472091)
			(xy 76.699079 -50.577902) (xy 76.681402 -50.682602) (xy 76.655046 -50.785461) (xy 76.620193 -50.885761)
			(xy 76.577088 -50.9828) (xy 76.552044 -51.029616) (xy 76.548248 -51.037231) (xy 76.545428 -51.054)
			(xy 76.548248 -51.070769) (xy 76.552044 -51.078384) (xy 76.577082 -51.125203) (xy 76.620176 -51.222245)
			(xy 76.655022 -51.322545) (xy 76.681378 -51.425403) (xy 76.69906 -51.530101) (xy 76.707945 -51.63591)
			(xy 76.708508 -51.689) (xy 76.707982 -51.740397) (xy 76.699644 -51.842853) (xy 76.683047 -51.944299)
			(xy 76.67117 -51.994308) (xy 76.669876 -52.000337) (xy 76.669876 -52.012663) (xy 76.67117 -52.018692)
			(xy 76.683034 -52.068703) (xy 76.699627 -52.170149) (xy 76.707975 -52.272603) (xy 76.708508 -52.324)
			(xy 79.628492 -52.324) (xy 79.629018 -52.272603) (xy 79.637356 -52.170147) (xy 79.653953 -52.068701)
			(xy 79.66583 -52.018692) (xy 79.667124 -52.012663) (xy 79.667124 -52.000337) (xy 79.66583 -51.994308)
			(xy 79.653966 -51.944297) (xy 79.637373 -51.842851) (xy 79.629025 -51.740397) (xy 79.628492 -51.689)
			(xy 79.629047 -51.635909) (xy 79.637921 -51.530098) (xy 79.655598 -51.425398) (xy 79.681954 -51.322539)
			(xy 79.716807 -51.222239) (xy 79.759912 -51.1252) (xy 79.784956 -51.078384) (xy 79.788752 -51.070769)
			(xy 79.791572 -51.054) (xy 79.788752 -51.037231) (xy 79.784956 -51.029616) (xy 79.759918 -50.982797)
			(xy 79.716824 -50.885755) (xy 79.681978 -50.785455) (xy 79.655622 -50.682597) (xy 79.63794 -50.577899)
			(xy 79.629055 -50.47209) (xy 79.628492 -50.419) (xy 79.629018 -50.367603) (xy 79.637356 -50.265147)
			(xy 79.653953 -50.163701) (xy 79.66583 -50.113692) (xy 79.667124 -50.107663) (xy 79.667124 -50.095337)
			(xy 79.66583 -50.089308) (xy 79.653966 -50.039297) (xy 79.637373 -49.937851) (xy 79.629025 -49.835397)
			(xy 79.628492 -49.784) (xy 79.628982 -49.734101) (xy 79.636812 -49.63461) (xy 79.652424 -49.536041)
			(xy 79.675721 -49.439) (xy 79.706561 -49.344086) (xy 79.744752 -49.251884) (xy 79.790059 -49.162963)
			(xy 79.842204 -49.077871) (xy 79.900864 -48.997133) (xy 79.965678 -48.921246) (xy 80.036246 -48.850678)
			(xy 80.112133 -48.785864) (xy 80.192871 -48.727204) (xy 80.277963 -48.675059) (xy 80.366884 -48.629752)
			(xy 80.459086 -48.591561) (xy 80.554 -48.560721) (xy 80.651041 -48.537424) (xy 80.74961 -48.521812)
			(xy 80.849101 -48.513982) (xy 80.948899 -48.513982) (xy 81.04839 -48.521812) (xy 81.146959 -48.537424)
			(xy 81.244 -48.560721) (xy 81.338914 -48.591561) (xy 81.431116 -48.629752) (xy 81.520037 -48.675059)
			(xy 81.605129 -48.727204) (xy 81.685867 -48.785864) (xy 81.761754 -48.850678) (xy 81.832322 -48.921246)
			(xy 81.897136 -48.997133) (xy 81.955796 -49.077871) (xy 82.007941 -49.162963) (xy 82.053248 -49.251884)
			(xy 82.091439 -49.344086) (xy 82.122279 -49.439) (xy 82.145576 -49.536041) (xy 82.161188 -49.63461)
			(xy 82.169018 -49.734101) (xy 82.169508 -49.784) (xy 82.168982 -49.835397) (xy 82.160644 -49.937853)
			(xy 82.144047 -50.039299) (xy 82.13217 -50.089308) (xy 82.130876 -50.095337) (xy 82.130876 -50.107663)
			(xy 82.13217 -50.113692) (xy 82.144034 -50.163703) (xy 82.160627 -50.265149) (xy 82.168975 -50.367603)
			(xy 82.169508 -50.419) (xy 82.168953 -50.472091) (xy 82.160079 -50.577902) (xy 82.142402 -50.682602)
			(xy 82.116046 -50.785461) (xy 82.081193 -50.885761) (xy 82.038088 -50.9828) (xy 82.013044 -51.029616)
			(xy 82.009248 -51.037231) (xy 82.006428 -51.054) (xy 82.009248 -51.070769) (xy 82.013044 -51.078384)
			(xy 82.038082 -51.125203) (xy 82.081176 -51.222245) (xy 82.116022 -51.322545) (xy 82.142378 -51.425403)
			(xy 82.16006 -51.530101) (xy 82.168945 -51.63591) (xy 82.169508 -51.689) (xy 82.168982 -51.740397)
			(xy 82.160644 -51.842853) (xy 82.144047 -51.944299) (xy 82.13217 -51.994308) (xy 82.130876 -52.000337)
			(xy 82.130876 -52.012663) (xy 82.13217 -52.018692) (xy 82.144034 -52.068703) (xy 82.160627 -52.170149)
			(xy 82.168975 -52.272603) (xy 82.169508 -52.324) (xy 85.089492 -52.324) (xy 85.090018 -52.272603)
			(xy 85.098356 -52.170147) (xy 85.114953 -52.068701) (xy 85.12683 -52.018692) (xy 85.128124 -52.012663)
			(xy 85.128124 -52.000337) (xy 85.12683 -51.994308) (xy 85.114966 -51.944297) (xy 85.098373 -51.842851)
			(xy 85.090025 -51.740397) (xy 85.089492 -51.689) (xy 85.090047 -51.635909) (xy 85.098921 -51.530098)
			(xy 85.116598 -51.425398) (xy 85.142954 -51.322539) (xy 85.177807 -51.222239) (xy 85.220912 -51.1252)
			(xy 85.245956 -51.078384) (xy 85.249752 -51.070769) (xy 85.252572 -51.054) (xy 85.249752 -51.037231)
			(xy 85.245956 -51.029616) (xy 85.220918 -50.982797) (xy 85.177824 -50.885755) (xy 85.142978 -50.785455)
			(xy 85.116622 -50.682597) (xy 85.09894 -50.577899) (xy 85.090055 -50.47209) (xy 85.089492 -50.419)
			(xy 85.090018 -50.367603) (xy 85.098356 -50.265147) (xy 85.114953 -50.163701) (xy 85.12683 -50.113692)
			(xy 85.128124 -50.107663) (xy 85.128124 -50.095337) (xy 85.12683 -50.089308) (xy 85.114966 -50.039297)
			(xy 85.098373 -49.937851) (xy 85.090025 -49.835397) (xy 85.089492 -49.784) (xy 85.089982 -49.734101)
			(xy 85.097812 -49.63461) (xy 85.113424 -49.536041) (xy 85.136721 -49.439) (xy 85.167561 -49.344086)
			(xy 85.205752 -49.251884) (xy 85.251059 -49.162963) (xy 85.303204 -49.077871) (xy 85.361864 -48.997133)
			(xy 85.426678 -48.921246) (xy 85.497246 -48.850678) (xy 85.573133 -48.785864) (xy 85.653871 -48.727204)
			(xy 85.738963 -48.675059) (xy 85.827884 -48.629752) (xy 85.920086 -48.591561) (xy 86.015 -48.560721)
			(xy 86.112041 -48.537424) (xy 86.21061 -48.521812) (xy 86.310101 -48.513982) (xy 86.409899 -48.513982)
			(xy 86.50939 -48.521812) (xy 86.607959 -48.537424) (xy 86.705 -48.560721) (xy 86.799914 -48.591561)
			(xy 86.892116 -48.629752) (xy 86.981037 -48.675059) (xy 87.066129 -48.727204) (xy 87.146867 -48.785864)
			(xy 87.222754 -48.850678) (xy 87.293322 -48.921246) (xy 87.358136 -48.997133) (xy 87.416796 -49.077871)
			(xy 87.468941 -49.162963) (xy 87.514248 -49.251884) (xy 87.552439 -49.344086) (xy 87.583279 -49.439)
			(xy 87.606576 -49.536041) (xy 87.622188 -49.63461) (xy 87.630018 -49.734101) (xy 87.630508 -49.784)
			(xy 87.629982 -49.835397) (xy 87.621644 -49.937853) (xy 87.605047 -50.039299) (xy 87.59317 -50.089308)
			(xy 87.591876 -50.095337) (xy 87.591876 -50.107663) (xy 87.59317 -50.113692) (xy 87.605034 -50.163703)
			(xy 87.621627 -50.265149) (xy 87.629975 -50.367603) (xy 87.630508 -50.419) (xy 87.629953 -50.472091)
			(xy 87.621079 -50.577902) (xy 87.603402 -50.682602) (xy 87.577046 -50.785461) (xy 87.542193 -50.885761)
			(xy 87.499088 -50.9828) (xy 87.474044 -51.029616) (xy 87.470248 -51.037231) (xy 87.467428 -51.054)
			(xy 87.470248 -51.070769) (xy 87.474044 -51.078384) (xy 87.499082 -51.125203) (xy 87.542176 -51.222245)
			(xy 87.577022 -51.322545) (xy 87.603378 -51.425403) (xy 87.62106 -51.530101) (xy 87.629945 -51.63591)
			(xy 87.630508 -51.689) (xy 87.629982 -51.740397) (xy 87.621644 -51.842853) (xy 87.605047 -51.944299)
			(xy 87.59317 -51.994308) (xy 87.591876 -52.000337) (xy 87.591876 -52.012663) (xy 87.59317 -52.018692)
			(xy 87.605034 -52.068703) (xy 87.621627 -52.170149) (xy 87.629975 -52.272603) (xy 87.630508 -52.324)
			(xy 90.550492 -52.324) (xy 90.551018 -52.272603) (xy 90.559356 -52.170147) (xy 90.575953 -52.068701)
			(xy 90.58783 -52.018692) (xy 90.589124 -52.012663) (xy 90.589124 -52.000337) (xy 90.58783 -51.994308)
			(xy 90.575966 -51.944297) (xy 90.559373 -51.842851) (xy 90.551025 -51.740397) (xy 90.550492 -51.689)
			(xy 90.551047 -51.635909) (xy 90.559921 -51.530098) (xy 90.577598 -51.425398) (xy 90.603954 -51.322539)
			(xy 90.638807 -51.222239) (xy 90.681912 -51.1252) (xy 90.706956 -51.078384) (xy 90.710752 -51.070769)
			(xy 90.713572 -51.054) (xy 90.710752 -51.037231) (xy 90.706956 -51.029616) (xy 90.681918 -50.982797)
			(xy 90.638824 -50.885755) (xy 90.603978 -50.785455) (xy 90.577622 -50.682597) (xy 90.55994 -50.577899)
			(xy 90.551055 -50.47209) (xy 90.550492 -50.419) (xy 90.551018 -50.367603) (xy 90.559356 -50.265147)
			(xy 90.575953 -50.163701) (xy 90.58783 -50.113692) (xy 90.589124 -50.107663) (xy 90.589124 -50.095337)
			(xy 90.58783 -50.089308) (xy 90.575966 -50.039297) (xy 90.559373 -49.937851) (xy 90.551025 -49.835397)
			(xy 90.550492 -49.784) (xy 90.550982 -49.734101) (xy 90.558812 -49.63461) (xy 90.574424 -49.536041)
			(xy 90.597721 -49.439) (xy 90.628561 -49.344086) (xy 90.666752 -49.251884) (xy 90.712059 -49.162963)
			(xy 90.764204 -49.077871) (xy 90.822864 -48.997133) (xy 90.887678 -48.921246) (xy 90.958246 -48.850678)
			(xy 91.034133 -48.785864) (xy 91.114871 -48.727204) (xy 91.199963 -48.675059) (xy 91.288884 -48.629752)
			(xy 91.381086 -48.591561) (xy 91.476 -48.560721) (xy 91.573041 -48.537424) (xy 91.67161 -48.521812)
			(xy 91.771101 -48.513982) (xy 91.870899 -48.513982) (xy 91.97039 -48.521812) (xy 92.068959 -48.537424)
			(xy 92.166 -48.560721) (xy 92.260914 -48.591561) (xy 92.353116 -48.629752) (xy 92.442037 -48.675059)
			(xy 92.527129 -48.727204) (xy 92.607867 -48.785864) (xy 92.683754 -48.850678) (xy 92.754322 -48.921246)
			(xy 92.819136 -48.997133) (xy 92.877796 -49.077871) (xy 92.929941 -49.162963) (xy 92.975248 -49.251884)
			(xy 93.013439 -49.344086) (xy 93.044279 -49.439) (xy 93.067576 -49.536041) (xy 93.083188 -49.63461)
			(xy 93.091018 -49.734101) (xy 93.091508 -49.784) (xy 93.090982 -49.835397) (xy 93.082644 -49.937853)
			(xy 93.066047 -50.039299) (xy 93.05417 -50.089308) (xy 93.052876 -50.095337) (xy 93.052876 -50.107663)
			(xy 93.05417 -50.113692) (xy 93.066034 -50.163703) (xy 93.082627 -50.265149) (xy 93.090975 -50.367603)
			(xy 93.091508 -50.419) (xy 93.090953 -50.472091) (xy 93.082079 -50.577902) (xy 93.064402 -50.682602)
			(xy 93.038046 -50.785461) (xy 93.003193 -50.885761) (xy 92.960088 -50.9828) (xy 92.935044 -51.029616)
			(xy 92.931248 -51.037231) (xy 92.928428 -51.054) (xy 92.931248 -51.070769) (xy 92.935044 -51.078384)
			(xy 92.960082 -51.125203) (xy 93.003176 -51.222245) (xy 93.038022 -51.322545) (xy 93.064378 -51.425403)
			(xy 93.08206 -51.530101) (xy 93.090945 -51.63591) (xy 93.091508 -51.689) (xy 93.090982 -51.740397)
			(xy 93.082644 -51.842853) (xy 93.066047 -51.944299) (xy 93.05417 -51.994308) (xy 93.052876 -52.000337)
			(xy 93.052876 -52.012663) (xy 93.05417 -52.018692) (xy 93.066034 -52.068703) (xy 93.082627 -52.170149)
			(xy 93.090975 -52.272603) (xy 93.091508 -52.324) (xy 96.011492 -52.324) (xy 96.012018 -52.272603)
			(xy 96.020356 -52.170147) (xy 96.036953 -52.068701) (xy 96.04883 -52.018692) (xy 96.050124 -52.012663)
			(xy 96.050124 -52.000337) (xy 96.04883 -51.994308) (xy 96.036966 -51.944297) (xy 96.020373 -51.842851)
			(xy 96.012025 -51.740397) (xy 96.011492 -51.689) (xy 96.012047 -51.635909) (xy 96.020921 -51.530098)
			(xy 96.038598 -51.425398) (xy 96.064954 -51.322539) (xy 96.099807 -51.222239) (xy 96.142912 -51.1252)
			(xy 96.167956 -51.078384) (xy 96.171752 -51.070769) (xy 96.174572 -51.054) (xy 96.171752 -51.037231)
			(xy 96.167956 -51.029616) (xy 96.142918 -50.982797) (xy 96.099824 -50.885755) (xy 96.064978 -50.785455)
			(xy 96.038622 -50.682597) (xy 96.02094 -50.577899) (xy 96.012055 -50.47209) (xy 96.011492 -50.419)
			(xy 96.012018 -50.367603) (xy 96.020356 -50.265147) (xy 96.036953 -50.163701) (xy 96.04883 -50.113692)
			(xy 96.050124 -50.107663) (xy 96.050124 -50.095337) (xy 96.04883 -50.089308) (xy 96.036966 -50.039297)
			(xy 96.020373 -49.937851) (xy 96.012025 -49.835397) (xy 96.011492 -49.784) (xy 96.011982 -49.734101)
			(xy 96.019812 -49.63461) (xy 96.035424 -49.536041) (xy 96.058721 -49.439) (xy 96.089561 -49.344086)
			(xy 96.127752 -49.251884) (xy 96.173059 -49.162963) (xy 96.225204 -49.077871) (xy 96.283864 -48.997133)
			(xy 96.348678 -48.921246) (xy 96.419246 -48.850678) (xy 96.495133 -48.785864) (xy 96.575871 -48.727204)
			(xy 96.660963 -48.675059) (xy 96.749884 -48.629752) (xy 96.842086 -48.591561) (xy 96.937 -48.560721)
			(xy 97.034041 -48.537424) (xy 97.13261 -48.521812) (xy 97.232101 -48.513982) (xy 97.331899 -48.513982)
			(xy 97.43139 -48.521812) (xy 97.529959 -48.537424) (xy 97.627 -48.560721) (xy 97.721914 -48.591561)
			(xy 97.814116 -48.629752) (xy 97.903037 -48.675059) (xy 97.988129 -48.727204) (xy 98.068867 -48.785864)
			(xy 98.144754 -48.850678) (xy 98.215322 -48.921246) (xy 98.280136 -48.997133) (xy 98.338796 -49.077871)
			(xy 98.390941 -49.162963) (xy 98.436248 -49.251884) (xy 98.474439 -49.344086) (xy 98.505279 -49.439)
			(xy 98.528576 -49.536041) (xy 98.544188 -49.63461) (xy 98.552018 -49.734101) (xy 98.552508 -49.784)
			(xy 98.551982 -49.835397) (xy 98.543644 -49.937853) (xy 98.527047 -50.039299) (xy 98.51517 -50.089308)
			(xy 98.513876 -50.095337) (xy 98.513876 -50.107663) (xy 98.51517 -50.113692) (xy 98.527034 -50.163703)
			(xy 98.543627 -50.265149) (xy 98.551975 -50.367603) (xy 98.552508 -50.419) (xy 98.551953 -50.472091)
			(xy 98.543079 -50.577902) (xy 98.525402 -50.682602) (xy 98.499046 -50.785461) (xy 98.464193 -50.885761)
			(xy 98.421088 -50.9828) (xy 98.396044 -51.029616) (xy 98.392248 -51.037231) (xy 98.389428 -51.054)
			(xy 98.392248 -51.070769) (xy 98.396044 -51.078384) (xy 98.421082 -51.125203) (xy 98.464176 -51.222245)
			(xy 98.499022 -51.322545) (xy 98.525378 -51.425403) (xy 98.54306 -51.530101) (xy 98.551945 -51.63591)
			(xy 98.552508 -51.689) (xy 98.551982 -51.740397) (xy 98.543644 -51.842853) (xy 98.527047 -51.944299)
			(xy 98.51517 -51.994308) (xy 98.513876 -52.000337) (xy 98.513876 -52.012663) (xy 98.51517 -52.018692)
			(xy 98.527034 -52.068703) (xy 98.543627 -52.170149) (xy 98.551975 -52.272603) (xy 98.552508 -52.324)
			(xy 101.472492 -52.324) (xy 101.473018 -52.272603) (xy 101.481356 -52.170147) (xy 101.497953 -52.068701)
			(xy 101.50983 -52.018692) (xy 101.511124 -52.012663) (xy 101.511124 -52.000337) (xy 101.50983 -51.994308)
			(xy 101.497966 -51.944297) (xy 101.481373 -51.842851) (xy 101.473025 -51.740397) (xy 101.472492 -51.689)
			(xy 101.473047 -51.635909) (xy 101.481921 -51.530098) (xy 101.499598 -51.425398) (xy 101.525954 -51.322539)
			(xy 101.560807 -51.222239) (xy 101.603912 -51.1252) (xy 101.628956 -51.078384) (xy 101.632752 -51.070769)
			(xy 101.635572 -51.054) (xy 101.632752 -51.037231) (xy 101.628956 -51.029616) (xy 101.603918 -50.982797)
			(xy 101.560824 -50.885755) (xy 101.525978 -50.785455) (xy 101.499622 -50.682597) (xy 101.48194 -50.577899)
			(xy 101.473055 -50.47209) (xy 101.472492 -50.419) (xy 101.473018 -50.367603) (xy 101.481356 -50.265147)
			(xy 101.497953 -50.163701) (xy 101.50983 -50.113692) (xy 101.511124 -50.107663) (xy 101.511124 -50.095337)
			(xy 101.50983 -50.089308) (xy 101.497966 -50.039297) (xy 101.481373 -49.937851) (xy 101.473025 -49.835397)
			(xy 101.472492 -49.784) (xy 101.472982 -49.734101) (xy 101.480812 -49.63461) (xy 101.496424 -49.536041)
			(xy 101.519721 -49.439) (xy 101.550561 -49.344086) (xy 101.588752 -49.251884) (xy 101.634059 -49.162963)
			(xy 101.686204 -49.077871) (xy 101.744864 -48.997133) (xy 101.809678 -48.921246) (xy 101.880246 -48.850678)
			(xy 101.956133 -48.785864) (xy 102.036871 -48.727204) (xy 102.121963 -48.675059) (xy 102.210884 -48.629752)
			(xy 102.303086 -48.591561) (xy 102.398 -48.560721) (xy 102.495041 -48.537424) (xy 102.59361 -48.521812)
			(xy 102.693101 -48.513982) (xy 102.792899 -48.513982) (xy 102.89239 -48.521812) (xy 102.990959 -48.537424)
			(xy 103.088 -48.560721) (xy 103.182914 -48.591561) (xy 103.275116 -48.629752) (xy 103.364037 -48.675059)
			(xy 103.449129 -48.727204) (xy 103.529867 -48.785864) (xy 103.605754 -48.850678) (xy 103.676322 -48.921246)
			(xy 103.741136 -48.997133) (xy 103.799796 -49.077871) (xy 103.851941 -49.162963) (xy 103.897248 -49.251884)
			(xy 103.935439 -49.344086) (xy 103.966279 -49.439) (xy 103.989576 -49.536041) (xy 104.005188 -49.63461)
			(xy 104.013018 -49.734101) (xy 104.013508 -49.784) (xy 104.012982 -49.835397) (xy 104.004644 -49.937853)
			(xy 103.988047 -50.039299) (xy 103.97617 -50.089308) (xy 103.974876 -50.095337) (xy 103.974876 -50.107663)
			(xy 103.97617 -50.113692) (xy 103.988034 -50.163703) (xy 104.004627 -50.265149) (xy 104.012975 -50.367603)
			(xy 104.013508 -50.419) (xy 104.012953 -50.472091) (xy 104.004079 -50.577902) (xy 103.986402 -50.682602)
			(xy 103.960046 -50.785461) (xy 103.925193 -50.885761) (xy 103.882088 -50.9828) (xy 103.857044 -51.029616)
			(xy 103.853248 -51.037231) (xy 103.850428 -51.054) (xy 103.853248 -51.070769) (xy 103.857044 -51.078384)
			(xy 103.882082 -51.125203) (xy 103.925176 -51.222245) (xy 103.960022 -51.322545) (xy 103.986378 -51.425403)
			(xy 104.00406 -51.530101) (xy 104.012945 -51.63591) (xy 104.013508 -51.689) (xy 104.012982 -51.740397)
			(xy 104.004644 -51.842853) (xy 103.988047 -51.944299) (xy 103.97617 -51.994308) (xy 103.974876 -52.000337)
			(xy 103.974876 -52.012663) (xy 103.97617 -52.018692) (xy 103.988034 -52.068703) (xy 104.004627 -52.170149)
			(xy 104.012975 -52.272603) (xy 104.013508 -52.324) (xy 106.933492 -52.324) (xy 106.934018 -52.272603)
			(xy 106.942356 -52.170147) (xy 106.958953 -52.068701) (xy 106.97083 -52.018692) (xy 106.972124 -52.012663)
			(xy 106.972124 -52.000337) (xy 106.97083 -51.994308) (xy 106.958966 -51.944297) (xy 106.942373 -51.842851)
			(xy 106.934025 -51.740397) (xy 106.933492 -51.689) (xy 106.934047 -51.635909) (xy 106.942921 -51.530098)
			(xy 106.960598 -51.425398) (xy 106.986954 -51.322539) (xy 107.021807 -51.222239) (xy 107.064912 -51.1252)
			(xy 107.089956 -51.078384) (xy 107.093752 -51.070769) (xy 107.096572 -51.054) (xy 107.093752 -51.037231)
			(xy 107.089956 -51.029616) (xy 107.064918 -50.982797) (xy 107.021824 -50.885755) (xy 106.986978 -50.785455)
			(xy 106.960622 -50.682597) (xy 106.94294 -50.577899) (xy 106.934055 -50.47209) (xy 106.933492 -50.419)
			(xy 106.934018 -50.367603) (xy 106.942356 -50.265147) (xy 106.958953 -50.163701) (xy 106.97083 -50.113692)
			(xy 106.972124 -50.107663) (xy 106.972124 -50.095337) (xy 106.97083 -50.089308) (xy 106.958966 -50.039297)
			(xy 106.942373 -49.937851) (xy 106.934025 -49.835397) (xy 106.933492 -49.784) (xy 106.933982 -49.734101)
			(xy 106.941812 -49.63461) (xy 106.957424 -49.536041) (xy 106.980721 -49.439) (xy 107.011561 -49.344086)
			(xy 107.049752 -49.251884) (xy 107.095059 -49.162963) (xy 107.147204 -49.077871) (xy 107.205864 -48.997133)
			(xy 107.270678 -48.921246) (xy 107.341246 -48.850678) (xy 107.417133 -48.785864) (xy 107.497871 -48.727204)
			(xy 107.582963 -48.675059) (xy 107.671884 -48.629752) (xy 107.764086 -48.591561) (xy 107.859 -48.560721)
			(xy 107.956041 -48.537424) (xy 108.05461 -48.521812) (xy 108.154101 -48.513982) (xy 108.253899 -48.513982)
			(xy 108.35339 -48.521812) (xy 108.451959 -48.537424) (xy 108.549 -48.560721) (xy 108.643914 -48.591561)
			(xy 108.736116 -48.629752) (xy 108.825037 -48.675059) (xy 108.910129 -48.727204) (xy 108.990867 -48.785864)
			(xy 109.066754 -48.850678) (xy 109.137322 -48.921246) (xy 109.202136 -48.997133) (xy 109.260796 -49.077871)
			(xy 109.312941 -49.162963) (xy 109.358248 -49.251884) (xy 109.396439 -49.344086) (xy 109.427279 -49.439)
			(xy 109.450576 -49.536041) (xy 109.466188 -49.63461) (xy 109.474018 -49.734101) (xy 109.474508 -49.784)
			(xy 109.473982 -49.835397) (xy 109.465644 -49.937853) (xy 109.449047 -50.039299) (xy 109.43717 -50.089308)
			(xy 109.435876 -50.095337) (xy 109.435876 -50.107663) (xy 109.43717 -50.113692) (xy 109.449034 -50.163703)
			(xy 109.465627 -50.265149) (xy 109.473975 -50.367603) (xy 109.474508 -50.419) (xy 109.473953 -50.472091)
			(xy 109.465079 -50.577902) (xy 109.447402 -50.682602) (xy 109.421046 -50.785461) (xy 109.386193 -50.885761)
			(xy 109.343088 -50.9828) (xy 109.318044 -51.029616) (xy 109.314248 -51.037231) (xy 109.311428 -51.054)
			(xy 109.314248 -51.070769) (xy 109.318044 -51.078384) (xy 109.343082 -51.125203) (xy 109.386176 -51.222245)
			(xy 109.421022 -51.322545) (xy 109.447378 -51.425403) (xy 109.46506 -51.530101) (xy 109.473945 -51.63591)
			(xy 109.474508 -51.689) (xy 109.473982 -51.740397) (xy 109.465644 -51.842853) (xy 109.449047 -51.944299)
			(xy 109.43717 -51.994308) (xy 109.435876 -52.000337) (xy 109.435876 -52.012663) (xy 109.43717 -52.018692)
			(xy 109.449034 -52.068703) (xy 109.465627 -52.170149) (xy 109.467815 -52.197) (xy 152.272492 -52.197)
			(xy 152.273018 -52.145603) (xy 152.281356 -52.043147) (xy 152.297953 -51.941701) (xy 152.30983 -51.891692)
			(xy 152.311124 -51.885663) (xy 152.311124 -51.873337) (xy 152.30983 -51.867308) (xy 152.297966 -51.817297)
			(xy 152.281373 -51.715851) (xy 152.273025 -51.613397) (xy 152.272492 -51.562) (xy 152.273047 -51.508909)
			(xy 152.281921 -51.403098) (xy 152.299598 -51.298398) (xy 152.325954 -51.195539) (xy 152.360807 -51.095239)
			(xy 152.403912 -50.9982) (xy 152.428956 -50.951384) (xy 152.432752 -50.943769) (xy 152.435572 -50.927)
			(xy 152.432752 -50.910231) (xy 152.428956 -50.902616) (xy 152.403918 -50.855797) (xy 152.360824 -50.758755)
			(xy 152.325978 -50.658455) (xy 152.299622 -50.555597) (xy 152.28194 -50.450899) (xy 152.273055 -50.34509)
			(xy 152.272492 -50.292) (xy 152.273018 -50.240603) (xy 152.281356 -50.138147) (xy 152.297953 -50.036701)
			(xy 152.30983 -49.986692) (xy 152.311124 -49.980663) (xy 152.311124 -49.968337) (xy 152.30983 -49.962308)
			(xy 152.297966 -49.912297) (xy 152.281373 -49.810851) (xy 152.273025 -49.708397) (xy 152.272492 -49.657)
			(xy 152.272982 -49.607101) (xy 152.280812 -49.50761) (xy 152.296424 -49.409041) (xy 152.319721 -49.312)
			(xy 152.350561 -49.217086) (xy 152.388752 -49.124884) (xy 152.434059 -49.035963) (xy 152.486204 -48.950871)
			(xy 152.544864 -48.870133) (xy 152.609678 -48.794246) (xy 152.680246 -48.723678) (xy 152.756133 -48.658864)
			(xy 152.836871 -48.600204) (xy 152.921963 -48.548059) (xy 153.010884 -48.502752) (xy 153.103086 -48.464561)
			(xy 153.198 -48.433721) (xy 153.295041 -48.410424) (xy 153.39361 -48.394812) (xy 153.493101 -48.386982)
			(xy 153.592899 -48.386982) (xy 153.69239 -48.394812) (xy 153.790959 -48.410424) (xy 153.888 -48.433721)
			(xy 153.982914 -48.464561) (xy 154.075116 -48.502752) (xy 154.164037 -48.548059) (xy 154.249129 -48.600204)
			(xy 154.329867 -48.658864) (xy 154.405754 -48.723678) (xy 154.476322 -48.794246) (xy 154.541136 -48.870133)
			(xy 154.599796 -48.950871) (xy 154.651941 -49.035963) (xy 154.697248 -49.124884) (xy 154.735439 -49.217086)
			(xy 154.766279 -49.312) (xy 154.789576 -49.409041) (xy 154.805188 -49.50761) (xy 154.813018 -49.607101)
			(xy 154.813508 -49.657) (xy 154.812982 -49.708397) (xy 154.804644 -49.810853) (xy 154.788047 -49.912299)
			(xy 154.77617 -49.962308) (xy 154.774876 -49.968337) (xy 154.774876 -49.980663) (xy 154.77617 -49.986692)
			(xy 154.788034 -50.036703) (xy 154.804627 -50.138149) (xy 154.812975 -50.240603) (xy 154.813508 -50.292)
			(xy 154.812953 -50.345091) (xy 154.804079 -50.450902) (xy 154.786402 -50.555602) (xy 154.760046 -50.658461)
			(xy 154.725193 -50.758761) (xy 154.682088 -50.8558) (xy 154.657044 -50.902616) (xy 154.653248 -50.910231)
			(xy 154.650428 -50.927) (xy 154.653248 -50.943769) (xy 154.657044 -50.951384) (xy 154.682082 -50.998203)
			(xy 154.725176 -51.095245) (xy 154.760022 -51.195545) (xy 154.786378 -51.298403) (xy 154.80406 -51.403101)
			(xy 154.812945 -51.50891) (xy 154.813508 -51.562) (xy 154.812982 -51.613397) (xy 154.804644 -51.715853)
			(xy 154.788047 -51.817299) (xy 154.77617 -51.867308) (xy 154.774876 -51.873337) (xy 154.774876 -51.885663)
			(xy 154.77617 -51.891692) (xy 154.788034 -51.941703) (xy 154.804627 -52.043149) (xy 154.812975 -52.145603)
			(xy 154.813508 -52.197) (xy 157.733492 -52.197) (xy 157.734018 -52.145603) (xy 157.742356 -52.043147)
			(xy 157.758953 -51.941701) (xy 157.77083 -51.891692) (xy 157.772124 -51.885663) (xy 157.772124 -51.873337)
			(xy 157.77083 -51.867308) (xy 157.758966 -51.817297) (xy 157.742373 -51.715851) (xy 157.734025 -51.613397)
			(xy 157.733492 -51.562) (xy 157.734047 -51.508909) (xy 157.742921 -51.403098) (xy 157.760598 -51.298398)
			(xy 157.786954 -51.195539) (xy 157.821807 -51.095239) (xy 157.864912 -50.9982) (xy 157.889956 -50.951384)
			(xy 157.893752 -50.943769) (xy 157.896572 -50.927) (xy 157.893752 -50.910231) (xy 157.889956 -50.902616)
			(xy 157.864918 -50.855797) (xy 157.821824 -50.758755) (xy 157.786978 -50.658455) (xy 157.760622 -50.555597)
			(xy 157.74294 -50.450899) (xy 157.734055 -50.34509) (xy 157.733492 -50.292) (xy 157.734018 -50.240603)
			(xy 157.742356 -50.138147) (xy 157.758953 -50.036701) (xy 157.77083 -49.986692) (xy 157.772124 -49.980663)
			(xy 157.772124 -49.968337) (xy 157.77083 -49.962308) (xy 157.758966 -49.912297) (xy 157.742373 -49.810851)
			(xy 157.734025 -49.708397) (xy 157.733492 -49.657) (xy 157.733982 -49.607101) (xy 157.741812 -49.50761)
			(xy 157.757424 -49.409041) (xy 157.780721 -49.312) (xy 157.811561 -49.217086) (xy 157.849752 -49.124884)
			(xy 157.895059 -49.035963) (xy 157.947204 -48.950871) (xy 158.005864 -48.870133) (xy 158.070678 -48.794246)
			(xy 158.141246 -48.723678) (xy 158.217133 -48.658864) (xy 158.297871 -48.600204) (xy 158.382963 -48.548059)
			(xy 158.471884 -48.502752) (xy 158.564086 -48.464561) (xy 158.659 -48.433721) (xy 158.756041 -48.410424)
			(xy 158.85461 -48.394812) (xy 158.954101 -48.386982) (xy 159.053899 -48.386982) (xy 159.15339 -48.394812)
			(xy 159.251959 -48.410424) (xy 159.349 -48.433721) (xy 159.443914 -48.464561) (xy 159.536116 -48.502752)
			(xy 159.625037 -48.548059) (xy 159.710129 -48.600204) (xy 159.790867 -48.658864) (xy 159.866754 -48.723678)
			(xy 159.937322 -48.794246) (xy 160.002136 -48.870133) (xy 160.060796 -48.950871) (xy 160.112941 -49.035963)
			(xy 160.158248 -49.124884) (xy 160.196439 -49.217086) (xy 160.227279 -49.312) (xy 160.250576 -49.409041)
			(xy 160.266188 -49.50761) (xy 160.274018 -49.607101) (xy 160.274508 -49.657) (xy 160.273982 -49.708397)
			(xy 160.265644 -49.810853) (xy 160.249047 -49.912299) (xy 160.23717 -49.962308) (xy 160.235876 -49.968337)
			(xy 160.235876 -49.980663) (xy 160.23717 -49.986692) (xy 160.249034 -50.036703) (xy 160.265627 -50.138149)
			(xy 160.273975 -50.240603) (xy 160.274508 -50.292) (xy 160.273953 -50.345091) (xy 160.265079 -50.450902)
			(xy 160.247402 -50.555602) (xy 160.221046 -50.658461) (xy 160.186193 -50.758761) (xy 160.143088 -50.8558)
			(xy 160.118044 -50.902616) (xy 160.114248 -50.910231) (xy 160.111428 -50.927) (xy 160.114248 -50.943769)
			(xy 160.118044 -50.951384) (xy 160.143082 -50.998203) (xy 160.186176 -51.095245) (xy 160.221022 -51.195545)
			(xy 160.247378 -51.298403) (xy 160.26506 -51.403101) (xy 160.273945 -51.50891) (xy 160.274508 -51.562)
			(xy 160.273982 -51.613397) (xy 160.265644 -51.715853) (xy 160.249047 -51.817299) (xy 160.23717 -51.867308)
			(xy 160.235876 -51.873337) (xy 160.235876 -51.885663) (xy 160.23717 -51.891692) (xy 160.249034 -51.941703)
			(xy 160.265627 -52.043149) (xy 160.273975 -52.145603) (xy 160.274508 -52.197) (xy 163.194492 -52.197)
			(xy 163.195018 -52.145603) (xy 163.203356 -52.043147) (xy 163.219953 -51.941701) (xy 163.23183 -51.891692)
			(xy 163.233124 -51.885663) (xy 163.233124 -51.873337) (xy 163.23183 -51.867308) (xy 163.219966 -51.817297)
			(xy 163.203373 -51.715851) (xy 163.195025 -51.613397) (xy 163.194492 -51.562) (xy 163.195047 -51.508909)
			(xy 163.203921 -51.403098) (xy 163.221598 -51.298398) (xy 163.247954 -51.195539) (xy 163.282807 -51.095239)
			(xy 163.325912 -50.9982) (xy 163.350956 -50.951384) (xy 163.354752 -50.943769) (xy 163.357572 -50.927)
			(xy 163.354752 -50.910231) (xy 163.350956 -50.902616) (xy 163.325918 -50.855797) (xy 163.282824 -50.758755)
			(xy 163.247978 -50.658455) (xy 163.221622 -50.555597) (xy 163.20394 -50.450899) (xy 163.195055 -50.34509)
			(xy 163.194492 -50.292) (xy 163.195018 -50.240603) (xy 163.203356 -50.138147) (xy 163.219953 -50.036701)
			(xy 163.23183 -49.986692) (xy 163.233124 -49.980663) (xy 163.233124 -49.968337) (xy 163.23183 -49.962308)
			(xy 163.219966 -49.912297) (xy 163.203373 -49.810851) (xy 163.195025 -49.708397) (xy 163.194492 -49.657)
			(xy 163.194982 -49.607101) (xy 163.202812 -49.50761) (xy 163.218424 -49.409041) (xy 163.241721 -49.312)
			(xy 163.272561 -49.217086) (xy 163.310752 -49.124884) (xy 163.356059 -49.035963) (xy 163.408204 -48.950871)
			(xy 163.466864 -48.870133) (xy 163.531678 -48.794246) (xy 163.602246 -48.723678) (xy 163.678133 -48.658864)
			(xy 163.758871 -48.600204) (xy 163.843963 -48.548059) (xy 163.932884 -48.502752) (xy 164.025086 -48.464561)
			(xy 164.12 -48.433721) (xy 164.217041 -48.410424) (xy 164.31561 -48.394812) (xy 164.415101 -48.386982)
			(xy 164.514899 -48.386982) (xy 164.61439 -48.394812) (xy 164.712959 -48.410424) (xy 164.81 -48.433721)
			(xy 164.904914 -48.464561) (xy 164.997116 -48.502752) (xy 165.086037 -48.548059) (xy 165.171129 -48.600204)
			(xy 165.251867 -48.658864) (xy 165.327754 -48.723678) (xy 165.398322 -48.794246) (xy 165.463136 -48.870133)
			(xy 165.521796 -48.950871) (xy 165.573941 -49.035963) (xy 165.619248 -49.124884) (xy 165.657439 -49.217086)
			(xy 165.688279 -49.312) (xy 165.711576 -49.409041) (xy 165.727188 -49.50761) (xy 165.735018 -49.607101)
			(xy 165.735508 -49.657) (xy 165.734982 -49.708397) (xy 165.726644 -49.810853) (xy 165.710047 -49.912299)
			(xy 165.69817 -49.962308) (xy 165.696876 -49.968337) (xy 165.696876 -49.980663) (xy 165.69817 -49.986692)
			(xy 165.710034 -50.036703) (xy 165.726627 -50.138149) (xy 165.734975 -50.240603) (xy 165.735508 -50.292)
			(xy 165.734953 -50.345091) (xy 165.726079 -50.450902) (xy 165.708402 -50.555602) (xy 165.682046 -50.658461)
			(xy 165.647193 -50.758761) (xy 165.604088 -50.8558) (xy 165.579044 -50.902616) (xy 165.575248 -50.910231)
			(xy 165.572428 -50.927) (xy 165.575248 -50.943769) (xy 165.579044 -50.951384) (xy 165.604082 -50.998203)
			(xy 165.647176 -51.095245) (xy 165.682022 -51.195545) (xy 165.708378 -51.298403) (xy 165.72606 -51.403101)
			(xy 165.734945 -51.50891) (xy 165.735508 -51.562) (xy 165.734982 -51.613397) (xy 165.726644 -51.715853)
			(xy 165.710047 -51.817299) (xy 165.69817 -51.867308) (xy 165.696876 -51.873337) (xy 165.696876 -51.885663)
			(xy 165.69817 -51.891692) (xy 165.710034 -51.941703) (xy 165.726627 -52.043149) (xy 165.734975 -52.145603)
			(xy 165.735508 -52.197) (xy 168.655492 -52.197) (xy 168.656018 -52.145603) (xy 168.664356 -52.043147)
			(xy 168.680953 -51.941701) (xy 168.69283 -51.891692) (xy 168.694124 -51.885663) (xy 168.694124 -51.873337)
			(xy 168.69283 -51.867308) (xy 168.680966 -51.817297) (xy 168.664373 -51.715851) (xy 168.656025 -51.613397)
			(xy 168.655492 -51.562) (xy 168.656047 -51.508909) (xy 168.664921 -51.403098) (xy 168.682598 -51.298398)
			(xy 168.708954 -51.195539) (xy 168.743807 -51.095239) (xy 168.786912 -50.9982) (xy 168.811956 -50.951384)
			(xy 168.815752 -50.943769) (xy 168.818572 -50.927) (xy 168.815752 -50.910231) (xy 168.811956 -50.902616)
			(xy 168.786918 -50.855797) (xy 168.743824 -50.758755) (xy 168.708978 -50.658455) (xy 168.682622 -50.555597)
			(xy 168.66494 -50.450899) (xy 168.656055 -50.34509) (xy 168.655492 -50.292) (xy 168.656018 -50.240603)
			(xy 168.664356 -50.138147) (xy 168.680953 -50.036701) (xy 168.69283 -49.986692) (xy 168.694124 -49.980663)
			(xy 168.694124 -49.968337) (xy 168.69283 -49.962308) (xy 168.680966 -49.912297) (xy 168.664373 -49.810851)
			(xy 168.656025 -49.708397) (xy 168.655492 -49.657) (xy 168.655982 -49.607101) (xy 168.663812 -49.50761)
			(xy 168.679424 -49.409041) (xy 168.702721 -49.312) (xy 168.733561 -49.217086) (xy 168.771752 -49.124884)
			(xy 168.817059 -49.035963) (xy 168.869204 -48.950871) (xy 168.927864 -48.870133) (xy 168.992678 -48.794246)
			(xy 169.063246 -48.723678) (xy 169.139133 -48.658864) (xy 169.219871 -48.600204) (xy 169.304963 -48.548059)
			(xy 169.393884 -48.502752) (xy 169.486086 -48.464561) (xy 169.581 -48.433721) (xy 169.678041 -48.410424)
			(xy 169.77661 -48.394812) (xy 169.876101 -48.386982) (xy 169.975899 -48.386982) (xy 170.07539 -48.394812)
			(xy 170.173959 -48.410424) (xy 170.271 -48.433721) (xy 170.365914 -48.464561) (xy 170.458116 -48.502752)
			(xy 170.547037 -48.548059) (xy 170.632129 -48.600204) (xy 170.712867 -48.658864) (xy 170.788754 -48.723678)
			(xy 170.859322 -48.794246) (xy 170.924136 -48.870133) (xy 170.982796 -48.950871) (xy 171.034941 -49.035963)
			(xy 171.080248 -49.124884) (xy 171.118439 -49.217086) (xy 171.149279 -49.312) (xy 171.172576 -49.409041)
			(xy 171.188188 -49.50761) (xy 171.196018 -49.607101) (xy 171.196508 -49.657) (xy 171.195982 -49.708397)
			(xy 171.187644 -49.810853) (xy 171.171047 -49.912299) (xy 171.15917 -49.962308) (xy 171.157876 -49.968337)
			(xy 171.157876 -49.980663) (xy 171.15917 -49.986692) (xy 171.171034 -50.036703) (xy 171.187627 -50.138149)
			(xy 171.195975 -50.240603) (xy 171.196508 -50.292) (xy 171.195953 -50.345091) (xy 171.187079 -50.450902)
			(xy 171.169402 -50.555602) (xy 171.143046 -50.658461) (xy 171.108193 -50.758761) (xy 171.065088 -50.8558)
			(xy 171.040044 -50.902616) (xy 171.036248 -50.910231) (xy 171.033428 -50.927) (xy 171.036248 -50.943769)
			(xy 171.040044 -50.951384) (xy 171.065082 -50.998203) (xy 171.108176 -51.095245) (xy 171.143022 -51.195545)
			(xy 171.169378 -51.298403) (xy 171.18706 -51.403101) (xy 171.195945 -51.50891) (xy 171.196508 -51.562)
			(xy 171.195982 -51.613397) (xy 171.187644 -51.715853) (xy 171.171047 -51.817299) (xy 171.15917 -51.867308)
			(xy 171.157876 -51.873337) (xy 171.157876 -51.885663) (xy 171.15917 -51.891692) (xy 171.171034 -51.941703)
			(xy 171.187627 -52.043149) (xy 171.195975 -52.145603) (xy 171.196508 -52.197) (xy 174.116492 -52.197)
			(xy 174.117018 -52.145603) (xy 174.125356 -52.043147) (xy 174.141953 -51.941701) (xy 174.15383 -51.891692)
			(xy 174.155124 -51.885663) (xy 174.155124 -51.873337) (xy 174.15383 -51.867308) (xy 174.141966 -51.817297)
			(xy 174.125373 -51.715851) (xy 174.117025 -51.613397) (xy 174.116492 -51.562) (xy 174.117047 -51.508909)
			(xy 174.125921 -51.403098) (xy 174.143598 -51.298398) (xy 174.169954 -51.195539) (xy 174.204807 -51.095239)
			(xy 174.247912 -50.9982) (xy 174.272956 -50.951384) (xy 174.276752 -50.943769) (xy 174.279572 -50.927)
			(xy 174.276752 -50.910231) (xy 174.272956 -50.902616) (xy 174.247918 -50.855797) (xy 174.204824 -50.758755)
			(xy 174.169978 -50.658455) (xy 174.143622 -50.555597) (xy 174.12594 -50.450899) (xy 174.117055 -50.34509)
			(xy 174.116492 -50.292) (xy 174.117018 -50.240603) (xy 174.125356 -50.138147) (xy 174.141953 -50.036701)
			(xy 174.15383 -49.986692) (xy 174.155124 -49.980663) (xy 174.155124 -49.968337) (xy 174.15383 -49.962308)
			(xy 174.141966 -49.912297) (xy 174.125373 -49.810851) (xy 174.117025 -49.708397) (xy 174.116492 -49.657)
			(xy 174.116982 -49.607101) (xy 174.124812 -49.50761) (xy 174.140424 -49.409041) (xy 174.163721 -49.312)
			(xy 174.194561 -49.217086) (xy 174.232752 -49.124884) (xy 174.278059 -49.035963) (xy 174.330204 -48.950871)
			(xy 174.388864 -48.870133) (xy 174.453678 -48.794246) (xy 174.524246 -48.723678) (xy 174.600133 -48.658864)
			(xy 174.680871 -48.600204) (xy 174.765963 -48.548059) (xy 174.854884 -48.502752) (xy 174.947086 -48.464561)
			(xy 175.042 -48.433721) (xy 175.139041 -48.410424) (xy 175.23761 -48.394812) (xy 175.337101 -48.386982)
			(xy 175.436899 -48.386982) (xy 175.53639 -48.394812) (xy 175.634959 -48.410424) (xy 175.732 -48.433721)
			(xy 175.826914 -48.464561) (xy 175.919116 -48.502752) (xy 176.008037 -48.548059) (xy 176.093129 -48.600204)
			(xy 176.173867 -48.658864) (xy 176.249754 -48.723678) (xy 176.320322 -48.794246) (xy 176.385136 -48.870133)
			(xy 176.443796 -48.950871) (xy 176.495941 -49.035963) (xy 176.541248 -49.124884) (xy 176.579439 -49.217086)
			(xy 176.610279 -49.312) (xy 176.633576 -49.409041) (xy 176.649188 -49.50761) (xy 176.657018 -49.607101)
			(xy 176.657508 -49.657) (xy 176.656982 -49.708397) (xy 176.648644 -49.810853) (xy 176.632047 -49.912299)
			(xy 176.62017 -49.962308) (xy 176.618876 -49.968337) (xy 176.618876 -49.980663) (xy 176.62017 -49.986692)
			(xy 176.632034 -50.036703) (xy 176.648627 -50.138149) (xy 176.656975 -50.240603) (xy 176.657508 -50.292)
			(xy 176.656953 -50.345091) (xy 176.648079 -50.450902) (xy 176.630402 -50.555602) (xy 176.604046 -50.658461)
			(xy 176.569193 -50.758761) (xy 176.526088 -50.8558) (xy 176.501044 -50.902616) (xy 176.497248 -50.910231)
			(xy 176.494428 -50.927) (xy 176.497248 -50.943769) (xy 176.501044 -50.951384) (xy 176.526082 -50.998203)
			(xy 176.569176 -51.095245) (xy 176.604022 -51.195545) (xy 176.630378 -51.298403) (xy 176.64806 -51.403101)
			(xy 176.656945 -51.50891) (xy 176.657508 -51.562) (xy 176.656982 -51.613397) (xy 176.648644 -51.715853)
			(xy 176.632047 -51.817299) (xy 176.62017 -51.867308) (xy 176.618876 -51.873337) (xy 176.618876 -51.885663)
			(xy 176.62017 -51.891692) (xy 176.632034 -51.941703) (xy 176.648627 -52.043149) (xy 176.656975 -52.145603)
			(xy 176.657508 -52.197) (xy 179.574952 -52.197) (xy 179.575479 -52.145603) (xy 179.583817 -52.043147)
			(xy 179.600413 -51.941701) (xy 179.61229 -51.891692) (xy 179.613582 -51.885663) (xy 179.613582 -51.873337)
			(xy 179.61229 -51.867308) (xy 179.600425 -51.817297) (xy 179.583833 -51.715851) (xy 179.575485 -51.613397)
			(xy 179.574952 -51.562) (xy 179.575512 -51.508909) (xy 179.584385 -51.403099) (xy 179.602062 -51.298398)
			(xy 179.628418 -51.195539) (xy 179.663269 -51.09524) (xy 179.706373 -50.9982) (xy 179.731416 -50.951384)
			(xy 179.735209 -50.943769) (xy 179.738025 -50.927) (xy 179.735209 -50.910231) (xy 179.731416 -50.902616)
			(xy 179.706374 -50.855799) (xy 179.663282 -50.758756) (xy 179.628436 -50.658455) (xy 179.602081 -50.555597)
			(xy 179.5844 -50.450899) (xy 179.575515 -50.34509) (xy 179.574952 -50.292) (xy 179.575479 -50.240603)
			(xy 179.583817 -50.138147) (xy 179.600413 -50.036701) (xy 179.61229 -49.986692) (xy 179.613582 -49.980663)
			(xy 179.613582 -49.968337) (xy 179.61229 -49.962308) (xy 179.600425 -49.912297) (xy 179.583833 -49.810851)
			(xy 179.575485 -49.708397) (xy 179.574952 -49.657) (xy 179.575442 -49.607101) (xy 179.583272 -49.50761)
			(xy 179.598884 -49.409041) (xy 179.622181 -49.312) (xy 179.653021 -49.217086) (xy 179.691212 -49.124884)
			(xy 179.736519 -49.035963) (xy 179.788664 -48.950871) (xy 179.847324 -48.870133) (xy 179.912138 -48.794246)
			(xy 179.982706 -48.723678) (xy 180.058593 -48.658864) (xy 180.139331 -48.600204) (xy 180.224423 -48.548059)
			(xy 180.313344 -48.502752) (xy 180.405546 -48.464561) (xy 180.50046 -48.433721) (xy 180.597501 -48.410424)
			(xy 180.69607 -48.394812) (xy 180.795561 -48.386982) (xy 180.895359 -48.386982) (xy 180.99485 -48.394812)
			(xy 181.093419 -48.410424) (xy 181.19046 -48.433721) (xy 181.285374 -48.464561) (xy 181.377576 -48.502752)
			(xy 181.466497 -48.548059) (xy 181.551589 -48.600204) (xy 181.632327 -48.658864) (xy 181.708214 -48.723678)
			(xy 181.778782 -48.794246) (xy 181.843596 -48.870133) (xy 181.902256 -48.950871) (xy 181.954401 -49.035963)
			(xy 181.999708 -49.124884) (xy 182.037899 -49.217086) (xy 182.068739 -49.312) (xy 182.092036 -49.409041)
			(xy 182.107648 -49.50761) (xy 182.115478 -49.607101) (xy 182.115968 -49.657) (xy 182.115441 -49.708397)
			(xy 182.107103 -49.810853) (xy 182.090506 -49.912299) (xy 182.07863 -49.962308) (xy 182.077337 -49.968337)
			(xy 182.077337 -49.980663) (xy 182.07863 -49.986692) (xy 182.090496 -50.036703) (xy 182.107087 -50.138149)
			(xy 182.115435 -50.240603) (xy 182.115968 -50.292) (xy 182.115405 -50.345091) (xy 182.106532 -50.450901)
			(xy 182.088856 -50.555601) (xy 182.062501 -50.65846) (xy 182.02765 -50.75876) (xy 181.984547 -50.855799)
			(xy 181.959504 -50.902616) (xy 181.95571 -50.910231) (xy 181.952893 -50.927) (xy 181.95571 -50.943769)
			(xy 181.959504 -50.951384) (xy 181.984548 -50.9982) (xy 182.02764 -51.095243) (xy 182.062485 -51.195544)
			(xy 182.088839 -51.298402) (xy 182.106521 -51.403101) (xy 182.115405 -51.50891) (xy 182.115968 -51.562)
			(xy 182.115441 -51.613397) (xy 182.107103 -51.715853) (xy 182.090506 -51.817299) (xy 182.07863 -51.867308)
			(xy 182.077337 -51.873337) (xy 182.077337 -51.885663) (xy 182.07863 -51.891692) (xy 182.090496 -51.941703)
			(xy 182.107087 -52.043149) (xy 182.115435 -52.145603) (xy 182.115968 -52.197) (xy 185.035952 -52.197)
			(xy 185.036479 -52.145603) (xy 185.044817 -52.043147) (xy 185.061413 -51.941701) (xy 185.07329 -51.891692)
			(xy 185.074582 -51.885663) (xy 185.074582 -51.873337) (xy 185.07329 -51.867308) (xy 185.061425 -51.817297)
			(xy 185.044833 -51.715851) (xy 185.036485 -51.613397) (xy 185.035952 -51.562) (xy 185.036512 -51.508909)
			(xy 185.045385 -51.403099) (xy 185.063062 -51.298398) (xy 185.089418 -51.195539) (xy 185.124269 -51.09524)
			(xy 185.167373 -50.9982) (xy 185.192416 -50.951384) (xy 185.196209 -50.943769) (xy 185.199025 -50.927)
			(xy 185.196209 -50.910231) (xy 185.192416 -50.902616) (xy 185.167374 -50.855799) (xy 185.124282 -50.758756)
			(xy 185.089436 -50.658455) (xy 185.063081 -50.555597) (xy 185.0454 -50.450899) (xy 185.036515 -50.34509)
			(xy 185.035952 -50.292) (xy 185.036479 -50.240603) (xy 185.044817 -50.138147) (xy 185.061413 -50.036701)
			(xy 185.07329 -49.986692) (xy 185.074582 -49.980663) (xy 185.074582 -49.968337) (xy 185.07329 -49.962308)
			(xy 185.061425 -49.912297) (xy 185.044833 -49.810851) (xy 185.036485 -49.708397) (xy 185.035952 -49.657)
			(xy 185.036442 -49.607101) (xy 185.044272 -49.50761) (xy 185.059884 -49.409041) (xy 185.083181 -49.312)
			(xy 185.114021 -49.217086) (xy 185.152212 -49.124884) (xy 185.197519 -49.035963) (xy 185.249664 -48.950871)
			(xy 185.308324 -48.870133) (xy 185.373138 -48.794246) (xy 185.443706 -48.723678) (xy 185.519593 -48.658864)
			(xy 185.600331 -48.600204) (xy 185.685423 -48.548059) (xy 185.774344 -48.502752) (xy 185.866546 -48.464561)
			(xy 185.96146 -48.433721) (xy 186.058501 -48.410424) (xy 186.15707 -48.394812) (xy 186.256561 -48.386982)
			(xy 186.356359 -48.386982) (xy 186.45585 -48.394812) (xy 186.554419 -48.410424) (xy 186.65146 -48.433721)
			(xy 186.746374 -48.464561) (xy 186.838576 -48.502752) (xy 186.927497 -48.548059) (xy 187.012589 -48.600204)
			(xy 187.093327 -48.658864) (xy 187.169214 -48.723678) (xy 187.239782 -48.794246) (xy 187.304596 -48.870133)
			(xy 187.363256 -48.950871) (xy 187.415401 -49.035963) (xy 187.460708 -49.124884) (xy 187.498899 -49.217086)
			(xy 187.529739 -49.312) (xy 187.553036 -49.409041) (xy 187.568648 -49.50761) (xy 187.576478 -49.607101)
			(xy 187.576968 -49.657) (xy 187.576441 -49.708397) (xy 187.568103 -49.810853) (xy 187.551506 -49.912299)
			(xy 187.53963 -49.962308) (xy 187.538337 -49.968337) (xy 187.538337 -49.980663) (xy 187.53963 -49.986692)
			(xy 187.551496 -50.036703) (xy 187.568087 -50.138149) (xy 187.576435 -50.240603) (xy 187.576968 -50.292)
			(xy 187.576405 -50.345091) (xy 187.567532 -50.450901) (xy 187.549856 -50.555601) (xy 187.523501 -50.65846)
			(xy 187.48865 -50.75876) (xy 187.445547 -50.855799) (xy 187.420504 -50.902616) (xy 187.41671 -50.910231)
			(xy 187.413893 -50.927) (xy 187.41671 -50.943769) (xy 187.420504 -50.951384) (xy 187.445548 -50.9982)
			(xy 187.48864 -51.095243) (xy 187.523485 -51.195544) (xy 187.549839 -51.298402) (xy 187.567521 -51.403101)
			(xy 187.576405 -51.50891) (xy 187.576968 -51.562) (xy 187.576441 -51.613397) (xy 187.568103 -51.715853)
			(xy 187.551506 -51.817299) (xy 187.53963 -51.867308) (xy 187.538337 -51.873337) (xy 187.538337 -51.885663)
			(xy 187.53963 -51.891692) (xy 187.551496 -51.941703) (xy 187.568087 -52.043149) (xy 187.576435 -52.145603)
			(xy 187.576968 -52.197) (xy 187.576478 -52.246899) (xy 187.568648 -52.34639) (xy 187.553036 -52.444959)
			(xy 187.529739 -52.542) (xy 187.498899 -52.636914) (xy 187.460708 -52.729116) (xy 187.415401 -52.818037)
			(xy 187.363256 -52.903129) (xy 187.304596 -52.983867) (xy 187.239782 -53.059754) (xy 187.169214 -53.130322)
			(xy 187.093327 -53.195136) (xy 187.012589 -53.253796) (xy 186.927497 -53.305941) (xy 186.838576 -53.351248)
			(xy 186.746374 -53.389439) (xy 186.65146 -53.420279) (xy 186.554419 -53.443576) (xy 186.45585 -53.459188)
			(xy 186.356359 -53.467018) (xy 186.256561 -53.467018) (xy 186.15707 -53.459188) (xy 186.058501 -53.443576)
			(xy 185.96146 -53.420279) (xy 185.866546 -53.389439) (xy 185.774344 -53.351248) (xy 185.685423 -53.305941)
			(xy 185.600331 -53.253796) (xy 185.519593 -53.195136) (xy 185.443706 -53.130322) (xy 185.373138 -53.059754)
			(xy 185.308324 -52.983867) (xy 185.249664 -52.903129) (xy 185.197519 -52.818037) (xy 185.152212 -52.729116)
			(xy 185.114021 -52.636914) (xy 185.083181 -52.542) (xy 185.059884 -52.444959) (xy 185.044272 -52.34639)
			(xy 185.036442 -52.246899) (xy 185.035952 -52.197) (xy 182.115968 -52.197) (xy 182.115478 -52.246899)
			(xy 182.107648 -52.34639) (xy 182.092036 -52.444959) (xy 182.068739 -52.542) (xy 182.037899 -52.636914)
			(xy 181.999708 -52.729116) (xy 181.954401 -52.818037) (xy 181.902256 -52.903129) (xy 181.843596 -52.983867)
			(xy 181.778782 -53.059754) (xy 181.708214 -53.130322) (xy 181.632327 -53.195136) (xy 181.551589 -53.253796)
			(xy 181.466497 -53.305941) (xy 181.377576 -53.351248) (xy 181.285374 -53.389439) (xy 181.19046 -53.420279)
			(xy 181.093419 -53.443576) (xy 180.99485 -53.459188) (xy 180.895359 -53.467018) (xy 180.795561 -53.467018)
			(xy 180.69607 -53.459188) (xy 180.597501 -53.443576) (xy 180.50046 -53.420279) (xy 180.405546 -53.389439)
			(xy 180.313344 -53.351248) (xy 180.224423 -53.305941) (xy 180.139331 -53.253796) (xy 180.058593 -53.195136)
			(xy 179.982706 -53.130322) (xy 179.912138 -53.059754) (xy 179.847324 -52.983867) (xy 179.788664 -52.903129)
			(xy 179.736519 -52.818037) (xy 179.691212 -52.729116) (xy 179.653021 -52.636914) (xy 179.622181 -52.542)
			(xy 179.598884 -52.444959) (xy 179.583272 -52.34639) (xy 179.575442 -52.246899) (xy 179.574952 -52.197)
			(xy 176.657508 -52.197) (xy 176.657018 -52.246899) (xy 176.649188 -52.34639) (xy 176.633576 -52.444959)
			(xy 176.610279 -52.542) (xy 176.579439 -52.636914) (xy 176.541248 -52.729116) (xy 176.495941 -52.818037)
			(xy 176.443796 -52.903129) (xy 176.385136 -52.983867) (xy 176.320322 -53.059754) (xy 176.249754 -53.130322)
			(xy 176.173867 -53.195136) (xy 176.093129 -53.253796) (xy 176.008037 -53.305941) (xy 175.919116 -53.351248)
			(xy 175.826914 -53.389439) (xy 175.732 -53.420279) (xy 175.634959 -53.443576) (xy 175.53639 -53.459188)
			(xy 175.436899 -53.467018) (xy 175.337101 -53.467018) (xy 175.23761 -53.459188) (xy 175.139041 -53.443576)
			(xy 175.042 -53.420279) (xy 174.947086 -53.389439) (xy 174.854884 -53.351248) (xy 174.765963 -53.305941)
			(xy 174.680871 -53.253796) (xy 174.600133 -53.195136) (xy 174.524246 -53.130322) (xy 174.453678 -53.059754)
			(xy 174.388864 -52.983867) (xy 174.330204 -52.903129) (xy 174.278059 -52.818037) (xy 174.232752 -52.729116)
			(xy 174.194561 -52.636914) (xy 174.163721 -52.542) (xy 174.140424 -52.444959) (xy 174.124812 -52.34639)
			(xy 174.116982 -52.246899) (xy 174.116492 -52.197) (xy 171.196508 -52.197) (xy 171.196018 -52.246899)
			(xy 171.188188 -52.34639) (xy 171.172576 -52.444959) (xy 171.149279 -52.542) (xy 171.118439 -52.636914)
			(xy 171.080248 -52.729116) (xy 171.034941 -52.818037) (xy 170.982796 -52.903129) (xy 170.924136 -52.983867)
			(xy 170.859322 -53.059754) (xy 170.788754 -53.130322) (xy 170.712867 -53.195136) (xy 170.632129 -53.253796)
			(xy 170.547037 -53.305941) (xy 170.458116 -53.351248) (xy 170.365914 -53.389439) (xy 170.271 -53.420279)
			(xy 170.173959 -53.443576) (xy 170.07539 -53.459188) (xy 169.975899 -53.467018) (xy 169.876101 -53.467018)
			(xy 169.77661 -53.459188) (xy 169.678041 -53.443576) (xy 169.581 -53.420279) (xy 169.486086 -53.389439)
			(xy 169.393884 -53.351248) (xy 169.304963 -53.305941) (xy 169.219871 -53.253796) (xy 169.139133 -53.195136)
			(xy 169.063246 -53.130322) (xy 168.992678 -53.059754) (xy 168.927864 -52.983867) (xy 168.869204 -52.903129)
			(xy 168.817059 -52.818037) (xy 168.771752 -52.729116) (xy 168.733561 -52.636914) (xy 168.702721 -52.542)
			(xy 168.679424 -52.444959) (xy 168.663812 -52.34639) (xy 168.655982 -52.246899) (xy 168.655492 -52.197)
			(xy 165.735508 -52.197) (xy 165.735018 -52.246899) (xy 165.727188 -52.34639) (xy 165.711576 -52.444959)
			(xy 165.688279 -52.542) (xy 165.657439 -52.636914) (xy 165.619248 -52.729116) (xy 165.573941 -52.818037)
			(xy 165.521796 -52.903129) (xy 165.463136 -52.983867) (xy 165.398322 -53.059754) (xy 165.327754 -53.130322)
			(xy 165.251867 -53.195136) (xy 165.171129 -53.253796) (xy 165.086037 -53.305941) (xy 164.997116 -53.351248)
			(xy 164.904914 -53.389439) (xy 164.81 -53.420279) (xy 164.712959 -53.443576) (xy 164.61439 -53.459188)
			(xy 164.514899 -53.467018) (xy 164.415101 -53.467018) (xy 164.31561 -53.459188) (xy 164.217041 -53.443576)
			(xy 164.12 -53.420279) (xy 164.025086 -53.389439) (xy 163.932884 -53.351248) (xy 163.843963 -53.305941)
			(xy 163.758871 -53.253796) (xy 163.678133 -53.195136) (xy 163.602246 -53.130322) (xy 163.531678 -53.059754)
			(xy 163.466864 -52.983867) (xy 163.408204 -52.903129) (xy 163.356059 -52.818037) (xy 163.310752 -52.729116)
			(xy 163.272561 -52.636914) (xy 163.241721 -52.542) (xy 163.218424 -52.444959) (xy 163.202812 -52.34639)
			(xy 163.194982 -52.246899) (xy 163.194492 -52.197) (xy 160.274508 -52.197) (xy 160.274018 -52.246899)
			(xy 160.266188 -52.34639) (xy 160.250576 -52.444959) (xy 160.227279 -52.542) (xy 160.196439 -52.636914)
			(xy 160.158248 -52.729116) (xy 160.112941 -52.818037) (xy 160.060796 -52.903129) (xy 160.002136 -52.983867)
			(xy 159.937322 -53.059754) (xy 159.866754 -53.130322) (xy 159.790867 -53.195136) (xy 159.710129 -53.253796)
			(xy 159.625037 -53.305941) (xy 159.536116 -53.351248) (xy 159.443914 -53.389439) (xy 159.349 -53.420279)
			(xy 159.251959 -53.443576) (xy 159.15339 -53.459188) (xy 159.053899 -53.467018) (xy 158.954101 -53.467018)
			(xy 158.85461 -53.459188) (xy 158.756041 -53.443576) (xy 158.659 -53.420279) (xy 158.564086 -53.389439)
			(xy 158.471884 -53.351248) (xy 158.382963 -53.305941) (xy 158.297871 -53.253796) (xy 158.217133 -53.195136)
			(xy 158.141246 -53.130322) (xy 158.070678 -53.059754) (xy 158.005864 -52.983867) (xy 157.947204 -52.903129)
			(xy 157.895059 -52.818037) (xy 157.849752 -52.729116) (xy 157.811561 -52.636914) (xy 157.780721 -52.542)
			(xy 157.757424 -52.444959) (xy 157.741812 -52.34639) (xy 157.733982 -52.246899) (xy 157.733492 -52.197)
			(xy 154.813508 -52.197) (xy 154.813018 -52.246899) (xy 154.805188 -52.34639) (xy 154.789576 -52.444959)
			(xy 154.766279 -52.542) (xy 154.735439 -52.636914) (xy 154.697248 -52.729116) (xy 154.651941 -52.818037)
			(xy 154.599796 -52.903129) (xy 154.541136 -52.983867) (xy 154.476322 -53.059754) (xy 154.405754 -53.130322)
			(xy 154.329867 -53.195136) (xy 154.249129 -53.253796) (xy 154.164037 -53.305941) (xy 154.075116 -53.351248)
			(xy 153.982914 -53.389439) (xy 153.888 -53.420279) (xy 153.790959 -53.443576) (xy 153.69239 -53.459188)
			(xy 153.592899 -53.467018) (xy 153.493101 -53.467018) (xy 153.39361 -53.459188) (xy 153.295041 -53.443576)
			(xy 153.198 -53.420279) (xy 153.103086 -53.389439) (xy 153.010884 -53.351248) (xy 152.921963 -53.305941)
			(xy 152.836871 -53.253796) (xy 152.756133 -53.195136) (xy 152.680246 -53.130322) (xy 152.609678 -53.059754)
			(xy 152.544864 -52.983867) (xy 152.486204 -52.903129) (xy 152.434059 -52.818037) (xy 152.388752 -52.729116)
			(xy 152.350561 -52.636914) (xy 152.319721 -52.542) (xy 152.296424 -52.444959) (xy 152.280812 -52.34639)
			(xy 152.272982 -52.246899) (xy 152.272492 -52.197) (xy 109.467815 -52.197) (xy 109.473975 -52.272603)
			(xy 109.474508 -52.324) (xy 109.474018 -52.373899) (xy 109.466188 -52.47339) (xy 109.450576 -52.571959)
			(xy 109.427279 -52.669) (xy 109.396439 -52.763914) (xy 109.358248 -52.856116) (xy 109.312941 -52.945037)
			(xy 109.260796 -53.030129) (xy 109.202136 -53.110867) (xy 109.137322 -53.186754) (xy 109.066754 -53.257322)
			(xy 108.990867 -53.322136) (xy 108.910129 -53.380796) (xy 108.825037 -53.432941) (xy 108.736116 -53.478248)
			(xy 108.643914 -53.516439) (xy 108.549 -53.547279) (xy 108.451959 -53.570576) (xy 108.35339 -53.586188)
			(xy 108.253899 -53.594018) (xy 108.154101 -53.594018) (xy 108.05461 -53.586188) (xy 107.956041 -53.570576)
			(xy 107.859 -53.547279) (xy 107.764086 -53.516439) (xy 107.671884 -53.478248) (xy 107.582963 -53.432941)
			(xy 107.497871 -53.380796) (xy 107.417133 -53.322136) (xy 107.341246 -53.257322) (xy 107.270678 -53.186754)
			(xy 107.205864 -53.110867) (xy 107.147204 -53.030129) (xy 107.095059 -52.945037) (xy 107.049752 -52.856116)
			(xy 107.011561 -52.763914) (xy 106.980721 -52.669) (xy 106.957424 -52.571959) (xy 106.941812 -52.47339)
			(xy 106.933982 -52.373899) (xy 106.933492 -52.324) (xy 104.013508 -52.324) (xy 104.013018 -52.373899)
			(xy 104.005188 -52.47339) (xy 103.989576 -52.571959) (xy 103.966279 -52.669) (xy 103.935439 -52.763914)
			(xy 103.897248 -52.856116) (xy 103.851941 -52.945037) (xy 103.799796 -53.030129) (xy 103.741136 -53.110867)
			(xy 103.676322 -53.186754) (xy 103.605754 -53.257322) (xy 103.529867 -53.322136) (xy 103.449129 -53.380796)
			(xy 103.364037 -53.432941) (xy 103.275116 -53.478248) (xy 103.182914 -53.516439) (xy 103.088 -53.547279)
			(xy 102.990959 -53.570576) (xy 102.89239 -53.586188) (xy 102.792899 -53.594018) (xy 102.693101 -53.594018)
			(xy 102.59361 -53.586188) (xy 102.495041 -53.570576) (xy 102.398 -53.547279) (xy 102.303086 -53.516439)
			(xy 102.210884 -53.478248) (xy 102.121963 -53.432941) (xy 102.036871 -53.380796) (xy 101.956133 -53.322136)
			(xy 101.880246 -53.257322) (xy 101.809678 -53.186754) (xy 101.744864 -53.110867) (xy 101.686204 -53.030129)
			(xy 101.634059 -52.945037) (xy 101.588752 -52.856116) (xy 101.550561 -52.763914) (xy 101.519721 -52.669)
			(xy 101.496424 -52.571959) (xy 101.480812 -52.47339) (xy 101.472982 -52.373899) (xy 101.472492 -52.324)
			(xy 98.552508 -52.324) (xy 98.552018 -52.373899) (xy 98.544188 -52.47339) (xy 98.528576 -52.571959)
			(xy 98.505279 -52.669) (xy 98.474439 -52.763914) (xy 98.436248 -52.856116) (xy 98.390941 -52.945037)
			(xy 98.338796 -53.030129) (xy 98.280136 -53.110867) (xy 98.215322 -53.186754) (xy 98.144754 -53.257322)
			(xy 98.068867 -53.322136) (xy 97.988129 -53.380796) (xy 97.903037 -53.432941) (xy 97.814116 -53.478248)
			(xy 97.721914 -53.516439) (xy 97.627 -53.547279) (xy 97.529959 -53.570576) (xy 97.43139 -53.586188)
			(xy 97.331899 -53.594018) (xy 97.232101 -53.594018) (xy 97.13261 -53.586188) (xy 97.034041 -53.570576)
			(xy 96.937 -53.547279) (xy 96.842086 -53.516439) (xy 96.749884 -53.478248) (xy 96.660963 -53.432941)
			(xy 96.575871 -53.380796) (xy 96.495133 -53.322136) (xy 96.419246 -53.257322) (xy 96.348678 -53.186754)
			(xy 96.283864 -53.110867) (xy 96.225204 -53.030129) (xy 96.173059 -52.945037) (xy 96.127752 -52.856116)
			(xy 96.089561 -52.763914) (xy 96.058721 -52.669) (xy 96.035424 -52.571959) (xy 96.019812 -52.47339)
			(xy 96.011982 -52.373899) (xy 96.011492 -52.324) (xy 93.091508 -52.324) (xy 93.091018 -52.373899)
			(xy 93.083188 -52.47339) (xy 93.067576 -52.571959) (xy 93.044279 -52.669) (xy 93.013439 -52.763914)
			(xy 92.975248 -52.856116) (xy 92.929941 -52.945037) (xy 92.877796 -53.030129) (xy 92.819136 -53.110867)
			(xy 92.754322 -53.186754) (xy 92.683754 -53.257322) (xy 92.607867 -53.322136) (xy 92.527129 -53.380796)
			(xy 92.442037 -53.432941) (xy 92.353116 -53.478248) (xy 92.260914 -53.516439) (xy 92.166 -53.547279)
			(xy 92.068959 -53.570576) (xy 91.97039 -53.586188) (xy 91.870899 -53.594018) (xy 91.771101 -53.594018)
			(xy 91.67161 -53.586188) (xy 91.573041 -53.570576) (xy 91.476 -53.547279) (xy 91.381086 -53.516439)
			(xy 91.288884 -53.478248) (xy 91.199963 -53.432941) (xy 91.114871 -53.380796) (xy 91.034133 -53.322136)
			(xy 90.958246 -53.257322) (xy 90.887678 -53.186754) (xy 90.822864 -53.110867) (xy 90.764204 -53.030129)
			(xy 90.712059 -52.945037) (xy 90.666752 -52.856116) (xy 90.628561 -52.763914) (xy 90.597721 -52.669)
			(xy 90.574424 -52.571959) (xy 90.558812 -52.47339) (xy 90.550982 -52.373899) (xy 90.550492 -52.324)
			(xy 87.630508 -52.324) (xy 87.630018 -52.373899) (xy 87.622188 -52.47339) (xy 87.606576 -52.571959)
			(xy 87.583279 -52.669) (xy 87.552439 -52.763914) (xy 87.514248 -52.856116) (xy 87.468941 -52.945037)
			(xy 87.416796 -53.030129) (xy 87.358136 -53.110867) (xy 87.293322 -53.186754) (xy 87.222754 -53.257322)
			(xy 87.146867 -53.322136) (xy 87.066129 -53.380796) (xy 86.981037 -53.432941) (xy 86.892116 -53.478248)
			(xy 86.799914 -53.516439) (xy 86.705 -53.547279) (xy 86.607959 -53.570576) (xy 86.50939 -53.586188)
			(xy 86.409899 -53.594018) (xy 86.310101 -53.594018) (xy 86.21061 -53.586188) (xy 86.112041 -53.570576)
			(xy 86.015 -53.547279) (xy 85.920086 -53.516439) (xy 85.827884 -53.478248) (xy 85.738963 -53.432941)
			(xy 85.653871 -53.380796) (xy 85.573133 -53.322136) (xy 85.497246 -53.257322) (xy 85.426678 -53.186754)
			(xy 85.361864 -53.110867) (xy 85.303204 -53.030129) (xy 85.251059 -52.945037) (xy 85.205752 -52.856116)
			(xy 85.167561 -52.763914) (xy 85.136721 -52.669) (xy 85.113424 -52.571959) (xy 85.097812 -52.47339)
			(xy 85.089982 -52.373899) (xy 85.089492 -52.324) (xy 82.169508 -52.324) (xy 82.169018 -52.373899)
			(xy 82.161188 -52.47339) (xy 82.145576 -52.571959) (xy 82.122279 -52.669) (xy 82.091439 -52.763914)
			(xy 82.053248 -52.856116) (xy 82.007941 -52.945037) (xy 81.955796 -53.030129) (xy 81.897136 -53.110867)
			(xy 81.832322 -53.186754) (xy 81.761754 -53.257322) (xy 81.685867 -53.322136) (xy 81.605129 -53.380796)
			(xy 81.520037 -53.432941) (xy 81.431116 -53.478248) (xy 81.338914 -53.516439) (xy 81.244 -53.547279)
			(xy 81.146959 -53.570576) (xy 81.04839 -53.586188) (xy 80.948899 -53.594018) (xy 80.849101 -53.594018)
			(xy 80.74961 -53.586188) (xy 80.651041 -53.570576) (xy 80.554 -53.547279) (xy 80.459086 -53.516439)
			(xy 80.366884 -53.478248) (xy 80.277963 -53.432941) (xy 80.192871 -53.380796) (xy 80.112133 -53.322136)
			(xy 80.036246 -53.257322) (xy 79.965678 -53.186754) (xy 79.900864 -53.110867) (xy 79.842204 -53.030129)
			(xy 79.790059 -52.945037) (xy 79.744752 -52.856116) (xy 79.706561 -52.763914) (xy 79.675721 -52.669)
			(xy 79.652424 -52.571959) (xy 79.636812 -52.47339) (xy 79.628982 -52.373899) (xy 79.628492 -52.324)
			(xy 76.708508 -52.324) (xy 76.708018 -52.373899) (xy 76.700188 -52.47339) (xy 76.684576 -52.571959)
			(xy 76.661279 -52.669) (xy 76.630439 -52.763914) (xy 76.592248 -52.856116) (xy 76.546941 -52.945037)
			(xy 76.494796 -53.030129) (xy 76.436136 -53.110867) (xy 76.371322 -53.186754) (xy 76.300754 -53.257322)
			(xy 76.224867 -53.322136) (xy 76.144129 -53.380796) (xy 76.059037 -53.432941) (xy 75.970116 -53.478248)
			(xy 75.877914 -53.516439) (xy 75.783 -53.547279) (xy 75.685959 -53.570576) (xy 75.58739 -53.586188)
			(xy 75.487899 -53.594018) (xy 75.388101 -53.594018) (xy 75.28861 -53.586188) (xy 75.190041 -53.570576)
			(xy 75.093 -53.547279) (xy 74.998086 -53.516439) (xy 74.905884 -53.478248) (xy 74.816963 -53.432941)
			(xy 74.731871 -53.380796) (xy 74.651133 -53.322136) (xy 74.575246 -53.257322) (xy 74.504678 -53.186754)
			(xy 74.439864 -53.110867) (xy 74.381204 -53.030129) (xy 74.329059 -52.945037) (xy 74.283752 -52.856116)
			(xy 74.245561 -52.763914) (xy 74.214721 -52.669) (xy 74.191424 -52.571959) (xy 74.175812 -52.47339)
			(xy 74.167982 -52.373899) (xy 74.167492 -52.324) (xy 63.9826 -52.324) (xy 63.9826 -56.019455) (xy 66.293988 -56.019455)
			(xy 66.293988 -55.900565) (xy 66.301929 -55.781939) (xy 66.317776 -55.664109) (xy 66.341457 -55.547601)
			(xy 66.372868 -55.432934) (xy 66.411867 -55.320622) (xy 66.458281 -55.211165) (xy 66.511902 -55.105053)
			(xy 66.57249 -55.002759) (xy 66.639776 -54.90474) (xy 66.713459 -54.811435) (xy 66.793209 -54.723259)
			(xy 66.878671 -54.640607) (xy 66.969462 -54.563848) (xy 67.065177 -54.493324) (xy 67.165389 -54.429351)
			(xy 67.269651 -54.372215) (xy 67.377496 -54.322169) (xy 67.488442 -54.279439) (xy 67.601995 -54.244215)
			(xy 67.717647 -54.216653) (xy 67.834882 -54.196878) (xy 67.953176 -54.184978) (xy 68.072 -54.181005)
			(xy 68.190824 -54.184978) (xy 68.309118 -54.196878) (xy 68.426353 -54.216653) (xy 68.542005 -54.244215)
			(xy 68.655558 -54.279439) (xy 68.766504 -54.322169) (xy 68.874349 -54.372215) (xy 68.978611 -54.429351)
			(xy 69.078823 -54.493324) (xy 69.174538 -54.563848) (xy 69.265329 -54.640607) (xy 69.350791 -54.723259)
			(xy 69.430541 -54.811435) (xy 69.504224 -54.90474) (xy 69.57151 -55.002759) (xy 69.632098 -55.105053)
			(xy 69.685719 -55.211165) (xy 69.732133 -55.320622) (xy 69.771132 -55.432934) (xy 69.802543 -55.547601)
			(xy 69.826224 -55.664109) (xy 69.842071 -55.781939) (xy 69.850012 -55.900565) (xy 69.850508 -55.96001)
			(xy 69.850012 -56.019455) (xy 77.596988 -56.019455) (xy 77.596988 -55.900565) (xy 77.604929 -55.781939)
			(xy 77.620776 -55.664109) (xy 77.644457 -55.547601) (xy 77.675868 -55.432934) (xy 77.714867 -55.320622)
			(xy 77.761281 -55.211165) (xy 77.814902 -55.105053) (xy 77.87549 -55.002759) (xy 77.942776 -54.90474)
			(xy 78.016459 -54.811435) (xy 78.096209 -54.723259) (xy 78.181671 -54.640607) (xy 78.272462 -54.563848)
			(xy 78.368177 -54.493324) (xy 78.468389 -54.429351) (xy 78.572651 -54.372215) (xy 78.680496 -54.322169)
			(xy 78.791442 -54.279439) (xy 78.904995 -54.244215) (xy 79.020647 -54.216653) (xy 79.137882 -54.196878)
			(xy 79.256176 -54.184978) (xy 79.375 -54.181005) (xy 79.493824 -54.184978) (xy 79.612118 -54.196878)
			(xy 79.729353 -54.216653) (xy 79.845005 -54.244215) (xy 79.958558 -54.279439) (xy 80.069504 -54.322169)
			(xy 80.177349 -54.372215) (xy 80.281611 -54.429351) (xy 80.381823 -54.493324) (xy 80.477538 -54.563848)
			(xy 80.568329 -54.640607) (xy 80.653791 -54.723259) (xy 80.733541 -54.811435) (xy 80.807224 -54.90474)
			(xy 80.87451 -55.002759) (xy 80.935098 -55.105053) (xy 80.988719 -55.211165) (xy 81.035133 -55.320622)
			(xy 81.074132 -55.432934) (xy 81.105543 -55.547601) (xy 81.129224 -55.664109) (xy 81.145071 -55.781939)
			(xy 81.153012 -55.900565) (xy 81.153508 -55.96001) (xy 81.153012 -56.019455) (xy 88.899988 -56.019455)
			(xy 88.899988 -55.900565) (xy 88.907929 -55.781939) (xy 88.923776 -55.664109) (xy 88.947457 -55.547601)
			(xy 88.978868 -55.432934) (xy 89.017867 -55.320622) (xy 89.064281 -55.211165) (xy 89.117902 -55.105053)
			(xy 89.17849 -55.002759) (xy 89.245776 -54.90474) (xy 89.319459 -54.811435) (xy 89.399209 -54.723259)
			(xy 89.484671 -54.640607) (xy 89.575462 -54.563848) (xy 89.671177 -54.493324) (xy 89.771389 -54.429351)
			(xy 89.875651 -54.372215) (xy 89.983496 -54.322169) (xy 90.094442 -54.279439) (xy 90.207995 -54.244215)
			(xy 90.323647 -54.216653) (xy 90.440882 -54.196878) (xy 90.559176 -54.184978) (xy 90.678 -54.181005)
			(xy 90.796824 -54.184978) (xy 90.915118 -54.196878) (xy 91.032353 -54.216653) (xy 91.148005 -54.244215)
			(xy 91.261558 -54.279439) (xy 91.372504 -54.322169) (xy 91.480349 -54.372215) (xy 91.584611 -54.429351)
			(xy 91.684823 -54.493324) (xy 91.780538 -54.563848) (xy 91.871329 -54.640607) (xy 91.956791 -54.723259)
			(xy 92.036541 -54.811435) (xy 92.110224 -54.90474) (xy 92.17751 -55.002759) (xy 92.238098 -55.105053)
			(xy 92.291719 -55.211165) (xy 92.338133 -55.320622) (xy 92.377132 -55.432934) (xy 92.408543 -55.547601)
			(xy 92.432224 -55.664109) (xy 92.448071 -55.781939) (xy 92.456012 -55.900565) (xy 92.456508 -55.96001)
			(xy 92.456012 -56.019455) (xy 107.060988 -56.019455) (xy 107.060988 -55.900565) (xy 107.068929 -55.781939)
			(xy 107.084776 -55.664109) (xy 107.108457 -55.547601) (xy 107.139868 -55.432934) (xy 107.178867 -55.320622)
			(xy 107.225281 -55.211165) (xy 107.278902 -55.105053) (xy 107.33949 -55.002759) (xy 107.406776 -54.90474)
			(xy 107.480459 -54.811435) (xy 107.560209 -54.723259) (xy 107.645671 -54.640607) (xy 107.736462 -54.563848)
			(xy 107.832177 -54.493324) (xy 107.932389 -54.429351) (xy 108.036651 -54.372215) (xy 108.144496 -54.322169)
			(xy 108.255442 -54.279439) (xy 108.368995 -54.244215) (xy 108.484647 -54.216653) (xy 108.601882 -54.196878)
			(xy 108.720176 -54.184978) (xy 108.839 -54.181005) (xy 108.957824 -54.184978) (xy 109.076118 -54.196878)
			(xy 109.193353 -54.216653) (xy 109.309005 -54.244215) (xy 109.422558 -54.279439) (xy 109.533504 -54.322169)
			(xy 109.641349 -54.372215) (xy 109.745611 -54.429351) (xy 109.845823 -54.493324) (xy 109.941538 -54.563848)
			(xy 110.032329 -54.640607) (xy 110.117791 -54.723259) (xy 110.197541 -54.811435) (xy 110.271224 -54.90474)
			(xy 110.33851 -55.002759) (xy 110.399098 -55.105053) (xy 110.452719 -55.211165) (xy 110.499133 -55.320622)
			(xy 110.538132 -55.432934) (xy 110.569543 -55.547601) (xy 110.593224 -55.664109) (xy 110.609071 -55.781939)
			(xy 110.617012 -55.900565) (xy 110.617508 -55.96001) (xy 110.617012 -56.019455) (xy 118.236988 -56.019455)
			(xy 118.236988 -55.900565) (xy 118.244929 -55.781939) (xy 118.260776 -55.664109) (xy 118.284457 -55.547601)
			(xy 118.315868 -55.432934) (xy 118.354867 -55.320622) (xy 118.401281 -55.211165) (xy 118.454902 -55.105053)
			(xy 118.51549 -55.002759) (xy 118.582776 -54.90474) (xy 118.656459 -54.811435) (xy 118.736209 -54.723259)
			(xy 118.821671 -54.640607) (xy 118.912462 -54.563848) (xy 119.008177 -54.493324) (xy 119.108389 -54.429351)
			(xy 119.212651 -54.372215) (xy 119.320496 -54.322169) (xy 119.431442 -54.279439) (xy 119.544995 -54.244215)
			(xy 119.660647 -54.216653) (xy 119.777882 -54.196878) (xy 119.896176 -54.184978) (xy 120.015 -54.181005)
			(xy 120.133824 -54.184978) (xy 120.252118 -54.196878) (xy 120.369353 -54.216653) (xy 120.485005 -54.244215)
			(xy 120.598558 -54.279439) (xy 120.709504 -54.322169) (xy 120.817349 -54.372215) (xy 120.921611 -54.429351)
			(xy 121.021823 -54.493324) (xy 121.117538 -54.563848) (xy 121.208329 -54.640607) (xy 121.293791 -54.723259)
			(xy 121.373541 -54.811435) (xy 121.447224 -54.90474) (xy 121.51451 -55.002759) (xy 121.575098 -55.105053)
			(xy 121.628719 -55.211165) (xy 121.675133 -55.320622) (xy 121.714132 -55.432934) (xy 121.745543 -55.547601)
			(xy 121.769224 -55.664109) (xy 121.785071 -55.781939) (xy 121.793012 -55.900565) (xy 121.793508 -55.96001)
			(xy 121.793012 -56.019455) (xy 129.412988 -56.019455) (xy 129.412988 -55.900565) (xy 129.420929 -55.781939)
			(xy 129.436776 -55.664109) (xy 129.460457 -55.547601) (xy 129.491868 -55.432934) (xy 129.530867 -55.320622)
			(xy 129.577281 -55.211165) (xy 129.630902 -55.105053) (xy 129.69149 -55.002759) (xy 129.758776 -54.90474)
			(xy 129.832459 -54.811435) (xy 129.912209 -54.723259) (xy 129.997671 -54.640607) (xy 130.088462 -54.563848)
			(xy 130.184177 -54.493324) (xy 130.284389 -54.429351) (xy 130.388651 -54.372215) (xy 130.496496 -54.322169)
			(xy 130.607442 -54.279439) (xy 130.720995 -54.244215) (xy 130.836647 -54.216653) (xy 130.953882 -54.196878)
			(xy 131.072176 -54.184978) (xy 131.191 -54.181005) (xy 131.309824 -54.184978) (xy 131.428118 -54.196878)
			(xy 131.545353 -54.216653) (xy 131.661005 -54.244215) (xy 131.774558 -54.279439) (xy 131.885504 -54.322169)
			(xy 131.993349 -54.372215) (xy 132.097611 -54.429351) (xy 132.197823 -54.493324) (xy 132.293538 -54.563848)
			(xy 132.384329 -54.640607) (xy 132.469791 -54.723259) (xy 132.549541 -54.811435) (xy 132.623224 -54.90474)
			(xy 132.69051 -55.002759) (xy 132.751098 -55.105053) (xy 132.804719 -55.211165) (xy 132.851133 -55.320622)
			(xy 132.890132 -55.432934) (xy 132.921543 -55.547601) (xy 132.945224 -55.664109) (xy 132.961071 -55.781939)
			(xy 132.969012 -55.900565) (xy 132.969508 -55.96001) (xy 132.969012 -56.019455) (xy 145.160988 -56.019455)
			(xy 145.160988 -55.900565) (xy 145.168929 -55.781939) (xy 145.184776 -55.664109) (xy 145.208457 -55.547601)
			(xy 145.239868 -55.432934) (xy 145.278867 -55.320622) (xy 145.325281 -55.211165) (xy 145.378902 -55.105053)
			(xy 145.43949 -55.002759) (xy 145.506776 -54.90474) (xy 145.580459 -54.811435) (xy 145.660209 -54.723259)
			(xy 145.745671 -54.640607) (xy 145.836462 -54.563848) (xy 145.932177 -54.493324) (xy 146.032389 -54.429351)
			(xy 146.136651 -54.372215) (xy 146.244496 -54.322169) (xy 146.355442 -54.279439) (xy 146.468995 -54.244215)
			(xy 146.584647 -54.216653) (xy 146.701882 -54.196878) (xy 146.820176 -54.184978) (xy 146.939 -54.181005)
			(xy 147.057824 -54.184978) (xy 147.176118 -54.196878) (xy 147.293353 -54.216653) (xy 147.409005 -54.244215)
			(xy 147.522558 -54.279439) (xy 147.633504 -54.322169) (xy 147.741349 -54.372215) (xy 147.845611 -54.429351)
			(xy 147.945823 -54.493324) (xy 148.041538 -54.563848) (xy 148.132329 -54.640607) (xy 148.217791 -54.723259)
			(xy 148.297541 -54.811435) (xy 148.371224 -54.90474) (xy 148.43851 -55.002759) (xy 148.499098 -55.105053)
			(xy 148.552719 -55.211165) (xy 148.599133 -55.320622) (xy 148.638132 -55.432934) (xy 148.669543 -55.547601)
			(xy 148.693224 -55.664109) (xy 148.709071 -55.781939) (xy 148.717012 -55.900565) (xy 148.717508 -55.96001)
			(xy 148.717012 -56.019455) (xy 156.336988 -56.019455) (xy 156.336988 -55.900565) (xy 156.344929 -55.781939)
			(xy 156.360776 -55.664109) (xy 156.384457 -55.547601) (xy 156.415868 -55.432934) (xy 156.454867 -55.320622)
			(xy 156.501281 -55.211165) (xy 156.554902 -55.105053) (xy 156.61549 -55.002759) (xy 156.682776 -54.90474)
			(xy 156.756459 -54.811435) (xy 156.836209 -54.723259) (xy 156.921671 -54.640607) (xy 157.012462 -54.563848)
			(xy 157.108177 -54.493324) (xy 157.208389 -54.429351) (xy 157.312651 -54.372215) (xy 157.420496 -54.322169)
			(xy 157.531442 -54.279439) (xy 157.644995 -54.244215) (xy 157.760647 -54.216653) (xy 157.877882 -54.196878)
			(xy 157.996176 -54.184978) (xy 158.115 -54.181005) (xy 158.233824 -54.184978) (xy 158.352118 -54.196878)
			(xy 158.469353 -54.216653) (xy 158.585005 -54.244215) (xy 158.698558 -54.279439) (xy 158.809504 -54.322169)
			(xy 158.917349 -54.372215) (xy 159.021611 -54.429351) (xy 159.121823 -54.493324) (xy 159.217538 -54.563848)
			(xy 159.308329 -54.640607) (xy 159.393791 -54.723259) (xy 159.473541 -54.811435) (xy 159.547224 -54.90474)
			(xy 159.61451 -55.002759) (xy 159.675098 -55.105053) (xy 159.728719 -55.211165) (xy 159.775133 -55.320622)
			(xy 159.814132 -55.432934) (xy 159.845543 -55.547601) (xy 159.869224 -55.664109) (xy 159.885071 -55.781939)
			(xy 159.893012 -55.900565) (xy 159.893508 -55.96001) (xy 159.893012 -56.019455) (xy 167.512988 -56.019455)
			(xy 167.512988 -55.900565) (xy 167.520929 -55.781939) (xy 167.536776 -55.664109) (xy 167.560457 -55.547601)
			(xy 167.591868 -55.432934) (xy 167.630867 -55.320622) (xy 167.677281 -55.211165) (xy 167.730902 -55.105053)
			(xy 167.79149 -55.002759) (xy 167.858776 -54.90474) (xy 167.932459 -54.811435) (xy 168.012209 -54.723259)
			(xy 168.097671 -54.640607) (xy 168.188462 -54.563848) (xy 168.284177 -54.493324) (xy 168.384389 -54.429351)
			(xy 168.488651 -54.372215) (xy 168.596496 -54.322169) (xy 168.707442 -54.279439) (xy 168.820995 -54.244215)
			(xy 168.936647 -54.216653) (xy 169.053882 -54.196878) (xy 169.172176 -54.184978) (xy 169.291 -54.181005)
			(xy 169.409824 -54.184978) (xy 169.528118 -54.196878) (xy 169.645353 -54.216653) (xy 169.761005 -54.244215)
			(xy 169.874558 -54.279439) (xy 169.985504 -54.322169) (xy 170.093349 -54.372215) (xy 170.197611 -54.429351)
			(xy 170.297823 -54.493324) (xy 170.393538 -54.563848) (xy 170.484329 -54.640607) (xy 170.569791 -54.723259)
			(xy 170.649541 -54.811435) (xy 170.723224 -54.90474) (xy 170.79051 -55.002759) (xy 170.851098 -55.105053)
			(xy 170.904719 -55.211165) (xy 170.951133 -55.320622) (xy 170.990132 -55.432934) (xy 171.021543 -55.547601)
			(xy 171.045224 -55.664109) (xy 171.061071 -55.781939) (xy 171.069012 -55.900565) (xy 171.069508 -55.96001)
			(xy 171.069012 -56.019455) (xy 185.161162 -56.019455) (xy 185.161162 -55.900565) (xy 185.169103 -55.781939)
			(xy 185.18495 -55.664109) (xy 185.208631 -55.547601) (xy 185.240042 -55.432934) (xy 185.279041 -55.320622)
			(xy 185.325455 -55.211165) (xy 185.379076 -55.105053) (xy 185.439664 -55.002759) (xy 185.50695 -54.90474)
			(xy 185.580633 -54.811435) (xy 185.660383 -54.723259) (xy 185.745845 -54.640607) (xy 185.836636 -54.563848)
			(xy 185.932351 -54.493324) (xy 186.032563 -54.429351) (xy 186.136825 -54.372215) (xy 186.24467 -54.322169)
			(xy 186.355616 -54.279439) (xy 186.469169 -54.244215) (xy 186.584821 -54.216653) (xy 186.702056 -54.196878)
			(xy 186.82035 -54.184978) (xy 186.939174 -54.181005) (xy 187.057998 -54.184978) (xy 187.176292 -54.196878)
			(xy 187.293527 -54.216653) (xy 187.409179 -54.244215) (xy 187.522732 -54.279439) (xy 187.633678 -54.322169)
			(xy 187.741523 -54.372215) (xy 187.845785 -54.429351) (xy 187.945997 -54.493324) (xy 188.041712 -54.563848)
			(xy 188.132503 -54.640607) (xy 188.217965 -54.723259) (xy 188.297715 -54.811435) (xy 188.371398 -54.90474)
			(xy 188.438684 -55.002759) (xy 188.499272 -55.105053) (xy 188.552893 -55.211165) (xy 188.599307 -55.320622)
			(xy 188.638306 -55.432934) (xy 188.669717 -55.547601) (xy 188.693398 -55.664109) (xy 188.709245 -55.781939)
			(xy 188.717186 -55.900565) (xy 188.717682 -55.96001) (xy 188.717186 -56.019455) (xy 196.337162 -56.019455)
			(xy 196.337162 -55.900565) (xy 196.345103 -55.781939) (xy 196.36095 -55.664109) (xy 196.384631 -55.547601)
			(xy 196.416042 -55.432934) (xy 196.455041 -55.320622) (xy 196.501455 -55.211165) (xy 196.555076 -55.105053)
			(xy 196.615664 -55.002759) (xy 196.68295 -54.90474) (xy 196.756633 -54.811435) (xy 196.836383 -54.723259)
			(xy 196.921845 -54.640607) (xy 197.012636 -54.563848) (xy 197.108351 -54.493324) (xy 197.208563 -54.429351)
			(xy 197.312825 -54.372215) (xy 197.42067 -54.322169) (xy 197.531616 -54.279439) (xy 197.645169 -54.244215)
			(xy 197.760821 -54.216653) (xy 197.878056 -54.196878) (xy 197.99635 -54.184978) (xy 198.115174 -54.181005)
			(xy 198.233998 -54.184978) (xy 198.352292 -54.196878) (xy 198.469527 -54.216653) (xy 198.585179 -54.244215)
			(xy 198.698732 -54.279439) (xy 198.809678 -54.322169) (xy 198.917523 -54.372215) (xy 199.021785 -54.429351)
			(xy 199.121997 -54.493324) (xy 199.217712 -54.563848) (xy 199.308503 -54.640607) (xy 199.393965 -54.723259)
			(xy 199.473715 -54.811435) (xy 199.547398 -54.90474) (xy 199.614684 -55.002759) (xy 199.675272 -55.105053)
			(xy 199.728893 -55.211165) (xy 199.775307 -55.320622) (xy 199.814306 -55.432934) (xy 199.845717 -55.547601)
			(xy 199.869398 -55.664109) (xy 199.885245 -55.781939) (xy 199.893186 -55.900565) (xy 199.893682 -55.96001)
			(xy 199.893186 -56.019455) (xy 207.513162 -56.019455) (xy 207.513162 -55.900565) (xy 207.521103 -55.781939)
			(xy 207.53695 -55.664109) (xy 207.560631 -55.547601) (xy 207.592042 -55.432934) (xy 207.631041 -55.320622)
			(xy 207.677455 -55.211165) (xy 207.731076 -55.105053) (xy 207.791664 -55.002759) (xy 207.85895 -54.90474)
			(xy 207.932633 -54.811435) (xy 208.012383 -54.723259) (xy 208.097845 -54.640607) (xy 208.188636 -54.563848)
			(xy 208.284351 -54.493324) (xy 208.384563 -54.429351) (xy 208.488825 -54.372215) (xy 208.59667 -54.322169)
			(xy 208.707616 -54.279439) (xy 208.821169 -54.244215) (xy 208.936821 -54.216653) (xy 209.054056 -54.196878)
			(xy 209.17235 -54.184978) (xy 209.291174 -54.181005) (xy 209.409998 -54.184978) (xy 209.528292 -54.196878)
			(xy 209.645527 -54.216653) (xy 209.761179 -54.244215) (xy 209.874732 -54.279439) (xy 209.985678 -54.322169)
			(xy 210.093523 -54.372215) (xy 210.197785 -54.429351) (xy 210.297997 -54.493324) (xy 210.393712 -54.563848)
			(xy 210.484503 -54.640607) (xy 210.569965 -54.723259) (xy 210.649715 -54.811435) (xy 210.723398 -54.90474)
			(xy 210.790684 -55.002759) (xy 210.851272 -55.105053) (xy 210.904893 -55.211165) (xy 210.951307 -55.320622)
			(xy 210.990306 -55.432934) (xy 211.021717 -55.547601) (xy 211.045398 -55.664109) (xy 211.061245 -55.781939)
			(xy 211.069186 -55.900565) (xy 211.069682 -55.96001) (xy 211.069186 -56.019455) (xy 211.061245 -56.138081)
			(xy 211.045398 -56.255911) (xy 211.021717 -56.372419) (xy 210.990306 -56.487086) (xy 210.951307 -56.599398)
			(xy 210.904893 -56.708855) (xy 210.851272 -56.814967) (xy 210.790684 -56.917261) (xy 210.723398 -57.01528)
			(xy 210.649715 -57.108585) (xy 210.569965 -57.196761) (xy 210.484503 -57.279413) (xy 210.393712 -57.356172)
			(xy 210.297997 -57.426696) (xy 210.197785 -57.490669) (xy 210.093523 -57.547805) (xy 209.985678 -57.597851)
			(xy 209.874732 -57.640581) (xy 209.761179 -57.675805) (xy 209.645527 -57.703367) (xy 209.528292 -57.723142)
			(xy 209.409998 -57.735042) (xy 209.291174 -57.739015) (xy 209.17235 -57.735042) (xy 209.054056 -57.723142)
			(xy 208.936821 -57.703367) (xy 208.821169 -57.675805) (xy 208.707616 -57.640581) (xy 208.59667 -57.597851)
			(xy 208.488825 -57.547805) (xy 208.384563 -57.490669) (xy 208.284351 -57.426696) (xy 208.188636 -57.356172)
			(xy 208.097845 -57.279413) (xy 208.012383 -57.196761) (xy 207.932633 -57.108585) (xy 207.85895 -57.01528)
			(xy 207.791664 -56.917261) (xy 207.731076 -56.814967) (xy 207.677455 -56.708855) (xy 207.631041 -56.599398)
			(xy 207.592042 -56.487086) (xy 207.560631 -56.372419) (xy 207.53695 -56.255911) (xy 207.521103 -56.138081)
			(xy 207.513162 -56.019455) (xy 199.893186 -56.019455) (xy 199.885245 -56.138081) (xy 199.869398 -56.255911)
			(xy 199.845717 -56.372419) (xy 199.814306 -56.487086) (xy 199.775307 -56.599398) (xy 199.728893 -56.708855)
			(xy 199.675272 -56.814967) (xy 199.614684 -56.917261) (xy 199.547398 -57.01528) (xy 199.473715 -57.108585)
			(xy 199.393965 -57.196761) (xy 199.308503 -57.279413) (xy 199.217712 -57.356172) (xy 199.121997 -57.426696)
			(xy 199.021785 -57.490669) (xy 198.917523 -57.547805) (xy 198.809678 -57.597851) (xy 198.698732 -57.640581)
			(xy 198.585179 -57.675805) (xy 198.469527 -57.703367) (xy 198.352292 -57.723142) (xy 198.233998 -57.735042)
			(xy 198.115174 -57.739015) (xy 197.99635 -57.735042) (xy 197.878056 -57.723142) (xy 197.760821 -57.703367)
			(xy 197.645169 -57.675805) (xy 197.531616 -57.640581) (xy 197.42067 -57.597851) (xy 197.312825 -57.547805)
			(xy 197.208563 -57.490669) (xy 197.108351 -57.426696) (xy 197.012636 -57.356172) (xy 196.921845 -57.279413)
			(xy 196.836383 -57.196761) (xy 196.756633 -57.108585) (xy 196.68295 -57.01528) (xy 196.615664 -56.917261)
			(xy 196.555076 -56.814967) (xy 196.501455 -56.708855) (xy 196.455041 -56.599398) (xy 196.416042 -56.487086)
			(xy 196.384631 -56.372419) (xy 196.36095 -56.255911) (xy 196.345103 -56.138081) (xy 196.337162 -56.019455)
			(xy 188.717186 -56.019455) (xy 188.709245 -56.138081) (xy 188.693398 -56.255911) (xy 188.669717 -56.372419)
			(xy 188.638306 -56.487086) (xy 188.599307 -56.599398) (xy 188.552893 -56.708855) (xy 188.499272 -56.814967)
			(xy 188.438684 -56.917261) (xy 188.371398 -57.01528) (xy 188.297715 -57.108585) (xy 188.217965 -57.196761)
			(xy 188.132503 -57.279413) (xy 188.041712 -57.356172) (xy 187.945997 -57.426696) (xy 187.845785 -57.490669)
			(xy 187.741523 -57.547805) (xy 187.633678 -57.597851) (xy 187.522732 -57.640581) (xy 187.409179 -57.675805)
			(xy 187.293527 -57.703367) (xy 187.176292 -57.723142) (xy 187.057998 -57.735042) (xy 186.939174 -57.739015)
			(xy 186.82035 -57.735042) (xy 186.702056 -57.723142) (xy 186.584821 -57.703367) (xy 186.469169 -57.675805)
			(xy 186.355616 -57.640581) (xy 186.24467 -57.597851) (xy 186.136825 -57.547805) (xy 186.032563 -57.490669)
			(xy 185.932351 -57.426696) (xy 185.836636 -57.356172) (xy 185.745845 -57.279413) (xy 185.660383 -57.196761)
			(xy 185.580633 -57.108585) (xy 185.50695 -57.01528) (xy 185.439664 -56.917261) (xy 185.379076 -56.814967)
			(xy 185.325455 -56.708855) (xy 185.279041 -56.599398) (xy 185.240042 -56.487086) (xy 185.208631 -56.372419)
			(xy 185.18495 -56.255911) (xy 185.169103 -56.138081) (xy 185.161162 -56.019455) (xy 171.069012 -56.019455)
			(xy 171.061071 -56.138081) (xy 171.045224 -56.255911) (xy 171.021543 -56.372419) (xy 170.990132 -56.487086)
			(xy 170.951133 -56.599398) (xy 170.904719 -56.708855) (xy 170.851098 -56.814967) (xy 170.79051 -56.917261)
			(xy 170.723224 -57.01528) (xy 170.649541 -57.108585) (xy 170.569791 -57.196761) (xy 170.484329 -57.279413)
			(xy 170.393538 -57.356172) (xy 170.297823 -57.426696) (xy 170.197611 -57.490669) (xy 170.093349 -57.547805)
			(xy 169.985504 -57.597851) (xy 169.874558 -57.640581) (xy 169.761005 -57.675805) (xy 169.645353 -57.703367)
			(xy 169.528118 -57.723142) (xy 169.409824 -57.735042) (xy 169.291 -57.739015) (xy 169.172176 -57.735042)
			(xy 169.053882 -57.723142) (xy 168.936647 -57.703367) (xy 168.820995 -57.675805) (xy 168.707442 -57.640581)
			(xy 168.596496 -57.597851) (xy 168.488651 -57.547805) (xy 168.384389 -57.490669) (xy 168.284177 -57.426696)
			(xy 168.188462 -57.356172) (xy 168.097671 -57.279413) (xy 168.012209 -57.196761) (xy 167.932459 -57.108585)
			(xy 167.858776 -57.01528) (xy 167.79149 -56.917261) (xy 167.730902 -56.814967) (xy 167.677281 -56.708855)
			(xy 167.630867 -56.599398) (xy 167.591868 -56.487086) (xy 167.560457 -56.372419) (xy 167.536776 -56.255911)
			(xy 167.520929 -56.138081) (xy 167.512988 -56.019455) (xy 159.893012 -56.019455) (xy 159.885071 -56.138081)
			(xy 159.869224 -56.255911) (xy 159.845543 -56.372419) (xy 159.814132 -56.487086) (xy 159.775133 -56.599398)
			(xy 159.728719 -56.708855) (xy 159.675098 -56.814967) (xy 159.61451 -56.917261) (xy 159.547224 -57.01528)
			(xy 159.473541 -57.108585) (xy 159.393791 -57.196761) (xy 159.308329 -57.279413) (xy 159.217538 -57.356172)
			(xy 159.121823 -57.426696) (xy 159.021611 -57.490669) (xy 158.917349 -57.547805) (xy 158.809504 -57.597851)
			(xy 158.698558 -57.640581) (xy 158.585005 -57.675805) (xy 158.469353 -57.703367) (xy 158.352118 -57.723142)
			(xy 158.233824 -57.735042) (xy 158.115 -57.739015) (xy 157.996176 -57.735042) (xy 157.877882 -57.723142)
			(xy 157.760647 -57.703367) (xy 157.644995 -57.675805) (xy 157.531442 -57.640581) (xy 157.420496 -57.597851)
			(xy 157.312651 -57.547805) (xy 157.208389 -57.490669) (xy 157.108177 -57.426696) (xy 157.012462 -57.356172)
			(xy 156.921671 -57.279413) (xy 156.836209 -57.196761) (xy 156.756459 -57.108585) (xy 156.682776 -57.01528)
			(xy 156.61549 -56.917261) (xy 156.554902 -56.814967) (xy 156.501281 -56.708855) (xy 156.454867 -56.599398)
			(xy 156.415868 -56.487086) (xy 156.384457 -56.372419) (xy 156.360776 -56.255911) (xy 156.344929 -56.138081)
			(xy 156.336988 -56.019455) (xy 148.717012 -56.019455) (xy 148.709071 -56.138081) (xy 148.693224 -56.255911)
			(xy 148.669543 -56.372419) (xy 148.638132 -56.487086) (xy 148.599133 -56.599398) (xy 148.552719 -56.708855)
			(xy 148.499098 -56.814967) (xy 148.43851 -56.917261) (xy 148.371224 -57.01528) (xy 148.297541 -57.108585)
			(xy 148.217791 -57.196761) (xy 148.132329 -57.279413) (xy 148.041538 -57.356172) (xy 147.945823 -57.426696)
			(xy 147.845611 -57.490669) (xy 147.741349 -57.547805) (xy 147.633504 -57.597851) (xy 147.522558 -57.640581)
			(xy 147.409005 -57.675805) (xy 147.293353 -57.703367) (xy 147.176118 -57.723142) (xy 147.057824 -57.735042)
			(xy 146.939 -57.739015) (xy 146.820176 -57.735042) (xy 146.701882 -57.723142) (xy 146.584647 -57.703367)
			(xy 146.468995 -57.675805) (xy 146.355442 -57.640581) (xy 146.244496 -57.597851) (xy 146.136651 -57.547805)
			(xy 146.032389 -57.490669) (xy 145.932177 -57.426696) (xy 145.836462 -57.356172) (xy 145.745671 -57.279413)
			(xy 145.660209 -57.196761) (xy 145.580459 -57.108585) (xy 145.506776 -57.01528) (xy 145.43949 -56.917261)
			(xy 145.378902 -56.814967) (xy 145.325281 -56.708855) (xy 145.278867 -56.599398) (xy 145.239868 -56.487086)
			(xy 145.208457 -56.372419) (xy 145.184776 -56.255911) (xy 145.168929 -56.138081) (xy 145.160988 -56.019455)
			(xy 132.969012 -56.019455) (xy 132.961071 -56.138081) (xy 132.945224 -56.255911) (xy 132.921543 -56.372419)
			(xy 132.890132 -56.487086) (xy 132.851133 -56.599398) (xy 132.804719 -56.708855) (xy 132.751098 -56.814967)
			(xy 132.69051 -56.917261) (xy 132.623224 -57.01528) (xy 132.549541 -57.108585) (xy 132.469791 -57.196761)
			(xy 132.384329 -57.279413) (xy 132.293538 -57.356172) (xy 132.197823 -57.426696) (xy 132.097611 -57.490669)
			(xy 131.993349 -57.547805) (xy 131.885504 -57.597851) (xy 131.774558 -57.640581) (xy 131.661005 -57.675805)
			(xy 131.545353 -57.703367) (xy 131.428118 -57.723142) (xy 131.309824 -57.735042) (xy 131.191 -57.739015)
			(xy 131.072176 -57.735042) (xy 130.953882 -57.723142) (xy 130.836647 -57.703367) (xy 130.720995 -57.675805)
			(xy 130.607442 -57.640581) (xy 130.496496 -57.597851) (xy 130.388651 -57.547805) (xy 130.284389 -57.490669)
			(xy 130.184177 -57.426696) (xy 130.088462 -57.356172) (xy 129.997671 -57.279413) (xy 129.912209 -57.196761)
			(xy 129.832459 -57.108585) (xy 129.758776 -57.01528) (xy 129.69149 -56.917261) (xy 129.630902 -56.814967)
			(xy 129.577281 -56.708855) (xy 129.530867 -56.599398) (xy 129.491868 -56.487086) (xy 129.460457 -56.372419)
			(xy 129.436776 -56.255911) (xy 129.420929 -56.138081) (xy 129.412988 -56.019455) (xy 121.793012 -56.019455)
			(xy 121.785071 -56.138081) (xy 121.769224 -56.255911) (xy 121.745543 -56.372419) (xy 121.714132 -56.487086)
			(xy 121.675133 -56.599398) (xy 121.628719 -56.708855) (xy 121.575098 -56.814967) (xy 121.51451 -56.917261)
			(xy 121.447224 -57.01528) (xy 121.373541 -57.108585) (xy 121.293791 -57.196761) (xy 121.208329 -57.279413)
			(xy 121.117538 -57.356172) (xy 121.021823 -57.426696) (xy 120.921611 -57.490669) (xy 120.817349 -57.547805)
			(xy 120.709504 -57.597851) (xy 120.598558 -57.640581) (xy 120.485005 -57.675805) (xy 120.369353 -57.703367)
			(xy 120.252118 -57.723142) (xy 120.133824 -57.735042) (xy 120.015 -57.739015) (xy 119.896176 -57.735042)
			(xy 119.777882 -57.723142) (xy 119.660647 -57.703367) (xy 119.544995 -57.675805) (xy 119.431442 -57.640581)
			(xy 119.320496 -57.597851) (xy 119.212651 -57.547805) (xy 119.108389 -57.490669) (xy 119.008177 -57.426696)
			(xy 118.912462 -57.356172) (xy 118.821671 -57.279413) (xy 118.736209 -57.196761) (xy 118.656459 -57.108585)
			(xy 118.582776 -57.01528) (xy 118.51549 -56.917261) (xy 118.454902 -56.814967) (xy 118.401281 -56.708855)
			(xy 118.354867 -56.599398) (xy 118.315868 -56.487086) (xy 118.284457 -56.372419) (xy 118.260776 -56.255911)
			(xy 118.244929 -56.138081) (xy 118.236988 -56.019455) (xy 110.617012 -56.019455) (xy 110.609071 -56.138081)
			(xy 110.593224 -56.255911) (xy 110.569543 -56.372419) (xy 110.538132 -56.487086) (xy 110.499133 -56.599398)
			(xy 110.452719 -56.708855) (xy 110.399098 -56.814967) (xy 110.33851 -56.917261) (xy 110.271224 -57.01528)
			(xy 110.197541 -57.108585) (xy 110.117791 -57.196761) (xy 110.032329 -57.279413) (xy 109.941538 -57.356172)
			(xy 109.845823 -57.426696) (xy 109.745611 -57.490669) (xy 109.641349 -57.547805) (xy 109.533504 -57.597851)
			(xy 109.422558 -57.640581) (xy 109.309005 -57.675805) (xy 109.193353 -57.703367) (xy 109.076118 -57.723142)
			(xy 108.957824 -57.735042) (xy 108.839 -57.739015) (xy 108.720176 -57.735042) (xy 108.601882 -57.723142)
			(xy 108.484647 -57.703367) (xy 108.368995 -57.675805) (xy 108.255442 -57.640581) (xy 108.144496 -57.597851)
			(xy 108.036651 -57.547805) (xy 107.932389 -57.490669) (xy 107.832177 -57.426696) (xy 107.736462 -57.356172)
			(xy 107.645671 -57.279413) (xy 107.560209 -57.196761) (xy 107.480459 -57.108585) (xy 107.406776 -57.01528)
			(xy 107.33949 -56.917261) (xy 107.278902 -56.814967) (xy 107.225281 -56.708855) (xy 107.178867 -56.599398)
			(xy 107.139868 -56.487086) (xy 107.108457 -56.372419) (xy 107.084776 -56.255911) (xy 107.068929 -56.138081)
			(xy 107.060988 -56.019455) (xy 92.456012 -56.019455) (xy 92.448071 -56.138081) (xy 92.432224 -56.255911)
			(xy 92.408543 -56.372419) (xy 92.377132 -56.487086) (xy 92.338133 -56.599398) (xy 92.291719 -56.708855)
			(xy 92.238098 -56.814967) (xy 92.17751 -56.917261) (xy 92.110224 -57.01528) (xy 92.036541 -57.108585)
			(xy 91.956791 -57.196761) (xy 91.871329 -57.279413) (xy 91.780538 -57.356172) (xy 91.684823 -57.426696)
			(xy 91.584611 -57.490669) (xy 91.480349 -57.547805) (xy 91.372504 -57.597851) (xy 91.261558 -57.640581)
			(xy 91.148005 -57.675805) (xy 91.032353 -57.703367) (xy 90.915118 -57.723142) (xy 90.796824 -57.735042)
			(xy 90.678 -57.739015) (xy 90.559176 -57.735042) (xy 90.440882 -57.723142) (xy 90.323647 -57.703367)
			(xy 90.207995 -57.675805) (xy 90.094442 -57.640581) (xy 89.983496 -57.597851) (xy 89.875651 -57.547805)
			(xy 89.771389 -57.490669) (xy 89.671177 -57.426696) (xy 89.575462 -57.356172) (xy 89.484671 -57.279413)
			(xy 89.399209 -57.196761) (xy 89.319459 -57.108585) (xy 89.245776 -57.01528) (xy 89.17849 -56.917261)
			(xy 89.117902 -56.814967) (xy 89.064281 -56.708855) (xy 89.017867 -56.599398) (xy 88.978868 -56.487086)
			(xy 88.947457 -56.372419) (xy 88.923776 -56.255911) (xy 88.907929 -56.138081) (xy 88.899988 -56.019455)
			(xy 81.153012 -56.019455) (xy 81.145071 -56.138081) (xy 81.129224 -56.255911) (xy 81.105543 -56.372419)
			(xy 81.074132 -56.487086) (xy 81.035133 -56.599398) (xy 80.988719 -56.708855) (xy 80.935098 -56.814967)
			(xy 80.87451 -56.917261) (xy 80.807224 -57.01528) (xy 80.733541 -57.108585) (xy 80.653791 -57.196761)
			(xy 80.568329 -57.279413) (xy 80.477538 -57.356172) (xy 80.381823 -57.426696) (xy 80.281611 -57.490669)
			(xy 80.177349 -57.547805) (xy 80.069504 -57.597851) (xy 79.958558 -57.640581) (xy 79.845005 -57.675805)
			(xy 79.729353 -57.703367) (xy 79.612118 -57.723142) (xy 79.493824 -57.735042) (xy 79.375 -57.739015)
			(xy 79.256176 -57.735042) (xy 79.137882 -57.723142) (xy 79.020647 -57.703367) (xy 78.904995 -57.675805)
			(xy 78.791442 -57.640581) (xy 78.680496 -57.597851) (xy 78.572651 -57.547805) (xy 78.468389 -57.490669)
			(xy 78.368177 -57.426696) (xy 78.272462 -57.356172) (xy 78.181671 -57.279413) (xy 78.096209 -57.196761)
			(xy 78.016459 -57.108585) (xy 77.942776 -57.01528) (xy 77.87549 -56.917261) (xy 77.814902 -56.814967)
			(xy 77.761281 -56.708855) (xy 77.714867 -56.599398) (xy 77.675868 -56.487086) (xy 77.644457 -56.372419)
			(xy 77.620776 -56.255911) (xy 77.604929 -56.138081) (xy 77.596988 -56.019455) (xy 69.850012 -56.019455)
			(xy 69.842071 -56.138081) (xy 69.826224 -56.255911) (xy 69.802543 -56.372419) (xy 69.771132 -56.487086)
			(xy 69.732133 -56.599398) (xy 69.685719 -56.708855) (xy 69.632098 -56.814967) (xy 69.57151 -56.917261)
			(xy 69.504224 -57.01528) (xy 69.430541 -57.108585) (xy 69.350791 -57.196761) (xy 69.265329 -57.279413)
			(xy 69.174538 -57.356172) (xy 69.078823 -57.426696) (xy 68.978611 -57.490669) (xy 68.874349 -57.547805)
			(xy 68.766504 -57.597851) (xy 68.655558 -57.640581) (xy 68.542005 -57.675805) (xy 68.426353 -57.703367)
			(xy 68.309118 -57.723142) (xy 68.190824 -57.735042) (xy 68.072 -57.739015) (xy 67.953176 -57.735042)
			(xy 67.834882 -57.723142) (xy 67.717647 -57.703367) (xy 67.601995 -57.675805) (xy 67.488442 -57.640581)
			(xy 67.377496 -57.597851) (xy 67.269651 -57.547805) (xy 67.165389 -57.490669) (xy 67.065177 -57.426696)
			(xy 66.969462 -57.356172) (xy 66.878671 -57.279413) (xy 66.793209 -57.196761) (xy 66.713459 -57.108585)
			(xy 66.639776 -57.01528) (xy 66.57249 -56.917261) (xy 66.511902 -56.814967) (xy 66.458281 -56.708855)
			(xy 66.411867 -56.599398) (xy 66.372868 -56.487086) (xy 66.341457 -56.372419) (xy 66.317776 -56.255911)
			(xy 66.301929 -56.138081) (xy 66.293988 -56.019455) (xy 63.9826 -56.019455) (xy 63.9826 -61.722)
			(xy 67.182492 -61.722) (xy 67.182492 -60.198) (xy 67.183038 -60.181285) (xy 67.19169 -60.148994)
			(xy 67.208405 -60.120043) (xy 67.232043 -60.096405) (xy 67.260994 -60.07969) (xy 67.293285 -60.071038)
			(xy 67.31 -60.070492) (xy 68.834 -60.070492) (xy 68.850715 -60.071038) (xy 68.883006 -60.07969) (xy 68.911957 -60.096405)
			(xy 68.935595 -60.120043) (xy 68.95231 -60.148994) (xy 68.960962 -60.181285) (xy 68.961508 -60.198)
			(xy 68.961508 -61.722) (xy 78.485492 -61.722) (xy 78.485492 -60.198) (xy 78.486038 -60.181285) (xy 78.49469 -60.148994)
			(xy 78.511405 -60.120043) (xy 78.535043 -60.096405) (xy 78.563994 -60.07969) (xy 78.596285 -60.071038)
			(xy 78.613 -60.070492) (xy 80.137 -60.070492) (xy 80.153715 -60.071038) (xy 80.186006 -60.07969)
			(xy 80.214957 -60.096405) (xy 80.238595 -60.120043) (xy 80.25531 -60.148994) (xy 80.263962 -60.181285)
			(xy 80.264508 -60.198) (xy 80.264508 -61.722) (xy 89.788492 -61.722) (xy 89.788492 -60.198) (xy 89.789038 -60.181285)
			(xy 89.79769 -60.148994) (xy 89.814405 -60.120043) (xy 89.838043 -60.096405) (xy 89.866994 -60.07969)
			(xy 89.899285 -60.071038) (xy 89.916 -60.070492) (xy 91.44 -60.070492) (xy 91.456715 -60.071038)
			(xy 91.489006 -60.07969) (xy 91.517957 -60.096405) (xy 91.541595 -60.120043) (xy 91.55831 -60.148994)
			(xy 91.566962 -60.181285) (xy 91.567508 -60.198) (xy 91.567508 -61.722) (xy 91.566962 -61.738715)
			(xy 91.55831 -61.771006) (xy 91.541595 -61.799957) (xy 91.517957 -61.823595) (xy 91.489006 -61.84031)
			(xy 91.456715 -61.848962) (xy 91.44 -61.849508) (xy 89.916 -61.849508) (xy 89.899285 -61.848962)
			(xy 89.866994 -61.84031) (xy 89.838043 -61.823595) (xy 89.814405 -61.799957) (xy 89.79769 -61.771006)
			(xy 89.789038 -61.738715) (xy 89.788492 -61.722) (xy 80.264508 -61.722) (xy 80.263962 -61.738715)
			(xy 80.25531 -61.771006) (xy 80.238595 -61.799957) (xy 80.214957 -61.823595) (xy 80.186006 -61.84031)
			(xy 80.153715 -61.848962) (xy 80.137 -61.849508) (xy 78.613 -61.849508) (xy 78.596285 -61.848962)
			(xy 78.563994 -61.84031) (xy 78.535043 -61.823595) (xy 78.511405 -61.799957) (xy 78.49469 -61.771006)
			(xy 78.486038 -61.738715) (xy 78.485492 -61.722) (xy 68.961508 -61.722) (xy 68.960962 -61.738715)
			(xy 68.95231 -61.771006) (xy 68.935595 -61.799957) (xy 68.911957 -61.823595) (xy 68.883006 -61.84031)
			(xy 68.850715 -61.848962) (xy 68.834 -61.849508) (xy 67.31 -61.849508) (xy 67.293285 -61.848962)
			(xy 67.260994 -61.84031) (xy 67.232043 -61.823595) (xy 67.208405 -61.799957) (xy 67.19169 -61.771006)
			(xy 67.183038 -61.738715) (xy 67.182492 -61.722) (xy 63.9826 -61.722) (xy 63.9826 -62.738) (xy 99.872292 -62.738)
			(xy 99.872868 -62.682599) (xy 99.881975 -62.572171) (xy 99.900126 -62.462865) (xy 99.927199 -62.35542)
			(xy 99.96301 -62.250564) (xy 100.007318 -62.149006) (xy 100.033074 -62.099952) (xy 100.037847 -62.089933)
			(xy 100.03915 -62.067801) (xy 100.035614 -62.05728) (xy 100.018788 -62.01305) (xy 99.990994 -61.922581)
			(xy 99.970015 -61.830294) (xy 99.955966 -61.7367) (xy 99.948926 -61.642321) (xy 99.948492 -61.595)
			(xy 99.948999 -61.545128) (xy 99.956821 -61.44569) (xy 99.972416 -61.347172) (xy 99.995689 -61.25018)
			(xy 100.026496 -61.155312) (xy 100.064648 -61.063152) (xy 100.10991 -60.974268) (xy 100.162002 -60.889207)
			(xy 100.220604 -60.808492) (xy 100.285355 -60.732622) (xy 100.355856 -60.662063) (xy 100.431673 -60.59725)
			(xy 100.512339 -60.538581) (xy 100.597358 -60.486419) (xy 100.686205 -60.441085) (xy 100.732082 -60.42152)
			(xy 100.740729 -60.417456) (xy 100.754458 -60.404192) (xy 100.7624 -60.386832) (xy 100.763324 -60.377324)
			(xy 100.766868 -60.32299) (xy 100.781673 -60.215107) (xy 100.805151 -60.108774) (xy 100.837146 -60.004686)
			(xy 100.856796 -59.953906) (xy 100.859297 -59.947153) (xy 100.860709 -59.932826) (xy 100.85959 -59.925712)
			(xy 100.849256 -59.867332) (xy 100.838189 -59.749283) (xy 100.837492 -59.69) (xy 100.837982 -59.640101)
			(xy 100.845812 -59.54061) (xy 100.861424 -59.442041) (xy 100.884721 -59.345) (xy 100.915561 -59.250086)
			(xy 100.953752 -59.157884) (xy 100.999059 -59.068963) (xy 101.051204 -58.983871) (xy 101.109864 -58.903133)
			(xy 101.174678 -58.827246) (xy 101.245246 -58.756678) (xy 101.321133 -58.691864) (xy 101.401871 -58.633204)
			(xy 101.486963 -58.581059) (xy 101.575884 -58.535752) (xy 101.668086 -58.497561) (xy 101.763 -58.466721)
			(xy 101.860041 -58.443424) (xy 101.95861 -58.427812) (xy 102.058101 -58.419982) (xy 102.157899 -58.419982)
			(xy 102.25739 -58.427812) (xy 102.355959 -58.443424) (xy 102.453 -58.466721) (xy 102.547914 -58.497561)
			(xy 102.640116 -58.535752) (xy 102.729037 -58.581059) (xy 102.814129 -58.633204) (xy 102.894867 -58.691864)
			(xy 102.970754 -58.756678) (xy 103.041322 -58.827246) (xy 103.106136 -58.903133) (xy 103.164796 -58.983871)
			(xy 103.216941 -59.068963) (xy 103.262248 -59.157884) (xy 103.300439 -59.250086) (xy 103.331279 -59.345)
			(xy 103.354576 -59.442041) (xy 103.370188 -59.54061) (xy 103.378018 -59.640101) (xy 103.378508 -59.69)
			(xy 103.377811 -59.749283) (xy 103.366747 -59.867333) (xy 103.35641 -59.925712) (xy 103.35536 -59.932827)
			(xy 103.356779 -59.947135) (xy 103.359204 -59.953906) (xy 103.377632 -60.001492) (xy 103.408097 -60.098895)
			(xy 103.4311 -60.198324) (xy 103.446509 -60.29921) (xy 103.454236 -60.400972) (xy 103.454708 -60.452)
			(xy 103.454185 -60.505313) (xy 103.44574 -60.611604) (xy 103.428917 -60.716895) (xy 103.403824 -60.820526)
			(xy 103.370616 -60.921849) (xy 103.329501 -61.02023) (xy 103.280738 -61.115052) (xy 103.22463 -61.205722)
			(xy 103.16153 -61.291673) (xy 103.091833 -61.372366) (xy 103.015974 -61.447296) (xy 102.934428 -61.515994)
			(xy 102.847707 -61.578031) (xy 102.756353 -61.633018) (xy 102.660937 -61.68061) (xy 102.562058 -61.720509)
			(xy 102.55747 -61.722) (xy 107.949492 -61.722) (xy 107.949492 -60.198) (xy 107.950038 -60.181285)
			(xy 107.95869 -60.148994) (xy 107.975405 -60.120043) (xy 107.999043 -60.096405) (xy 108.027994 -60.07969)
			(xy 108.060285 -60.071038) (xy 108.077 -60.070492) (xy 109.601 -60.070492) (xy 109.617715 -60.071038)
			(xy 109.650006 -60.07969) (xy 109.678957 -60.096405) (xy 109.702595 -60.120043) (xy 109.71931 -60.148994)
			(xy 109.727962 -60.181285) (xy 109.728508 -60.198) (xy 109.728508 -61.722) (xy 119.125492 -61.722)
			(xy 119.125492 -60.198) (xy 119.126038 -60.181285) (xy 119.13469 -60.148994) (xy 119.151405 -60.120043)
			(xy 119.175043 -60.096405) (xy 119.203994 -60.07969) (xy 119.236285 -60.071038) (xy 119.253 -60.070492)
			(xy 120.777 -60.070492) (xy 120.793715 -60.071038) (xy 120.826006 -60.07969) (xy 120.854957 -60.096405)
			(xy 120.878595 -60.120043) (xy 120.89531 -60.148994) (xy 120.903962 -60.181285) (xy 120.904508 -60.198)
			(xy 120.904508 -61.722) (xy 130.301492 -61.722) (xy 130.301492 -60.198) (xy 130.302038 -60.181285)
			(xy 130.31069 -60.148994) (xy 130.327405 -60.120043) (xy 130.351043 -60.096405) (xy 130.379994 -60.07969)
			(xy 130.412285 -60.071038) (xy 130.429 -60.070492) (xy 131.953 -60.070492) (xy 131.969715 -60.071038)
			(xy 132.002006 -60.07969) (xy 132.030957 -60.096405) (xy 132.054595 -60.120043) (xy 132.07131 -60.148994)
			(xy 132.079962 -60.181285) (xy 132.080508 -60.198) (xy 132.080508 -61.722) (xy 132.079962 -61.738715)
			(xy 132.07131 -61.771006) (xy 132.054595 -61.799957) (xy 132.030957 -61.823595) (xy 132.002006 -61.84031)
			(xy 131.969715 -61.848962) (xy 131.953 -61.849508) (xy 130.429 -61.849508) (xy 130.412285 -61.848962)
			(xy 130.379994 -61.84031) (xy 130.351043 -61.823595) (xy 130.327405 -61.799957) (xy 130.31069 -61.771006)
			(xy 130.302038 -61.738715) (xy 130.301492 -61.722) (xy 120.904508 -61.722) (xy 120.903962 -61.738715)
			(xy 120.89531 -61.771006) (xy 120.878595 -61.799957) (xy 120.854957 -61.823595) (xy 120.826006 -61.84031)
			(xy 120.793715 -61.848962) (xy 120.777 -61.849508) (xy 119.253 -61.849508) (xy 119.236285 -61.848962)
			(xy 119.203994 -61.84031) (xy 119.175043 -61.823595) (xy 119.151405 -61.799957) (xy 119.13469 -61.771006)
			(xy 119.126038 -61.738715) (xy 119.125492 -61.722) (xy 109.728508 -61.722) (xy 109.727962 -61.738715)
			(xy 109.71931 -61.771006) (xy 109.702595 -61.799957) (xy 109.678957 -61.823595) (xy 109.650006 -61.84031)
			(xy 109.617715 -61.848962) (xy 109.601 -61.849508) (xy 108.077 -61.849508) (xy 108.060285 -61.848962)
			(xy 108.027994 -61.84031) (xy 107.999043 -61.823595) (xy 107.975405 -61.799957) (xy 107.95869 -61.771006)
			(xy 107.950038 -61.738715) (xy 107.949492 -61.722) (xy 102.55747 -61.722) (xy 102.511352 -61.736986)
			(xy 102.50236 -61.740189) (xy 102.487519 -61.752178) (xy 102.478069 -61.768752) (xy 102.4763 -61.778134)
			(xy 102.4689 -61.825803) (xy 102.447763 -61.919936) (xy 102.41954 -62.012192) (xy 102.402386 -62.05728)
			(xy 102.398834 -62.067798) (xy 102.400149 -62.089932) (xy 102.404926 -62.099952) (xy 102.430683 -62.149005)
			(xy 102.474995 -62.250563) (xy 102.510809 -62.355419) (xy 102.537884 -62.462863) (xy 102.556037 -62.57217)
			(xy 102.565144 -62.682598) (xy 102.565708 -62.738) (xy 138.937492 -62.738) (xy 138.938071 -62.683491)
			(xy 138.947439 -62.574875) (xy 138.966078 -62.467462) (xy 138.993854 -62.36204) (xy 139.01166 -62.310518)
			(xy 139.014239 -62.302201) (xy 139.014239 -62.284799) (xy 139.01166 -62.276482) (xy 138.993867 -62.224955)
			(xy 138.966092 -62.119535) (xy 138.947453 -62.012123) (xy 138.938086 -61.903509) (xy 138.937492 -61.849)
			(xy 138.937965 -61.799723) (xy 138.945588 -61.701465) (xy 138.960804 -61.604094) (xy 138.983521 -61.508194)
			(xy 139.013602 -61.414344) (xy 139.050868 -61.323108) (xy 139.095092 -61.235035) (xy 139.14601 -61.150654)
			(xy 139.203315 -61.070473) (xy 139.266661 -60.994975) (xy 139.335669 -60.924614) (xy 139.409923 -60.859814)
			(xy 139.488976 -60.800963) (xy 139.572353 -60.748417) (xy 139.659551 -60.702491) (xy 139.750047 -60.663462)
			(xy 139.79652 -60.647072) (xy 139.805672 -60.64344) (xy 139.820467 -60.630473) (xy 139.829309 -60.612898)
			(xy 139.830556 -60.60313) (xy 139.834582 -60.558545) (xy 139.848104 -60.470043) (xy 139.867814 -60.38271)
			(xy 139.88034 -60.339732) (xy 139.88226 -60.332489) (xy 139.88226 -60.317511) (xy 139.88034 -60.310268)
			(xy 139.867388 -60.265729) (xy 139.847222 -60.175182) (xy 139.83371 -60.083407) (xy 139.826925 -59.99089)
			(xy 139.826492 -59.944508) (xy 139.826492 -59.944) (xy 139.826982 -59.894101) (xy 139.834812 -59.79461)
			(xy 139.850424 -59.696041) (xy 139.873721 -59.599) (xy 139.904561 -59.504086) (xy 139.942752 -59.411884)
			(xy 139.988059 -59.322963) (xy 140.040204 -59.237871) (xy 140.098864 -59.157133) (xy 140.163678 -59.081246)
			(xy 140.234246 -59.010678) (xy 140.310133 -58.945864) (xy 140.390871 -58.887204) (xy 140.475963 -58.835059)
			(xy 140.564884 -58.789752) (xy 140.657086 -58.751561) (xy 140.752 -58.720721) (xy 140.849041 -58.697424)
			(xy 140.94761 -58.681812) (xy 141.047101 -58.673982) (xy 141.146899 -58.673982) (xy 141.24639 -58.681812)
			(xy 141.344959 -58.697424) (xy 141.442 -58.720721) (xy 141.536914 -58.751561) (xy 141.629116 -58.789752)
			(xy 141.718037 -58.835059) (xy 141.803129 -58.887204) (xy 141.883867 -58.945864) (xy 141.959754 -59.010678)
			(xy 142.030322 -59.081246) (xy 142.095136 -59.157133) (xy 142.153796 -59.237871) (xy 142.205941 -59.322963)
			(xy 142.251248 -59.411884) (xy 142.289439 -59.504086) (xy 142.320279 -59.599) (xy 142.343576 -59.696041)
			(xy 142.359188 -59.79461) (xy 142.367018 -59.894101) (xy 142.367508 -59.944) (xy 142.367508 -59.944508)
			(xy 142.367079 -59.990891) (xy 142.360302 -60.083408) (xy 142.34679 -60.175185) (xy 142.326618 -60.26573)
			(xy 142.31366 -60.310268) (xy 142.31174 -60.317511) (xy 142.31174 -60.332489) (xy 142.31366 -60.339732)
			(xy 142.326612 -60.384271) (xy 142.346778 -60.474818) (xy 142.36029 -60.566593) (xy 142.367075 -60.65911)
			(xy 142.367508 -60.705492) (xy 142.367508 -60.706) (xy 142.367035 -60.755277) (xy 142.359412 -60.853535)
			(xy 142.344196 -60.950906) (xy 142.321479 -61.046806) (xy 142.291398 -61.140656) (xy 142.254132 -61.231892)
			(xy 142.209908 -61.319965) (xy 142.15899 -61.404346) (xy 142.101685 -61.484527) (xy 142.038339 -61.560025)
			(xy 141.969331 -61.630386) (xy 141.895077 -61.695186) (xy 141.859058 -61.722) (xy 146.049492 -61.722)
			(xy 146.049492 -60.198) (xy 146.050038 -60.181285) (xy 146.05869 -60.148994) (xy 146.075405 -60.120043)
			(xy 146.099043 -60.096405) (xy 146.127994 -60.07969) (xy 146.160285 -60.071038) (xy 146.177 -60.070492)
			(xy 147.701 -60.070492) (xy 147.717715 -60.071038) (xy 147.750006 -60.07969) (xy 147.778957 -60.096405)
			(xy 147.802595 -60.120043) (xy 147.81931 -60.148994) (xy 147.827962 -60.181285) (xy 147.828508 -60.198)
			(xy 147.828508 -61.722) (xy 157.225492 -61.722) (xy 157.225492 -60.198) (xy 157.226038 -60.181285)
			(xy 157.23469 -60.148994) (xy 157.251405 -60.120043) (xy 157.275043 -60.096405) (xy 157.303994 -60.07969)
			(xy 157.336285 -60.071038) (xy 157.353 -60.070492) (xy 158.877 -60.070492) (xy 158.893715 -60.071038)
			(xy 158.926006 -60.07969) (xy 158.954957 -60.096405) (xy 158.978595 -60.120043) (xy 158.99531 -60.148994)
			(xy 159.003962 -60.181285) (xy 159.004508 -60.198) (xy 159.004508 -61.722) (xy 168.401492 -61.722)
			(xy 168.401492 -60.198) (xy 168.402038 -60.181285) (xy 168.41069 -60.148994) (xy 168.427405 -60.120043)
			(xy 168.451043 -60.096405) (xy 168.479994 -60.07969) (xy 168.512285 -60.071038) (xy 168.529 -60.070492)
			(xy 170.053 -60.070492) (xy 170.069715 -60.071038) (xy 170.102006 -60.07969) (xy 170.130957 -60.096405)
			(xy 170.154595 -60.120043) (xy 170.17131 -60.148994) (xy 170.179962 -60.181285) (xy 170.180508 -60.198)
			(xy 170.180508 -61.722) (xy 170.179962 -61.738715) (xy 170.17131 -61.771006) (xy 170.154595 -61.799957)
			(xy 170.130957 -61.823595) (xy 170.102006 -61.84031) (xy 170.069715 -61.848962) (xy 170.053 -61.849508)
			(xy 168.529 -61.849508) (xy 168.512285 -61.848962) (xy 168.479994 -61.84031) (xy 168.451043 -61.823595)
			(xy 168.427405 -61.799957) (xy 168.41069 -61.771006) (xy 168.402038 -61.738715) (xy 168.401492 -61.722)
			(xy 159.004508 -61.722) (xy 159.003962 -61.738715) (xy 158.99531 -61.771006) (xy 158.978595 -61.799957)
			(xy 158.954957 -61.823595) (xy 158.926006 -61.84031) (xy 158.893715 -61.848962) (xy 158.877 -61.849508)
			(xy 157.353 -61.849508) (xy 157.336285 -61.848962) (xy 157.303994 -61.84031) (xy 157.275043 -61.823595)
			(xy 157.251405 -61.799957) (xy 157.23469 -61.771006) (xy 157.226038 -61.738715) (xy 157.225492 -61.722)
			(xy 147.828508 -61.722) (xy 147.827962 -61.738715) (xy 147.81931 -61.771006) (xy 147.802595 -61.799957)
			(xy 147.778957 -61.823595) (xy 147.750006 -61.84031) (xy 147.717715 -61.848962) (xy 147.701 -61.849508)
			(xy 146.177 -61.849508) (xy 146.160285 -61.848962) (xy 146.127994 -61.84031) (xy 146.099043 -61.823595)
			(xy 146.075405 -61.799957) (xy 146.05869 -61.771006) (xy 146.050038 -61.738715) (xy 146.049492 -61.722)
			(xy 141.859058 -61.722) (xy 141.816024 -61.754037) (xy 141.732647 -61.806583) (xy 141.645449 -61.852509)
			(xy 141.554953 -61.891538) (xy 141.50848 -61.907928) (xy 141.499328 -61.91156) (xy 141.484533 -61.924527)
			(xy 141.475691 -61.942102) (xy 141.474444 -61.95187) (xy 141.469328 -62.007155) (xy 141.450657 -62.116609)
			(xy 141.422498 -62.224015) (xy 141.40434 -62.276482) (xy 141.401761 -62.284799) (xy 141.401761 -62.302201)
			(xy 141.40434 -62.310518) (xy 141.422133 -62.362045) (xy 141.449908 -62.467465) (xy 141.468547 -62.574877)
			(xy 141.477914 -62.683491) (xy 141.478508 -62.738) (xy 141.478018 -62.787899) (xy 141.470188 -62.88739)
			(xy 141.454576 -62.985959) (xy 141.431279 -63.083) (xy 141.400439 -63.177914) (xy 141.362248 -63.270116)
			(xy 141.316941 -63.359037) (xy 141.264796 -63.444129) (xy 141.206136 -63.524867) (xy 141.141322 -63.600754)
			(xy 141.070754 -63.671322) (xy 140.994867 -63.736136) (xy 140.914129 -63.794796) (xy 140.829037 -63.846941)
			(xy 140.740116 -63.892248) (xy 140.647914 -63.930439) (xy 140.553 -63.961279) (xy 140.455959 -63.984576)
			(xy 140.35739 -64.000188) (xy 140.257899 -64.008018) (xy 140.158101 -64.008018) (xy 140.05861 -64.000188)
			(xy 139.960041 -63.984576) (xy 139.863 -63.961279) (xy 139.768086 -63.930439) (xy 139.675884 -63.892248)
			(xy 139.586963 -63.846941) (xy 139.501871 -63.794796) (xy 139.421133 -63.736136) (xy 139.345246 -63.671322)
			(xy 139.274678 -63.600754) (xy 139.209864 -63.524867) (xy 139.151204 -63.444129) (xy 139.099059 -63.359037)
			(xy 139.053752 -63.270116) (xy 139.015561 -63.177914) (xy 138.984721 -63.083) (xy 138.961424 -62.985959)
			(xy 138.945812 -62.88739) (xy 138.937982 -62.787899) (xy 138.937492 -62.738) (xy 102.565708 -62.738)
			(xy 102.565214 -62.789602) (xy 102.557314 -62.892502) (xy 102.54156 -62.994495) (xy 102.518045 -63.094984)
			(xy 102.486906 -63.193377) (xy 102.448327 -63.289098) (xy 102.402534 -63.381585) (xy 102.349795 -63.470296)
			(xy 102.290421 -63.554708) (xy 102.224758 -63.634328) (xy 102.153194 -63.708688) (xy 102.076147 -63.777352)
			(xy 101.994071 -63.839916) (xy 101.907446 -63.896014) (xy 101.81678 -63.945316) (xy 101.722607 -63.987534)
			(xy 101.625479 -64.022418) (xy 101.525965 -64.049765) (xy 101.424649 -64.069414) (xy 101.322127 -64.08125)
			(xy 101.219 -64.085203) (xy 101.115873 -64.08125) (xy 101.013351 -64.069414) (xy 100.912035 -64.049765)
			(xy 100.812521 -64.022418) (xy 100.715393 -63.987534) (xy 100.62122 -63.945316) (xy 100.530554 -63.896014)
			(xy 100.443929 -63.839916) (xy 100.361853 -63.777352) (xy 100.284806 -63.708688) (xy 100.213242 -63.634328)
			(xy 100.147579 -63.554708) (xy 100.088205 -63.470296) (xy 100.035466 -63.381585) (xy 99.989673 -63.289098)
			(xy 99.951094 -63.193377) (xy 99.919955 -63.094984) (xy 99.89644 -62.994495) (xy 99.880686 -62.892502)
			(xy 99.872786 -62.789602) (xy 99.872292 -62.738) (xy 63.9826 -62.738) (xy 63.9826 -66.611246) (xy 63.983148 -66.621602)
			(xy 63.991415 -66.640599) (xy 63.998602 -66.648076) (xy 64.040064 -66.6877) (xy 64.118085 -66.771776)
			(xy 64.190179 -66.860986) (xy 64.256009 -66.954913) (xy 64.315268 -67.053119) (xy 64.367678 -67.155144)
			(xy 64.390778 -67.207638) (xy 64.396112 -67.220592) (xy 64.417205 -67.271994) (xy 64.453348 -67.377071)
			(xy 64.482459 -67.484309) (xy 64.504409 -67.593239) (xy 64.519103 -67.703382) (xy 64.526475 -67.814256)
			(xy 64.526922 -67.869816) (xy 64.526384 -67.930562) (xy 64.517592 -68.051735) (xy 64.50005 -68.171953)
			(xy 64.473848 -68.290586) (xy 64.439124 -68.40701) (xy 64.396061 -68.520614) (xy 64.370966 -68.575936)
			(xy 64.365378 -68.587874) (xy 64.367156 -68.613528) (xy 64.427608 -68.708016) (xy 64.450468 -68.720208)
			(xy 64.470026 -68.720208) (xy 64.527727 -68.720701) (xy 64.642859 -68.728578) (xy 64.757186 -68.744294)
			(xy 64.870173 -68.767774) (xy 64.981295 -68.798911) (xy 65.090033 -68.837558) (xy 65.19588 -68.883535)
			(xy 65.298343 -68.936628) (xy 65.396944 -68.99659) (xy 65.491223 -69.063141) (xy 65.580741 -69.13597)
			(xy 65.66508 -69.214739) (xy 65.743847 -69.299079) (xy 65.816675 -69.388598) (xy 65.883224 -69.482878)
			(xy 65.943184 -69.581479) (xy 65.996276 -69.683943) (xy 66.042252 -69.789791) (xy 66.080897 -69.89853)
			(xy 66.112032 -70.009652) (xy 66.135511 -70.12264) (xy 66.151225 -70.236967) (xy 66.1591 -70.352099)
			(xy 66.1591 -70.409816) (xy 66.589915 -70.409816) (xy 66.593942 -70.293213) (xy 66.606004 -70.177166)
			(xy 66.626043 -70.062228) (xy 66.653965 -69.948946) (xy 66.689635 -69.83786) (xy 66.732884 -69.7295)
			(xy 66.783507 -69.624382) (xy 66.84126 -69.523007) (xy 66.905871 -69.425858) (xy 66.977029 -69.333398)
			(xy 67.054397 -69.246067) (xy 67.137606 -69.164283) (xy 67.226259 -69.088434) (xy 67.319933 -69.018882)
			(xy 67.418183 -68.955958) (xy 67.52054 -68.899962) (xy 67.626516 -68.851162) (xy 67.735607 -68.80979)
			(xy 67.847291 -68.776042) (xy 67.961038 -68.75008) (xy 68.076306 -68.732027) (xy 68.192544 -68.72197)
			(xy 68.309198 -68.719956) (xy 68.425714 -68.725995) (xy 68.541536 -68.740059) (xy 68.656111 -68.762079)
			(xy 68.768894 -68.791952) (xy 68.879348 -68.829534) (xy 68.986945 -68.874648) (xy 69.091174 -68.927077)
			(xy 69.191537 -68.986572) (xy 69.287556 -69.052849) (xy 69.378774 -69.125593) (xy 69.464756 -69.204457)
			(xy 69.545093 -69.289065) (xy 69.6194 -69.379014) (xy 69.687325 -69.473875) (xy 69.748544 -69.573196)
			(xy 69.802764 -69.676504) (xy 69.849728 -69.783307) (xy 69.889211 -69.893095) (xy 69.921026 -70.005346)
			(xy 69.945021 -70.119524) (xy 69.961081 -70.235086) (xy 69.96913 -70.35148) (xy 69.969634 -70.409816)
			(xy 69.96913 -70.468152) (xy 69.961081 -70.584546) (xy 69.945021 -70.700108) (xy 69.921026 -70.814286)
			(xy 69.889211 -70.926537) (xy 69.849728 -71.036325) (xy 69.802764 -71.143128) (xy 69.748544 -71.246436)
			(xy 69.687325 -71.345757) (xy 69.6194 -71.440618) (xy 69.545093 -71.530567) (xy 69.464756 -71.615175)
			(xy 69.378774 -71.694039) (xy 69.287556 -71.766783) (xy 69.191537 -71.83306) (xy 69.091174 -71.892555)
			(xy 68.986945 -71.944984) (xy 68.879348 -71.990098) (xy 68.768894 -72.02768) (xy 68.656111 -72.057553)
			(xy 68.541536 -72.079573) (xy 68.425714 -72.093637) (xy 68.309198 -72.099676) (xy 68.192544 -72.097662)
			(xy 68.076306 -72.087605) (xy 67.961038 -72.069552) (xy 67.847291 -72.04359) (xy 67.735607 -72.009842)
			(xy 67.626516 -71.96847) (xy 67.52054 -71.91967) (xy 67.418183 -71.863674) (xy 67.319933 -71.80075)
			(xy 67.226259 -71.731198) (xy 67.137606 -71.655349) (xy 67.054397 -71.573565) (xy 66.977029 -71.486234)
			(xy 66.905871 -71.393774) (xy 66.84126 -71.296625) (xy 66.783507 -71.19525) (xy 66.732884 -71.090132)
			(xy 66.689635 -70.981772) (xy 66.653965 -70.870686) (xy 66.626043 -70.757404) (xy 66.606004 -70.642466)
			(xy 66.593942 -70.526419) (xy 66.589915 -70.409816) (xy 66.1591 -70.409816) (xy 66.1591 -70.467501)
			(xy 66.151225 -70.582633) (xy 66.135511 -70.69696) (xy 66.112032 -70.809948) (xy 66.080897 -70.92107)
			(xy 66.042252 -71.029809) (xy 65.996276 -71.135657) (xy 65.943184 -71.238121) (xy 65.883224 -71.336722)
			(xy 65.816675 -71.431002) (xy 65.743847 -71.520521) (xy 65.66508 -71.604861) (xy 65.580741 -71.68363)
			(xy 65.491223 -71.756459) (xy 65.396944 -71.82301) (xy 65.298343 -71.882972) (xy 65.19588 -71.936065)
			(xy 65.090033 -71.982042) (xy 64.981295 -72.020689) (xy 64.870173 -72.051826) (xy 64.757186 -72.075306)
			(xy 64.642859 -72.091022) (xy 64.527727 -72.098899) (xy 64.470026 -72.099424) (xy 64.41283 -72.098949)
			(xy 64.298699 -72.091212) (xy 64.185353 -72.075771) (xy 64.073311 -72.052698) (xy 63.963087 -72.022097)
			(xy 63.855186 -71.98411) (xy 63.750102 -71.93891) (xy 63.648317 -71.886704) (xy 63.550297 -71.827732)
			(xy 63.45649 -71.762263) (xy 63.411608 -71.726806) (xy 63.400178 -71.717662) (xy 63.371222 -71.71436)
			(xy 63.275464 -71.760334) (xy 63.266998 -71.764785) (xy 63.253927 -71.778728) (xy 63.246891 -71.796498)
			(xy 63.246508 -71.806054) (xy 63.246508 -72.852026) (xy 63.246987 -72.861991) (xy 63.254565 -72.880425)
			(xy 63.26124 -72.88784) (xy 64.704214 -74.330814) (xy 64.711609 -74.337668) (xy 64.730208 -74.34541)
			(xy 64.740282 -74.3458)
		)
		(stroke
			(width 0)
			(type solid)
		)
		(fill yes)
		(layer "B.Cu")
		(net "P12V_BRICK")
	)
	(gr_poly
		(pts
			(xy 222.089472 -145.000726) (xy 222.099523 -145.000222) (xy 222.118086 -144.992502) (xy 222.12554 -144.98574)
			(xy 222.743014 -144.368266) (xy 222.749865 -144.36087) (xy 222.7576 -144.342271) (xy 222.758 -144.332198)
			(xy 222.758 -144.028668) (xy 222.757625 -144.019195) (xy 222.750759 -144.001538) (xy 222.737942 -143.987586)
			(xy 222.720929 -143.979251) (xy 222.711518 -143.978122) (xy 222.646862 -143.972174) (xy 222.51839 -143.953282)
			(xy 222.391334 -143.926472) (xy 222.266181 -143.891849) (xy 222.143412 -143.849543) (xy 222.023497 -143.799719)
			(xy 221.906897 -143.742566) (xy 221.794058 -143.678305) (xy 221.685415 -143.607181) (xy 221.581383 -143.529468)
			(xy 221.482361 -143.445463) (xy 221.38873 -143.35549) (xy 221.300849 -143.259892) (xy 221.219054 -143.159038)
			(xy 221.14366 -143.053313) (xy 221.074956 -142.943123) (xy 221.013205 -142.828891) (xy 220.958645 -142.711056)
			(xy 220.911484 -142.590069) (xy 220.871903 -142.466394) (xy 220.840055 -142.340506) (xy 220.816062 -142.212889)
			(xy 220.800015 -142.08403) (xy 220.791976 -141.954425) (xy 220.791976 -141.824571) (xy 220.800015 -141.694967)
			(xy 220.816062 -141.566108) (xy 220.840056 -141.43849) (xy 220.871904 -141.312603) (xy 220.911485 -141.188928)
			(xy 220.958646 -141.067941) (xy 221.013207 -140.950106) (xy 221.074958 -140.835874) (xy 221.143662 -140.725685)
			(xy 221.219056 -140.61996) (xy 221.300851 -140.519105) (xy 221.388732 -140.423508) (xy 221.482364 -140.333534)
			(xy 221.581385 -140.24953) (xy 221.685418 -140.171817) (xy 221.794061 -140.100693) (xy 221.9069 -140.036432)
			(xy 222.0235 -139.97928) (xy 222.143415 -139.929455) (xy 222.266184 -139.88715) (xy 222.391337 -139.852527)
			(xy 222.518393 -139.825718) (xy 222.646866 -139.806826) (xy 222.711518 -139.800838) (xy 222.720903 -139.799638)
			(xy 222.737867 -139.791285) (xy 222.750655 -139.777358) (xy 222.757533 -139.759745) (xy 222.758 -139.750292)
			(xy 222.758 -117.724682) (xy 222.757573 -117.714613) (xy 222.749854 -117.696014) (xy 222.743014 -117.688614)
			(xy 222.228664 -117.174264) (xy 222.221267 -117.167416) (xy 222.202668 -117.159685) (xy 222.192596 -117.159278)
			(xy 193.520314 -117.159278) (xy 193.507106 -117.163088) (xy 193.50101 -117.166644) (xy 193.494904 -117.170145)
			(xy 193.481374 -117.174007) (xy 193.47434 -117.174264) (xy 179.056284 -117.174264) (xy 179.046276 -117.174754)
			(xy 179.027783 -117.182415) (xy 179.013627 -117.196566) (xy 179.005958 -117.215056) (xy 179.005484 -117.225064)
			(xy 179.005484 -117.542818) (xy 179.005058 -117.552821) (xy 178.997377 -117.571294) (xy 178.983198 -117.585408)
			(xy 178.964689 -117.593004) (xy 178.954684 -117.593364) (xy 178.94554 -117.593364) (xy 178.94554 -117.80774)
			(xy 178.945046 -117.817745) (xy 178.93738 -117.83623) (xy 178.92323 -117.85038) (xy 178.904745 -117.858046)
			(xy 178.89474 -117.85854) (xy 178.892708 -117.85854) (xy 178.882689 -117.858959) (xy 178.864176 -117.866629)
			(xy 178.850011 -117.880803) (xy 178.842353 -117.89932) (xy 178.841908 -117.90934) (xy 178.841908 -118.828312)
			(xy 178.842451 -118.839329) (xy 178.851674 -118.85934) (xy 178.859688 -118.86692) (xy 178.918769 -118.918227)
			(xy 179.032251 -119.025989) (xy 179.140125 -119.139364) (xy 179.242115 -119.258061) (xy 179.337957 -119.381774)
			(xy 179.427406 -119.510186) (xy 179.510231 -119.642967) (xy 179.586221 -119.779775) (xy 179.655179 -119.920259)
			(xy 179.716927 -120.064057) (xy 179.771309 -120.210799) (xy 179.818183 -120.36011) (xy 179.857429 -120.511604)
			(xy 179.888947 -120.664893) (xy 179.912655 -120.819582) (xy 179.928492 -120.975274) (xy 179.936418 -121.131568)
			(xy 179.936902 -121.209816) (xy 179.936407 -121.288021) (xy 179.928485 -121.444229) (xy 179.912661 -121.599836)
			(xy 179.888976 -121.754442) (xy 179.857491 -121.90765) (xy 179.818287 -122.059066) (xy 179.771464 -122.208303)
			(xy 179.717142 -122.354976) (xy 179.701501 -122.391424) (xy 183.16194 -122.391424) (xy 183.16194 -120.028716)
			(xy 183.162449 -120.012019) (xy 183.17108 -119.979759) (xy 183.187759 -119.950829) (xy 183.211352 -119.927195)
			(xy 183.240253 -119.910465) (xy 183.272498 -119.901778) (xy 183.289194 -119.901208) (xy 185.651394 -119.901208)
			(xy 185.668051 -119.901792) (xy 185.700234 -119.910401) (xy 185.729098 -119.927035) (xy 185.752683 -119.950564)
			(xy 185.769384 -119.97939) (xy 185.778069 -120.011552) (xy 185.778648 -120.028208) (xy 185.778648 -122.390916)
			(xy 185.77808 -122.407607) (xy 185.769449 -122.439855) (xy 185.752777 -122.468777) (xy 185.729198 -122.492407)
			(xy 185.700313 -122.509142) (xy 185.668084 -122.517843) (xy 185.651394 -122.518424) (xy 183.289194 -122.518424)
			(xy 183.272531 -122.517917) (xy 183.240337 -122.5093) (xy 183.211466 -122.492653) (xy 183.187881 -122.469107)
			(xy 183.171184 -122.440265) (xy 183.162511 -122.408086) (xy 183.16194 -122.391424) (xy 179.701501 -122.391424)
			(xy 179.655461 -122.498709) (xy 179.586579 -122.639135) (xy 179.510673 -122.775891) (xy 179.427938 -122.908627)
			(xy 179.338587 -123.037002) (xy 179.242848 -123.160686) (xy 179.140967 -123.279363) (xy 179.033206 -123.392728)
			(xy 178.919841 -123.500489) (xy 178.801164 -123.60237) (xy 178.67748 -123.698109) (xy 178.549105 -123.78746)
			(xy 178.416369 -123.870195) (xy 178.279613 -123.946101) (xy 178.139187 -124.014983) (xy 177.995454 -124.076664)
			(xy 177.848781 -124.130986) (xy 177.699544 -124.177809) (xy 177.548128 -124.217013) (xy 177.39492 -124.248498)
			(xy 177.240314 -124.272183) (xy 177.084707 -124.288007) (xy 176.928499 -124.295929) (xy 176.772089 -124.295929)
			(xy 176.615881 -124.288007) (xy 176.460274 -124.272183) (xy 176.305668 -124.248498) (xy 176.15246 -124.217013)
			(xy 176.001044 -124.177809) (xy 175.851807 -124.130986) (xy 175.705134 -124.076664) (xy 175.561401 -124.014983)
			(xy 175.420975 -123.946101) (xy 175.284219 -123.870195) (xy 175.151483 -123.78746) (xy 175.023108 -123.698109)
			(xy 174.899424 -123.60237) (xy 174.780747 -123.500489) (xy 174.667382 -123.392728) (xy 174.559621 -123.279363)
			(xy 174.45774 -123.160686) (xy 174.362001 -123.037002) (xy 174.27265 -122.908627) (xy 174.189915 -122.775891)
			(xy 174.114009 -122.639135) (xy 174.045127 -122.498709) (xy 173.983446 -122.354976) (xy 173.929124 -122.208303)
			(xy 173.882301 -122.059066) (xy 173.843097 -121.90765) (xy 173.811612 -121.754442) (xy 173.787927 -121.599836)
			(xy 173.772103 -121.444229) (xy 173.764181 -121.288021) (xy 173.763686 -121.209816) (xy 173.764176 -121.131569)
			(xy 173.772111 -120.975278) (xy 173.787957 -120.819589) (xy 173.811671 -120.664903) (xy 173.843195 -120.511618)
			(xy 173.882446 -120.360127) (xy 173.929324 -120.21082) (xy 173.983708 -120.064081) (xy 174.045459 -119.920286)
			(xy 174.114417 -119.779806) (xy 174.190406 -119.643) (xy 174.273231 -119.510222) (xy 174.362678 -119.381811)
			(xy 174.458517 -119.258098) (xy 174.560503 -119.139401) (xy 174.668373 -119.026025) (xy 174.78185 -118.918261)
			(xy 174.8409 -118.86692) (xy 174.848927 -118.859349) (xy 174.858155 -118.839333) (xy 174.85868 -118.828312)
			(xy 174.85868 -117.90934) (xy 174.858267 -117.899315) (xy 174.850603 -117.880788) (xy 174.836429 -117.866608)
			(xy 174.817905 -117.858937) (xy 174.80788 -117.85854) (xy 174.805848 -117.85854) (xy 174.795817 -117.858129)
			(xy 174.777277 -117.850469) (xy 174.76308 -117.836297) (xy 174.755388 -117.81777) (xy 174.755048 -117.80774)
			(xy 174.755048 -117.720364) (xy 174.754492 -117.710382) (xy 174.746771 -117.691961) (xy 174.73265 -117.677835)
			(xy 174.71423 -117.67011) (xy 174.704248 -117.669564) (xy 154.869388 -117.669564) (xy 154.805013 -117.669027)
			(xy 154.676534 -117.660673) (xy 154.548863 -117.64404) (xy 154.422533 -117.619196) (xy 154.29807 -117.586247)
			(xy 154.175995 -117.545329) (xy 154.056818 -117.496613) (xy 153.941035 -117.440302) (xy 153.82913 -117.376632)
			(xy 153.72157 -117.305868) (xy 153.618805 -117.228306) (xy 153.56967 -117.18671) (xy 153.53665 -117.174264)
			(xy 152.23617 -117.174264) (xy 152.226184 -117.174806) (xy 152.207757 -117.182523) (xy 152.200356 -117.18925)
			(xy 151.843232 -117.54612) (xy 151.836454 -117.553544) (xy 151.828863 -117.572141) (xy 151.8285 -117.582188)
			(xy 151.806148 -117.60454) (xy 151.796117 -117.604979) (xy 151.777545 -117.612557) (xy 151.77008 -117.619272)
			(xy 151.757126 -117.63248) (xy 151.714181 -117.674789) (xy 151.623926 -117.754728) (xy 151.529001 -117.829061)
			(xy 151.429754 -117.897518) (xy 151.326548 -117.959846) (xy 151.219761 -118.015818) (xy 151.109784 -118.065228)
			(xy 150.99702 -118.107896) (xy 150.881882 -118.143666) (xy 150.764791 -118.172406) (xy 150.705566 -118.18366)
			(xy 150.694136 -118.186962) (xy 150.63916 -118.210784) (xy 150.52687 -118.252612) (xy 150.41228 -118.287654)
			(xy 150.295802 -118.315786) (xy 150.17785 -118.336907) (xy 150.058848 -118.350942) (xy 149.939219 -118.35784)
			(xy 149.879304 -118.358158) (xy 149.879304 -118.357904) (xy 149.597364 -118.357904) (xy 149.597364 -118.360444)
			(xy 148.073872 -118.360444) (xy 148.073872 -118.360698) (xy 146.027648 -118.360698) (xy 145.962406 -118.360168)
			(xy 145.8322 -118.351669) (xy 145.702823 -118.334718) (xy 145.574822 -118.309386) (xy 145.448741 -118.27578)
			(xy 145.325113 -118.234043) (xy 145.204462 -118.184352) (xy 145.087299 -118.126916) (xy 144.974121 -118.061981)
			(xy 144.865408 -117.989819) (xy 144.761619 -117.910739) (xy 144.663195 -117.825073) (xy 144.570552 -117.733186)
			(xy 144.484083 -117.635467) (xy 144.443704 -117.58422) (xy 143.79448 -117.58422) (xy 143.767833 -117.585635)
			(xy 143.714485 -117.587158) (xy 143.6878 -117.587268) (xy 142.3162 -117.587268) (xy 142.252272 -117.58674)
			(xy 142.124705 -117.578168) (xy 141.997998 -117.561064) (xy 141.872724 -117.535505) (xy 141.749445 -117.501604)
			(xy 141.628716 -117.459516) (xy 141.51108 -117.409428) (xy 141.397066 -117.351567) (xy 141.287188 -117.286193)
			(xy 141.18194 -117.2136) (xy 141.131544 -117.174264) (xy 139.056364 -117.174264) (xy 139.046358 -117.174758)
			(xy 139.027873 -117.182422) (xy 139.013722 -117.196573) (xy 139.006058 -117.215058) (xy 139.005564 -117.225064)
			(xy 139.005564 -117.542564) (xy 139.00515 -117.552587) (xy 138.997485 -117.57111) (xy 138.98331 -117.585285)
			(xy 138.964787 -117.59295) (xy 138.954764 -117.593364) (xy 138.94562 -117.593364) (xy 138.94562 -117.80774)
			(xy 138.945126 -117.817744) (xy 138.93746 -117.836225) (xy 138.923309 -117.850371) (xy 138.904824 -117.858029)
			(xy 138.89482 -117.85854) (xy 138.892788 -117.85854) (xy 138.882816 -117.859025) (xy 138.864384 -117.866641)
			(xy 138.850254 -117.880715) (xy 138.842565 -117.899117) (xy 138.841988 -117.909086) (xy 138.841988 -118.828566)
			(xy 138.859514 -118.86692) (xy 138.918595 -118.918227) (xy 139.032076 -119.025989) (xy 139.139949 -119.139365)
			(xy 139.241938 -119.258062) (xy 139.337779 -119.381776) (xy 139.427227 -119.510188) (xy 139.510052 -119.642969)
			(xy 139.586041 -119.779777) (xy 139.654998 -119.92026) (xy 139.716746 -120.064058) (xy 139.771127 -120.210801)
			(xy 139.818001 -120.360111) (xy 139.857247 -120.511605) (xy 139.888764 -120.664894) (xy 139.912472 -120.819583)
			(xy 139.928309 -120.975274) (xy 139.936235 -121.131568) (xy 139.936728 -121.209816) (xy 139.936233 -121.288021)
			(xy 139.928311 -121.444229) (xy 139.912487 -121.599836) (xy 139.888802 -121.754442) (xy 139.857317 -121.90765)
			(xy 139.818113 -122.059066) (xy 139.77129 -122.208303) (xy 139.716968 -122.354976) (xy 139.701545 -122.390916)
			(xy 143.161512 -122.390916) (xy 143.161512 -120.028716) (xy 143.162003 -120.011994) (xy 143.170656 -119.979688)
			(xy 143.187378 -119.950724) (xy 143.211027 -119.927075) (xy 143.239992 -119.910355) (xy 143.272298 -119.901702)
			(xy 143.28902 -119.901208) (xy 145.65122 -119.901208) (xy 145.667937 -119.90172) (xy 145.700231 -119.910379)
			(xy 145.729184 -119.9271) (xy 145.752822 -119.950745) (xy 145.769535 -119.979702) (xy 145.778184 -120.011999)
			(xy 145.778728 -120.028716) (xy 145.778728 -121.209816) (xy 166.143183 -121.209816) (xy 166.147209 -121.052186)
			(xy 166.15928 -120.894968) (xy 166.179362 -120.738571) (xy 166.207404 -120.583403) (xy 166.243332 -120.42987)
			(xy 166.287053 -120.278371) (xy 166.338452 -120.129302) (xy 166.397396 -119.983053) (xy 166.463731 -119.840003)
			(xy 166.537283 -119.700528) (xy 166.617861 -119.56499) (xy 166.705255 -119.433743) (xy 166.799236 -119.30713)
			(xy 166.899559 -119.185481) (xy 167.005964 -119.069113) (xy 167.118171 -118.958329) (xy 167.235888 -118.85342)
			(xy 167.358809 -118.754658) (xy 167.486612 -118.662302) (xy 167.618964 -118.576591) (xy 167.75552 -118.497751)
			(xy 167.895923 -118.425986) (xy 168.039808 -118.361483) (xy 168.186798 -118.304412) (xy 168.336511 -118.25492)
			(xy 168.488556 -118.213138) (xy 168.642535 -118.179173) (xy 168.798049 -118.153115) (xy 168.954689 -118.135032)
			(xy 169.112049 -118.12497) (xy 169.269718 -118.122956) (xy 169.427283 -118.128996) (xy 169.584335 -118.143073)
			(xy 169.740462 -118.165151) (xy 169.895259 -118.195172) (xy 170.048321 -118.233058) (xy 170.199249 -118.27871)
			(xy 170.347649 -118.332009) (xy 170.493134 -118.392816) (xy 170.635325 -118.460972) (xy 170.77385 -118.536299)
			(xy 170.908348 -118.618601) (xy 171.038468 -118.707664) (xy 171.16387 -118.803254) (xy 171.284229 -118.905123)
			(xy 171.399228 -119.013004) (xy 171.50857 -119.126617) (xy 171.611967 -119.245665) (xy 171.709151 -119.369836)
			(xy 171.799868 -119.498808) (xy 171.883881 -119.632244) (xy 171.960972 -119.769796) (xy 172.030938 -119.911104)
			(xy 172.093597 -120.055801) (xy 172.148787 -120.203508) (xy 172.196363 -120.353841) (xy 172.2362 -120.506407)
			(xy 172.268196 -120.660808) (xy 172.292266 -120.816641) (xy 172.308347 -120.9735) (xy 172.316399 -121.130975)
			(xy 172.316902 -121.209816) (xy 172.316399 -121.288657) (xy 172.308347 -121.446132) (xy 172.292266 -121.602991)
			(xy 172.268196 -121.758824) (xy 172.2362 -121.913225) (xy 172.196363 -122.065791) (xy 172.148787 -122.216124)
			(xy 172.093597 -122.363831) (xy 172.030938 -122.508528) (xy 171.960972 -122.649836) (xy 171.883881 -122.787388)
			(xy 171.799868 -122.920824) (xy 171.709151 -123.049796) (xy 171.611967 -123.173967) (xy 171.50857 -123.293015)
			(xy 171.399228 -123.406628) (xy 171.284229 -123.514509) (xy 171.16387 -123.616378) (xy 171.038468 -123.711968)
			(xy 170.908348 -123.801031) (xy 170.77385 -123.883333) (xy 170.635325 -123.95866) (xy 170.493134 -124.026816)
			(xy 170.347649 -124.087623) (xy 170.199249 -124.140922) (xy 170.048321 -124.186574) (xy 169.895259 -124.22446)
			(xy 169.740462 -124.254481) (xy 169.584335 -124.276559) (xy 169.427283 -124.290636) (xy 169.269718 -124.296676)
			(xy 169.112049 -124.294662) (xy 168.954689 -124.2846) (xy 168.798049 -124.266517) (xy 168.642535 -124.240459)
			(xy 168.488556 -124.206494) (xy 168.336511 -124.164712) (xy 168.186798 -124.11522) (xy 168.039808 -124.058149)
			(xy 167.895923 -123.993646) (xy 167.75552 -123.921881) (xy 167.618964 -123.843041) (xy 167.486612 -123.75733)
			(xy 167.358809 -123.664974) (xy 167.235888 -123.566212) (xy 167.118171 -123.461303) (xy 167.005964 -123.350519)
			(xy 166.899559 -123.234151) (xy 166.799236 -123.112502) (xy 166.705255 -122.985889) (xy 166.617861 -122.854642)
			(xy 166.537283 -122.719104) (xy 166.463731 -122.579629) (xy 166.397396 -122.436579) (xy 166.338452 -122.29033)
			(xy 166.287053 -122.141261) (xy 166.243332 -121.989762) (xy 166.207404 -121.836229) (xy 166.179362 -121.681061)
			(xy 166.15928 -121.524664) (xy 166.147209 -121.367446) (xy 166.143183 -121.209816) (xy 145.778728 -121.209816)
			(xy 145.778728 -122.390916) (xy 145.778177 -122.40763) (xy 145.769522 -122.439918) (xy 145.752807 -122.468867)
			(xy 145.72917 -122.492505) (xy 145.700222 -122.509221) (xy 145.667934 -122.517876) (xy 145.65122 -122.518424)
			(xy 143.28902 -122.518424) (xy 143.272301 -122.517894) (xy 143.240001 -122.509245) (xy 143.21104 -122.49253)
			(xy 143.187392 -122.468889) (xy 143.170669 -122.439933) (xy 143.16201 -122.407635) (xy 143.161512 -122.390916)
			(xy 139.701545 -122.390916) (xy 139.655287 -122.498709) (xy 139.586405 -122.639135) (xy 139.510499 -122.775891)
			(xy 139.427764 -122.908627) (xy 139.338413 -123.037002) (xy 139.242674 -123.160686) (xy 139.140793 -123.279363)
			(xy 139.033032 -123.392728) (xy 138.919667 -123.500489) (xy 138.80099 -123.60237) (xy 138.677306 -123.698109)
			(xy 138.548931 -123.78746) (xy 138.416195 -123.870195) (xy 138.279439 -123.946101) (xy 138.139013 -124.014983)
			(xy 137.99528 -124.076664) (xy 137.848607 -124.130986) (xy 137.69937 -124.177809) (xy 137.547954 -124.217013)
			(xy 137.394746 -124.248498) (xy 137.24014 -124.272183) (xy 137.084533 -124.288007) (xy 136.928325 -124.295929)
			(xy 136.771915 -124.295929) (xy 136.615707 -124.288007) (xy 136.4601 -124.272183) (xy 136.305494 -124.248498)
			(xy 136.152286 -124.217013) (xy 136.00087 -124.177809) (xy 135.851633 -124.130986) (xy 135.70496 -124.076664)
			(xy 135.561227 -124.014983) (xy 135.420801 -123.946101) (xy 135.284045 -123.870195) (xy 135.151309 -123.78746)
			(xy 135.022934 -123.698109) (xy 134.89925 -123.60237) (xy 134.780573 -123.500489) (xy 134.667208 -123.392728)
			(xy 134.559447 -123.279363) (xy 134.457566 -123.160686) (xy 134.361827 -123.037002) (xy 134.272476 -122.908627)
			(xy 134.189741 -122.775891) (xy 134.113835 -122.639135) (xy 134.044953 -122.498709) (xy 133.983272 -122.354976)
			(xy 133.92895 -122.208303) (xy 133.882127 -122.059066) (xy 133.842923 -121.90765) (xy 133.811438 -121.754442)
			(xy 133.787753 -121.599836) (xy 133.771929 -121.444229) (xy 133.764007 -121.288021) (xy 133.763512 -121.209816)
			(xy 133.764002 -121.131569) (xy 133.771937 -120.975277) (xy 133.787782 -120.819588) (xy 133.811497 -120.664902)
			(xy 133.84302 -120.511616) (xy 133.88227 -120.360124) (xy 133.929147 -120.210817) (xy 133.98353 -120.064077)
			(xy 134.04528 -119.920281) (xy 134.114237 -119.779799) (xy 134.190225 -119.642993) (xy 134.273048 -119.510213)
			(xy 134.362494 -119.3818) (xy 134.458332 -119.258086) (xy 134.560316 -119.139387) (xy 134.668185 -119.026009)
			(xy 134.78166 -118.918243) (xy 134.840726 -118.86692) (xy 134.858252 -118.828566) (xy 134.858252 -117.909086)
			(xy 134.857695 -117.899122) (xy 134.849968 -117.880745) (xy 134.835835 -117.866685) (xy 134.817418 -117.859052)
			(xy 134.807452 -117.85854) (xy 134.80542 -117.85854) (xy 134.795444 -117.857977) (xy 134.777039 -117.850248)
			(xy 134.762929 -117.836127) (xy 134.755215 -117.817716) (xy 134.75462 -117.80774) (xy 134.75462 -117.644164)
			(xy 134.754126 -117.63416) (xy 134.746461 -117.615677) (xy 134.73231 -117.60153) (xy 134.713825 -117.593871)
			(xy 134.70382 -117.593364) (xy 134.694676 -117.593364) (xy 134.694676 -117.225064) (xy 134.694181 -117.215063)
			(xy 134.686515 -117.196588) (xy 134.672362 -117.182452) (xy 134.653878 -117.174807) (xy 134.643876 -117.174264)
			(xy 111.938816 -117.174264) (xy 111.928804 -117.174749) (xy 111.9103 -117.182404) (xy 111.896133 -117.196556)
			(xy 111.888459 -117.215052) (xy 111.888016 -117.225064) (xy 111.888016 -117.288818) (xy 111.887589 -117.298816)
			(xy 111.879906 -117.317278) (xy 111.865724 -117.331375) (xy 111.847217 -117.338948) (xy 111.837216 -117.339364)
			(xy 111.828072 -117.339364) (xy 111.828072 -117.55374) (xy 111.827577 -117.56374) (xy 111.819909 -117.582214)
			(xy 111.805757 -117.596347) (xy 111.787273 -117.60399) (xy 111.777272 -117.60454) (xy 111.46282 -117.60454)
			(xy 111.4425 -117.613938) (xy 111.435134 -117.623082) (xy 111.394519 -117.671938) (xy 111.307998 -117.764991)
			(xy 111.215755 -117.852376) (xy 111.11816 -117.93374) (xy 111.015607 -118.008757) (xy 110.908506 -118.077126)
			(xy 110.797288 -118.138571) (xy 110.682401 -118.192846) (xy 110.564306 -118.239733) (xy 110.443477 -118.279042)
			(xy 110.3204 -118.310618) (xy 110.19557 -118.334331) (xy 110.069489 -118.350087) (xy 109.942662 -118.357824)
			(xy 109.87913 -118.358158) (xy 109.87913 -118.357904) (xy 109.597444 -118.357904) (xy 109.597444 -118.360444)
			(xy 106.617008 -118.360444) (xy 106.60702 -118.359896) (xy 106.588585 -118.352182) (xy 106.574447 -118.338059)
			(xy 106.566715 -118.319632) (xy 106.566208 -118.309644) (xy 106.566208 -118.3005) (xy 106.35234 -118.3005)
			(xy 106.342313 -118.300087) (xy 106.323783 -118.292425) (xy 106.309598 -118.278251) (xy 106.30192 -118.259726)
			(xy 106.30154 -118.2497) (xy 106.30154 -117.934994) (xy 106.291888 -117.914674) (xy 106.282744 -117.907308)
			(xy 106.233368 -117.866243) (xy 106.139377 -117.77871) (xy 106.051185 -117.685338) (xy 105.969151 -117.586511)
			(xy 105.893615 -117.482634) (xy 105.824884 -117.374134) (xy 105.763242 -117.261455) (xy 105.735628 -117.203474)
			(xy 105.689654 -117.174264) (xy 99.055936 -117.174264) (xy 99.045921 -117.174745) (xy 99.027411 -117.182397)
			(xy 99.013238 -117.19655) (xy 99.005559 -117.21505) (xy 99.005136 -117.225064) (xy 99.005136 -117.542818)
			(xy 99.004709 -117.552818) (xy 98.997027 -117.571282) (xy 98.982845 -117.585385) (xy 98.964338 -117.592964)
			(xy 98.954336 -117.593364) (xy 98.945192 -117.593364) (xy 98.945192 -117.80774) (xy 98.944697 -117.817742)
			(xy 98.93703 -117.836218) (xy 98.922878 -117.850357) (xy 98.904394 -117.858006) (xy 98.894392 -117.85854)
			(xy 98.89236 -117.85854) (xy 98.882361 -117.859036) (xy 98.86389 -117.866704) (xy 98.849759 -117.880857)
			(xy 98.84212 -117.89934) (xy 98.84156 -117.90934) (xy 98.84156 -118.828312) (xy 98.842102 -118.83933)
			(xy 98.851319 -118.859347) (xy 98.85934 -118.86692) (xy 98.918422 -118.918226) (xy 99.031905 -119.025987)
			(xy 99.139781 -119.139362) (xy 99.241772 -119.258058) (xy 99.337616 -119.381771) (xy 99.427066 -119.510183)
			(xy 99.509893 -119.642964) (xy 99.585884 -119.779771) (xy 99.654843 -119.920255) (xy 99.716593 -120.064053)
			(xy 99.770975 -120.210796) (xy 99.81785 -120.360107) (xy 99.857097 -120.511602) (xy 99.888615 -120.664891)
			(xy 99.912323 -120.819581) (xy 99.928161 -120.975273) (xy 99.936087 -121.131568) (xy 99.936554 -121.209816)
			(xy 99.936059 -121.288021) (xy 99.928137 -121.444229) (xy 99.912313 -121.599836) (xy 99.888628 -121.754442)
			(xy 99.857143 -121.90765) (xy 99.817939 -122.059066) (xy 99.771116 -122.208303) (xy 99.716794 -122.354976)
			(xy 99.701153 -122.391424) (xy 103.161592 -122.391424) (xy 103.161592 -120.028716) (xy 103.162148 -120.012023)
			(xy 103.170775 -119.97977) (xy 103.187447 -119.950845) (xy 103.21103 -119.927212) (xy 103.23992 -119.910479)
			(xy 103.272154 -119.901784) (xy 103.288846 -119.901208) (xy 105.651046 -119.901208) (xy 105.667705 -119.901747)
			(xy 105.69989 -119.910368) (xy 105.728754 -119.927012) (xy 105.752337 -119.95055) (xy 105.769037 -119.979382)
			(xy 105.777721 -120.01155) (xy 105.7783 -120.028208) (xy 105.7783 -121.209816) (xy 126.143009 -121.209816)
			(xy 126.147035 -121.052186) (xy 126.159106 -120.894968) (xy 126.179188 -120.738571) (xy 126.20723 -120.583403)
			(xy 126.243158 -120.42987) (xy 126.286879 -120.278371) (xy 126.338278 -120.129302) (xy 126.397222 -119.983053)
			(xy 126.463557 -119.840003) (xy 126.537109 -119.700528) (xy 126.617687 -119.56499) (xy 126.705081 -119.433743)
			(xy 126.799062 -119.30713) (xy 126.899385 -119.185481) (xy 127.00579 -119.069113) (xy 127.117997 -118.958329)
			(xy 127.235714 -118.85342) (xy 127.358635 -118.754658) (xy 127.486438 -118.662302) (xy 127.61879 -118.576591)
			(xy 127.755346 -118.497751) (xy 127.895749 -118.425986) (xy 128.039634 -118.361483) (xy 128.186624 -118.304412)
			(xy 128.336337 -118.25492) (xy 128.488382 -118.213138) (xy 128.642361 -118.179173) (xy 128.797875 -118.153115)
			(xy 128.954515 -118.135032) (xy 129.111875 -118.12497) (xy 129.269544 -118.122956) (xy 129.427109 -118.128996)
			(xy 129.584161 -118.143073) (xy 129.740288 -118.165151) (xy 129.895085 -118.195172) (xy 130.048147 -118.233058)
			(xy 130.199075 -118.27871) (xy 130.347475 -118.332009) (xy 130.49296 -118.392816) (xy 130.635151 -118.460972)
			(xy 130.773676 -118.536299) (xy 130.908174 -118.618601) (xy 131.038294 -118.707664) (xy 131.163696 -118.803254)
			(xy 131.284055 -118.905123) (xy 131.399054 -119.013004) (xy 131.508396 -119.126617) (xy 131.611793 -119.245665)
			(xy 131.708977 -119.369836) (xy 131.799694 -119.498808) (xy 131.883707 -119.632244) (xy 131.960798 -119.769796)
			(xy 132.030764 -119.911104) (xy 132.093423 -120.055801) (xy 132.148613 -120.203508) (xy 132.196189 -120.353841)
			(xy 132.236026 -120.506407) (xy 132.268022 -120.660808) (xy 132.292092 -120.816641) (xy 132.308173 -120.9735)
			(xy 132.316225 -121.130975) (xy 132.316728 -121.209816) (xy 132.316225 -121.288657) (xy 132.308173 -121.446132)
			(xy 132.292092 -121.602991) (xy 132.268022 -121.758824) (xy 132.236026 -121.913225) (xy 132.196189 -122.065791)
			(xy 132.148613 -122.216124) (xy 132.093423 -122.363831) (xy 132.030764 -122.508528) (xy 131.960798 -122.649836)
			(xy 131.883707 -122.787388) (xy 131.799694 -122.920824) (xy 131.708977 -123.049796) (xy 131.611793 -123.173967)
			(xy 131.508396 -123.293015) (xy 131.399054 -123.406628) (xy 131.284055 -123.514509) (xy 131.163696 -123.616378)
			(xy 131.038294 -123.711968) (xy 130.908174 -123.801031) (xy 130.773676 -123.883333) (xy 130.635151 -123.95866)
			(xy 130.49296 -124.026816) (xy 130.347475 -124.087623) (xy 130.199075 -124.140922) (xy 130.048147 -124.186574)
			(xy 129.895085 -124.22446) (xy 129.740288 -124.254481) (xy 129.584161 -124.276559) (xy 129.427109 -124.290636)
			(xy 129.269544 -124.296676) (xy 129.111875 -124.294662) (xy 128.954515 -124.2846) (xy 128.797875 -124.266517)
			(xy 128.642361 -124.240459) (xy 128.488382 -124.206494) (xy 128.336337 -124.164712) (xy 128.186624 -124.11522)
			(xy 128.039634 -124.058149) (xy 127.895749 -123.993646) (xy 127.755346 -123.921881) (xy 127.61879 -123.843041)
			(xy 127.486438 -123.75733) (xy 127.358635 -123.664974) (xy 127.235714 -123.566212) (xy 127.117997 -123.461303)
			(xy 127.00579 -123.350519) (xy 126.899385 -123.234151) (xy 126.799062 -123.112502) (xy 126.705081 -122.985889)
			(xy 126.617687 -122.854642) (xy 126.537109 -122.719104) (xy 126.463557 -122.579629) (xy 126.397222 -122.436579)
			(xy 126.338278 -122.29033) (xy 126.286879 -122.141261) (xy 126.243158 -121.989762) (xy 126.20723 -121.836229)
			(xy 126.179188 -121.681061) (xy 126.159106 -121.524664) (xy 126.147035 -121.367446) (xy 126.143009 -121.209816)
			(xy 105.7783 -121.209816) (xy 105.7783 -122.390916) (xy 105.777779 -122.407611) (xy 105.769144 -122.439866)
			(xy 105.752465 -122.468792) (xy 105.728876 -122.492424) (xy 105.699979 -122.509156) (xy 105.66774 -122.517849)
			(xy 105.651046 -122.518424) (xy 103.288846 -122.518424) (xy 103.272185 -122.517872) (xy 103.239993 -122.509267)
			(xy 103.211122 -122.49263) (xy 103.187535 -122.469093) (xy 103.170837 -122.440257) (xy 103.162163 -122.408084)
			(xy 103.161592 -122.391424) (xy 99.701153 -122.391424) (xy 99.655113 -122.498709) (xy 99.586231 -122.639135)
			(xy 99.510325 -122.775891) (xy 99.42759 -122.908627) (xy 99.338239 -123.037002) (xy 99.2425 -123.160686)
			(xy 99.140619 -123.279363) (xy 99.032858 -123.392728) (xy 98.919493 -123.500489) (xy 98.800816 -123.60237)
			(xy 98.677132 -123.698109) (xy 98.548757 -123.78746) (xy 98.416021 -123.870195) (xy 98.279265 -123.946101)
			(xy 98.138839 -124.014983) (xy 97.995106 -124.076664) (xy 97.848433 -124.130986) (xy 97.699196 -124.177809)
			(xy 97.54778 -124.217013) (xy 97.394572 -124.248498) (xy 97.239966 -124.272183) (xy 97.084359 -124.288007)
			(xy 96.928151 -124.295929) (xy 96.771741 -124.295929) (xy 96.615533 -124.288007) (xy 96.459926 -124.272183)
			(xy 96.30532 -124.248498) (xy 96.152112 -124.217013) (xy 96.000696 -124.177809) (xy 95.851459 -124.130986)
			(xy 95.704786 -124.076664) (xy 95.561053 -124.014983) (xy 95.420627 -123.946101) (xy 95.283871 -123.870195)
			(xy 95.151135 -123.78746) (xy 95.02276 -123.698109) (xy 94.899076 -123.60237) (xy 94.780399 -123.500489)
			(xy 94.667034 -123.392728) (xy 94.559273 -123.279363) (xy 94.457392 -123.160686) (xy 94.361653 -123.037002)
			(xy 94.272302 -122.908627) (xy 94.189567 -122.775891) (xy 94.113661 -122.639135) (xy 94.044779 -122.498709)
			(xy 93.983098 -122.354976) (xy 93.928776 -122.208303) (xy 93.881953 -122.059066) (xy 93.842749 -121.90765)
			(xy 93.811264 -121.754442) (xy 93.787579 -121.599836) (xy 93.771755 -121.444229) (xy 93.763833 -121.288021)
			(xy 93.763338 -121.209816) (xy 93.763828 -121.131569) (xy 93.771763 -120.975277) (xy 93.787608 -120.819588)
			(xy 93.811323 -120.664902) (xy 93.842846 -120.511617) (xy 93.882097 -120.360125) (xy 93.928974 -120.210818)
			(xy 93.983358 -120.064078) (xy 94.045107 -119.920283) (xy 94.114065 -119.779802) (xy 94.190054 -119.642995)
			(xy 94.272877 -119.510216) (xy 94.362323 -119.381804) (xy 94.458162 -119.25809) (xy 94.560147 -119.139392)
			(xy 94.668016 -119.026015) (xy 94.781492 -118.91825) (xy 94.840552 -118.86692) (xy 94.848572 -118.859346)
			(xy 94.857791 -118.83933) (xy 94.858332 -118.828312) (xy 94.858332 -117.90934) (xy 94.85792 -117.899311)
			(xy 94.850258 -117.880775) (xy 94.836086 -117.866582) (xy 94.81756 -117.858894) (xy 94.807532 -117.85854)
			(xy 94.8055 -117.85854) (xy 94.795489 -117.858053) (xy 94.776991 -117.850394) (xy 94.762828 -117.836243)
			(xy 94.755155 -117.81775) (xy 94.7547 -117.80774) (xy 94.7547 -117.644164) (xy 94.754144 -117.634185)
			(xy 94.746421 -117.615772) (xy 94.732297 -117.601659) (xy 94.713879 -117.593949) (xy 94.7039 -117.593364)
			(xy 94.694756 -117.593364) (xy 94.694756 -117.225064) (xy 94.69433 -117.215051) (xy 94.686652 -117.196554)
			(xy 94.672479 -117.182403) (xy 94.65397 -117.174755) (xy 94.643956 -117.174264) (xy 59.056016 -117.174264)
			(xy 59.046004 -117.174749) (xy 59.0275 -117.182404) (xy 59.013333 -117.196556) (xy 59.005659 -117.215052)
			(xy 59.005216 -117.225064) (xy 59.005216 -117.542818) (xy 59.004789 -117.552816) (xy 58.997106 -117.571278)
			(xy 58.982924 -117.585375) (xy 58.964417 -117.592948) (xy 58.954416 -117.593364) (xy 58.945272 -117.593364)
			(xy 58.945272 -117.80774) (xy 58.944777 -117.81774) (xy 58.937109 -117.836214) (xy 58.922957 -117.850347)
			(xy 58.904473 -117.85799) (xy 58.894472 -117.85854) (xy 58.89244 -117.85854) (xy 58.882416 -117.858953)
			(xy 58.863893 -117.866618) (xy 58.849718 -117.880793) (xy 58.842053 -117.899316) (xy 58.84164 -117.90934)
			(xy 58.84164 -118.828312) (xy 58.842181 -118.839331) (xy 58.851395 -118.85935) (xy 58.85942 -118.86692)
			(xy 58.9185 -118.918227) (xy 59.031981 -119.02599) (xy 59.139854 -119.139365) (xy 59.241843 -119.258063)
			(xy 59.337684 -119.381776) (xy 59.427132 -119.510189) (xy 59.509957 -119.642969) (xy 59.585945 -119.779777)
			(xy 59.654903 -119.920261) (xy 59.716651 -120.064059) (xy 59.771032 -120.210801) (xy 59.817905 -120.360112)
			(xy 59.857151 -120.511606) (xy 59.888668 -120.664894) (xy 59.912376 -120.819583) (xy 59.928213 -120.975274)
			(xy 59.936139 -121.131569) (xy 59.936634 -121.209816) (xy 59.936139 -121.288021) (xy 59.928217 -121.444229)
			(xy 59.912393 -121.599836) (xy 59.888708 -121.754442) (xy 59.857223 -121.90765) (xy 59.818019 -122.059066)
			(xy 59.771196 -122.208303) (xy 59.716874 -122.354976) (xy 59.701233 -122.391424) (xy 63.161672 -122.391424)
			(xy 63.161672 -120.028716) (xy 63.162248 -120.012024) (xy 63.170873 -119.979775) (xy 63.187542 -119.950851)
			(xy 63.21112 -119.927219) (xy 63.240006 -119.910485) (xy 63.272236 -119.901786) (xy 63.288926 -119.901208)
			(xy 65.651126 -119.901208) (xy 65.667785 -119.901764) (xy 65.699969 -119.910381) (xy 65.728833 -119.927021)
			(xy 65.752416 -119.950555) (xy 65.769117 -119.979385) (xy 65.777801 -120.011551) (xy 65.77838 -120.028208)
			(xy 65.77838 -121.209816) (xy 86.142835 -121.209816) (xy 86.146861 -121.052186) (xy 86.158932 -120.894968)
			(xy 86.179014 -120.738571) (xy 86.207056 -120.583403) (xy 86.242984 -120.42987) (xy 86.286705 -120.278371)
			(xy 86.338104 -120.129302) (xy 86.397048 -119.983053) (xy 86.463383 -119.840003) (xy 86.536935 -119.700528)
			(xy 86.617513 -119.56499) (xy 86.704907 -119.433743) (xy 86.798888 -119.30713) (xy 86.899211 -119.185481)
			(xy 87.005616 -119.069113) (xy 87.117823 -118.958329) (xy 87.23554 -118.85342) (xy 87.358461 -118.754658)
			(xy 87.486264 -118.662302) (xy 87.618616 -118.576591) (xy 87.755172 -118.497751) (xy 87.895575 -118.425986)
			(xy 88.03946 -118.361483) (xy 88.18645 -118.304412) (xy 88.336163 -118.25492) (xy 88.488208 -118.213138)
			(xy 88.642187 -118.179173) (xy 88.797701 -118.153115) (xy 88.954341 -118.135032) (xy 89.111701 -118.12497)
			(xy 89.26937 -118.122956) (xy 89.426935 -118.128996) (xy 89.583987 -118.143073) (xy 89.740114 -118.165151)
			(xy 89.894911 -118.195172) (xy 90.047973 -118.233058) (xy 90.198901 -118.27871) (xy 90.347301 -118.332009)
			(xy 90.492786 -118.392816) (xy 90.634977 -118.460972) (xy 90.773502 -118.536299) (xy 90.908 -118.618601)
			(xy 91.03812 -118.707664) (xy 91.163522 -118.803254) (xy 91.283881 -118.905123) (xy 91.39888 -119.013004)
			(xy 91.508222 -119.126617) (xy 91.611619 -119.245665) (xy 91.708803 -119.369836) (xy 91.79952 -119.498808)
			(xy 91.883533 -119.632244) (xy 91.960624 -119.769796) (xy 92.03059 -119.911104) (xy 92.093249 -120.055801)
			(xy 92.148439 -120.203508) (xy 92.196015 -120.353841) (xy 92.235852 -120.506407) (xy 92.267848 -120.660808)
			(xy 92.291918 -120.816641) (xy 92.307999 -120.9735) (xy 92.316051 -121.130975) (xy 92.316554 -121.209816)
			(xy 92.316051 -121.288657) (xy 92.307999 -121.446132) (xy 92.291918 -121.602991) (xy 92.267848 -121.758824)
			(xy 92.235852 -121.913225) (xy 92.196015 -122.065791) (xy 92.148439 -122.216124) (xy 92.093249 -122.363831)
			(xy 92.03059 -122.508528) (xy 91.960624 -122.649836) (xy 91.883533 -122.787388) (xy 91.79952 -122.920824)
			(xy 91.708803 -123.049796) (xy 91.611619 -123.173967) (xy 91.508222 -123.293015) (xy 91.39888 -123.406628)
			(xy 91.283881 -123.514509) (xy 91.163522 -123.616378) (xy 91.03812 -123.711968) (xy 90.908 -123.801031)
			(xy 90.773502 -123.883333) (xy 90.634977 -123.95866) (xy 90.492786 -124.026816) (xy 90.347301 -124.087623)
			(xy 90.198901 -124.140922) (xy 90.047973 -124.186574) (xy 89.894911 -124.22446) (xy 89.740114 -124.254481)
			(xy 89.583987 -124.276559) (xy 89.426935 -124.290636) (xy 89.26937 -124.296676) (xy 89.111701 -124.294662)
			(xy 88.954341 -124.2846) (xy 88.797701 -124.266517) (xy 88.642187 -124.240459) (xy 88.488208 -124.206494)
			(xy 88.336163 -124.164712) (xy 88.18645 -124.11522) (xy 88.03946 -124.058149) (xy 87.895575 -123.993646)
			(xy 87.755172 -123.921881) (xy 87.618616 -123.843041) (xy 87.486264 -123.75733) (xy 87.358461 -123.664974)
			(xy 87.23554 -123.566212) (xy 87.117823 -123.461303) (xy 87.005616 -123.350519) (xy 86.899211 -123.234151)
			(xy 86.798888 -123.112502) (xy 86.704907 -122.985889) (xy 86.617513 -122.854642) (xy 86.536935 -122.719104)
			(xy 86.463383 -122.579629) (xy 86.397048 -122.436579) (xy 86.338104 -122.29033) (xy 86.286705 -122.141261)
			(xy 86.242984 -121.989762) (xy 86.207056 -121.836229) (xy 86.179014 -121.681061) (xy 86.158932 -121.524664)
			(xy 86.146861 -121.367446) (xy 86.142835 -121.209816) (xy 65.77838 -121.209816) (xy 65.77838 -122.390916)
			(xy 65.777879 -122.407613) (xy 65.769242 -122.439871) (xy 65.75256 -122.468799) (xy 65.728966 -122.492432)
			(xy 65.700065 -122.509161) (xy 65.667822 -122.517851) (xy 65.651126 -122.518424) (xy 63.288926 -122.518424)
			(xy 63.272264 -122.51789) (xy 63.240072 -122.50928) (xy 63.211201 -122.492639) (xy 63.187614 -122.469099)
			(xy 63.170916 -122.44026) (xy 63.162243 -122.408085) (xy 63.161672 -122.391424) (xy 59.701233 -122.391424)
			(xy 59.655193 -122.498709) (xy 59.586311 -122.639135) (xy 59.510405 -122.775891) (xy 59.42767 -122.908627)
			(xy 59.338319 -123.037002) (xy 59.24258 -123.160686) (xy 59.140699 -123.279363) (xy 59.032938 -123.392728)
			(xy 58.919573 -123.500489) (xy 58.800896 -123.60237) (xy 58.677212 -123.698109) (xy 58.548837 -123.78746)
			(xy 58.416101 -123.870195) (xy 58.279345 -123.946101) (xy 58.138919 -124.014983) (xy 57.995186 -124.076664)
			(xy 57.848513 -124.130986) (xy 57.699276 -124.177809) (xy 57.54786 -124.217013) (xy 57.394652 -124.248498)
			(xy 57.240046 -124.272183) (xy 57.084439 -124.288007) (xy 56.928231 -124.295929) (xy 56.771821 -124.295929)
			(xy 56.615613 -124.288007) (xy 56.460006 -124.272183) (xy 56.3054 -124.248498) (xy 56.152192 -124.217013)
			(xy 56.000776 -124.177809) (xy 55.851539 -124.130986) (xy 55.704866 -124.076664) (xy 55.561133 -124.014983)
			(xy 55.420707 -123.946101) (xy 55.283951 -123.870195) (xy 55.151215 -123.78746) (xy 55.02284 -123.698109)
			(xy 54.899156 -123.60237) (xy 54.780479 -123.500489) (xy 54.667114 -123.392728) (xy 54.559353 -123.279363)
			(xy 54.457472 -123.160686) (xy 54.361733 -123.037002) (xy 54.272382 -122.908627) (xy 54.189647 -122.775891)
			(xy 54.113741 -122.639135) (xy 54.044859 -122.498709) (xy 53.983178 -122.354976) (xy 53.928856 -122.208303)
			(xy 53.882033 -122.059066) (xy 53.842829 -121.90765) (xy 53.811344 -121.754442) (xy 53.787659 -121.599836)
			(xy 53.771835 -121.444229) (xy 53.763913 -121.288021) (xy 53.763418 -121.209816) (xy 53.763908 -121.131569)
			(xy 53.771843 -120.975277) (xy 53.787688 -120.819588) (xy 53.811403 -120.664902) (xy 53.842926 -120.511616)
			(xy 53.882176 -120.360125) (xy 53.929053 -120.210817) (xy 53.983436 -120.064077) (xy 54.045186 -119.920281)
			(xy 54.114144 -119.7798) (xy 54.190132 -119.642993) (xy 54.272955 -119.510213) (xy 54.3624 -119.381801)
			(xy 54.458239 -119.258087) (xy 54.560223 -119.139388) (xy 54.668092 -119.02601) (xy 54.781568 -118.918245)
			(xy 54.840632 -118.86692) (xy 54.848655 -118.859347) (xy 54.857877 -118.839331) (xy 54.858412 -118.828312)
			(xy 54.858412 -117.90934) (xy 54.857999 -117.899313) (xy 54.850337 -117.88078) (xy 54.836164 -117.866592)
			(xy 54.817639 -117.858911) (xy 54.807612 -117.85854) (xy 54.80558 -117.85854) (xy 54.795572 -117.858049)
			(xy 54.77708 -117.850387) (xy 54.762924 -117.836237) (xy 54.755255 -117.817748) (xy 54.75478 -117.80774)
			(xy 54.75478 -117.644164) (xy 54.754225 -117.634179) (xy 54.746505 -117.615753) (xy 54.732385 -117.60162)
			(xy 54.713965 -117.593884) (xy 54.70398 -117.593364) (xy 54.694836 -117.593364) (xy 54.694836 -117.225064)
			(xy 54.694342 -117.215058) (xy 54.686678 -117.196573) (xy 54.672527 -117.182422) (xy 54.654042 -117.174758)
			(xy 54.644036 -117.174264) (xy 38.082474 -117.174264) (xy 38.063678 -117.181884) (xy 38.056566 -117.18925)
			(xy 37.546788 -117.698774) (xy 37.539422 -117.705886) (xy 37.531802 -117.724682) (xy 37.531802 -121.209816)
			(xy 46.142915 -121.209816) (xy 46.146941 -121.052186) (xy 46.159012 -120.894968) (xy 46.179094 -120.738571)
			(xy 46.207136 -120.583403) (xy 46.243064 -120.42987) (xy 46.286785 -120.278371) (xy 46.338184 -120.129302)
			(xy 46.397128 -119.983053) (xy 46.463463 -119.840003) (xy 46.537015 -119.700528) (xy 46.617593 -119.56499)
			(xy 46.704987 -119.433743) (xy 46.798968 -119.30713) (xy 46.899291 -119.185481) (xy 47.005696 -119.069113)
			(xy 47.117903 -118.958329) (xy 47.23562 -118.85342) (xy 47.358541 -118.754658) (xy 47.486344 -118.662302)
			(xy 47.618696 -118.576591) (xy 47.755252 -118.497751) (xy 47.895655 -118.425986) (xy 48.03954 -118.361483)
			(xy 48.18653 -118.304412) (xy 48.336243 -118.25492) (xy 48.488288 -118.213138) (xy 48.642267 -118.179173)
			(xy 48.797781 -118.153115) (xy 48.954421 -118.135032) (xy 49.111781 -118.12497) (xy 49.26945 -118.122956)
			(xy 49.427015 -118.128996) (xy 49.584067 -118.143073) (xy 49.740194 -118.165151) (xy 49.894991 -118.195172)
			(xy 50.048053 -118.233058) (xy 50.198981 -118.27871) (xy 50.347381 -118.332009) (xy 50.492866 -118.392816)
			(xy 50.635057 -118.460972) (xy 50.773582 -118.536299) (xy 50.90808 -118.618601) (xy 51.0382 -118.707664)
			(xy 51.163602 -118.803254) (xy 51.283961 -118.905123) (xy 51.39896 -119.013004) (xy 51.508302 -119.126617)
			(xy 51.611699 -119.245665) (xy 51.708883 -119.369836) (xy 51.7996 -119.498808) (xy 51.883613 -119.632244)
			(xy 51.960704 -119.769796) (xy 52.03067 -119.911104) (xy 52.093329 -120.055801) (xy 52.148519 -120.203508)
			(xy 52.196095 -120.353841) (xy 52.235932 -120.506407) (xy 52.267928 -120.660808) (xy 52.291998 -120.816641)
			(xy 52.308079 -120.9735) (xy 52.316131 -121.130975) (xy 52.316634 -121.209816) (xy 52.316131 -121.288657)
			(xy 52.308079 -121.446132) (xy 52.291998 -121.602991) (xy 52.267928 -121.758824) (xy 52.235932 -121.913225)
			(xy 52.196095 -122.065791) (xy 52.148519 -122.216124) (xy 52.093329 -122.363831) (xy 52.03067 -122.508528)
			(xy 51.960704 -122.649836) (xy 51.883613 -122.787388) (xy 51.7996 -122.920824) (xy 51.708883 -123.049796)
			(xy 51.611699 -123.173967) (xy 51.508302 -123.293015) (xy 51.39896 -123.406628) (xy 51.283961 -123.514509)
			(xy 51.163602 -123.616378) (xy 51.0382 -123.711968) (xy 50.90808 -123.801031) (xy 50.773582 -123.883333)
			(xy 50.635057 -123.95866) (xy 50.492866 -124.026816) (xy 50.347381 -124.087623) (xy 50.198981 -124.140922)
			(xy 50.048053 -124.186574) (xy 49.894991 -124.22446) (xy 49.740194 -124.254481) (xy 49.584067 -124.276559)
			(xy 49.427015 -124.290636) (xy 49.26945 -124.296676) (xy 49.111781 -124.294662) (xy 48.954421 -124.2846)
			(xy 48.797781 -124.266517) (xy 48.642267 -124.240459) (xy 48.488288 -124.206494) (xy 48.336243 -124.164712)
			(xy 48.18653 -124.11522) (xy 48.03954 -124.058149) (xy 47.895655 -123.993646) (xy 47.755252 -123.921881)
			(xy 47.618696 -123.843041) (xy 47.486344 -123.75733) (xy 47.358541 -123.664974) (xy 47.23562 -123.566212)
			(xy 47.117903 -123.461303) (xy 47.005696 -123.350519) (xy 46.899291 -123.234151) (xy 46.798968 -123.112502)
			(xy 46.704987 -122.985889) (xy 46.617593 -122.854642) (xy 46.537015 -122.719104) (xy 46.463463 -122.579629)
			(xy 46.397128 -122.436579) (xy 46.338184 -122.29033) (xy 46.286785 -122.141261) (xy 46.243064 -121.989762)
			(xy 46.207136 -121.836229) (xy 46.179094 -121.681061) (xy 46.159012 -121.524664) (xy 46.146941 -121.367446)
			(xy 46.142915 -121.209816) (xy 37.531802 -121.209816) (xy 37.531802 -126.557239) (xy 43.697875 -126.557239)
			(xy 43.697875 -126.426761) (xy 43.705753 -126.296521) (xy 43.72148 -126.166995) (xy 43.745 -126.038654)
			(xy 43.776225 -125.911967) (xy 43.815043 -125.787397) (xy 43.861311 -125.665398) (xy 43.914861 -125.546416)
			(xy 43.975497 -125.430883) (xy 44.042998 -125.319223) (xy 44.117119 -125.211841) (xy 44.197587 -125.109132)
			(xy 44.28411 -125.011467) (xy 44.376372 -124.919206) (xy 44.474036 -124.832683) (xy 44.576746 -124.752215)
			(xy 44.684128 -124.678095) (xy 44.795788 -124.610594) (xy 44.911321 -124.549958) (xy 45.030304 -124.496409)
			(xy 45.152303 -124.450141) (xy 45.276873 -124.411324) (xy 45.40356 -124.380099) (xy 45.5319 -124.35658)
			(xy 45.661427 -124.340852) (xy 45.791667 -124.332975) (xy 45.856906 -124.332492) (xy 45.858938 -124.332492)
			(xy 45.896626 -124.332677) (xy 45.971954 -124.335344) (xy 46.00956 -124.337826) (xy 46.013848 -124.338076)
			(xy 46.022403 -124.337311) (xy 46.026578 -124.336302) (xy 46.099006 -124.317033) (xy 46.24587 -124.287069)
			(xy 46.394411 -124.267004) (xy 46.543961 -124.256929) (xy 46.618906 -124.256292) (xy 46.685172 -124.256783)
			(xy 46.817471 -124.264635) (xy 46.949072 -124.28031) (xy 47.079514 -124.303754) (xy 47.208338 -124.334884)
			(xy 47.335092 -124.373591) (xy 47.459329 -124.419739) (xy 47.580615 -124.473166) (xy 47.698523 -124.533684)
			(xy 47.812639 -124.601081) (xy 47.922561 -124.67512) (xy 48.027904 -124.75554) (xy 48.128299 -124.84206)
			(xy 48.223391 -124.934375) (xy 48.312848 -125.032162) (xy 48.396354 -125.135076) (xy 48.473617 -125.242757)
			(xy 48.544366 -125.354825) (xy 48.608351 -125.470888) (xy 48.665348 -125.590537) (xy 48.715157 -125.713353)
			(xy 48.757603 -125.838904) (xy 48.792537 -125.966749) (xy 48.819836 -126.096439) (xy 48.839403 -126.227518)
			(xy 48.851172 -126.359526) (xy 48.855099 -126.492) (xy 48.853165 -126.557239) (xy 55.889875 -126.557239)
			(xy 55.889875 -126.426761) (xy 55.897753 -126.296521) (xy 55.91348 -126.166995) (xy 55.937 -126.038654)
			(xy 55.968225 -125.911967) (xy 56.007043 -125.787397) (xy 56.053311 -125.665398) (xy 56.106861 -125.546416)
			(xy 56.167497 -125.430883) (xy 56.234998 -125.319223) (xy 56.309119 -125.211841) (xy 56.389587 -125.109132)
			(xy 56.47611 -125.011467) (xy 56.568372 -124.919206) (xy 56.666036 -124.832683) (xy 56.768746 -124.752215)
			(xy 56.876128 -124.678095) (xy 56.987788 -124.610594) (xy 57.103321 -124.549958) (xy 57.222304 -124.496409)
			(xy 57.344303 -124.450141) (xy 57.468873 -124.411324) (xy 57.59556 -124.380099) (xy 57.7239 -124.35658)
			(xy 57.853427 -124.340852) (xy 57.983667 -124.332975) (xy 58.048906 -124.332492) (xy 58.050938 -124.332492)
			(xy 58.088626 -124.332677) (xy 58.163954 -124.335344) (xy 58.20156 -124.337826) (xy 58.205848 -124.338076)
			(xy 58.214403 -124.337311) (xy 58.218578 -124.336302) (xy 58.291006 -124.317033) (xy 58.43787 -124.287069)
			(xy 58.586411 -124.267004) (xy 58.735961 -124.256929) (xy 58.810906 -124.256292) (xy 58.877172 -124.256783)
			(xy 59.009471 -124.264635) (xy 59.141072 -124.28031) (xy 59.271514 -124.303754) (xy 59.400338 -124.334884)
			(xy 59.527092 -124.373591) (xy 59.651329 -124.419739) (xy 59.772615 -124.473166) (xy 59.890523 -124.533684)
			(xy 60.004639 -124.601081) (xy 60.114561 -124.67512) (xy 60.219904 -124.75554) (xy 60.320299 -124.84206)
			(xy 60.415391 -124.934375) (xy 60.504848 -125.032162) (xy 60.588354 -125.135076) (xy 60.665617 -125.242757)
			(xy 60.736366 -125.354825) (xy 60.800351 -125.470888) (xy 60.857348 -125.590537) (xy 60.907157 -125.713353)
			(xy 60.949603 -125.838904) (xy 60.984537 -125.966749) (xy 61.011836 -126.096439) (xy 61.031403 -126.227518)
			(xy 61.043172 -126.359526) (xy 61.047099 -126.492) (xy 61.045165 -126.557239) (xy 68.081875 -126.557239)
			(xy 68.081875 -126.426761) (xy 68.089753 -126.296521) (xy 68.10548 -126.166995) (xy 68.129 -126.038654)
			(xy 68.160225 -125.911967) (xy 68.199043 -125.787397) (xy 68.245311 -125.665398) (xy 68.298861 -125.546416)
			(xy 68.359497 -125.430883) (xy 68.426998 -125.319223) (xy 68.501119 -125.211841) (xy 68.581587 -125.109132)
			(xy 68.66811 -125.011467) (xy 68.760372 -124.919206) (xy 68.858036 -124.832683) (xy 68.960746 -124.752215)
			(xy 69.068128 -124.678095) (xy 69.179788 -124.610594) (xy 69.295321 -124.549958) (xy 69.414304 -124.496409)
			(xy 69.536303 -124.450141) (xy 69.660873 -124.411324) (xy 69.78756 -124.380099) (xy 69.9159 -124.35658)
			(xy 70.045427 -124.340852) (xy 70.175667 -124.332975) (xy 70.240906 -124.332492) (xy 70.242938 -124.332492)
			(xy 70.280626 -124.332677) (xy 70.355954 -124.335344) (xy 70.39356 -124.337826) (xy 70.397848 -124.338076)
			(xy 70.406403 -124.337311) (xy 70.410578 -124.336302) (xy 70.483006 -124.317033) (xy 70.62987 -124.287069)
			(xy 70.778411 -124.267004) (xy 70.927961 -124.256929) (xy 71.002906 -124.256292) (xy 71.069172 -124.256783)
			(xy 71.201471 -124.264635) (xy 71.333072 -124.28031) (xy 71.463514 -124.303754) (xy 71.592338 -124.334884)
			(xy 71.719092 -124.373591) (xy 71.843329 -124.419739) (xy 71.964615 -124.473166) (xy 72.082523 -124.533684)
			(xy 72.196639 -124.601081) (xy 72.306561 -124.67512) (xy 72.411904 -124.75554) (xy 72.512299 -124.84206)
			(xy 72.607391 -124.934375) (xy 72.696848 -125.032162) (xy 72.780354 -125.135076) (xy 72.857617 -125.242757)
			(xy 72.928366 -125.354825) (xy 72.992351 -125.470888) (xy 73.049348 -125.590537) (xy 73.099157 -125.713353)
			(xy 73.141603 -125.838904) (xy 73.176537 -125.966749) (xy 73.203836 -126.096439) (xy 73.223403 -126.227518)
			(xy 73.235172 -126.359526) (xy 73.239099 -126.492) (xy 73.237165 -126.557239) (xy 83.697775 -126.557239)
			(xy 83.697775 -126.426761) (xy 83.705653 -126.29652) (xy 83.721381 -126.166993) (xy 83.7449 -126.038651)
			(xy 83.776126 -125.911964) (xy 83.814944 -125.787393) (xy 83.861213 -125.665394) (xy 83.914764 -125.54641)
			(xy 83.9754 -125.430877) (xy 84.042902 -125.319217) (xy 84.117023 -125.211835) (xy 84.197493 -125.109125)
			(xy 84.284016 -125.01146) (xy 84.376279 -124.919199) (xy 84.473945 -124.832676) (xy 84.576656 -124.752208)
			(xy 84.684038 -124.678088) (xy 84.7957 -124.610588) (xy 84.911234 -124.549952) (xy 85.030218 -124.496403)
			(xy 85.152218 -124.450136) (xy 85.276789 -124.411319) (xy 85.403477 -124.380095) (xy 85.531818 -124.356577)
			(xy 85.661346 -124.340851) (xy 85.791587 -124.332974) (xy 85.856826 -124.332492) (xy 85.858858 -124.332492)
			(xy 85.896546 -124.332676) (xy 85.971874 -124.335344) (xy 86.00948 -124.337826) (xy 86.013768 -124.338081)
			(xy 86.022323 -124.337313) (xy 86.026498 -124.336302) (xy 86.098925 -124.317029) (xy 86.245789 -124.287065)
			(xy 86.39433 -124.267002) (xy 86.543881 -124.256928) (xy 86.618826 -124.256292) (xy 86.685092 -124.256784)
			(xy 86.81739 -124.264637) (xy 86.94899 -124.280313) (xy 87.079431 -124.303758) (xy 87.208254 -124.334889)
			(xy 87.335007 -124.373596) (xy 87.459243 -124.419745) (xy 87.580528 -124.473172) (xy 87.698435 -124.533691)
			(xy 87.812549 -124.601088) (xy 87.922471 -124.675127) (xy 88.027813 -124.755547) (xy 88.128206 -124.842067)
			(xy 88.223298 -124.934382) (xy 88.312754 -125.032169) (xy 88.396259 -125.135083) (xy 88.473522 -125.242763)
			(xy 88.544269 -125.354831) (xy 88.608254 -125.470893) (xy 88.66525 -125.590542) (xy 88.715059 -125.713357)
			(xy 88.757504 -125.838908) (xy 88.792438 -125.966752) (xy 88.819736 -126.096441) (xy 88.839304 -126.22752)
			(xy 88.851072 -126.359527) (xy 88.854999 -126.492) (xy 88.853065 -126.557239) (xy 95.889775 -126.557239)
			(xy 95.889775 -126.426761) (xy 95.897653 -126.29652) (xy 95.913381 -126.166993) (xy 95.9369 -126.038651)
			(xy 95.968126 -125.911964) (xy 96.006944 -125.787393) (xy 96.053213 -125.665394) (xy 96.106764 -125.54641)
			(xy 96.1674 -125.430877) (xy 96.234902 -125.319217) (xy 96.309023 -125.211835) (xy 96.389493 -125.109125)
			(xy 96.476016 -125.01146) (xy 96.568279 -124.919199) (xy 96.665945 -124.832676) (xy 96.768656 -124.752208)
			(xy 96.876038 -124.678088) (xy 96.9877 -124.610588) (xy 97.103234 -124.549952) (xy 97.222218 -124.496403)
			(xy 97.344218 -124.450136) (xy 97.468789 -124.411319) (xy 97.595477 -124.380095) (xy 97.723818 -124.356577)
			(xy 97.853346 -124.340851) (xy 97.983587 -124.332974) (xy 98.048826 -124.332492) (xy 98.050858 -124.332492)
			(xy 98.088546 -124.332676) (xy 98.163874 -124.335344) (xy 98.20148 -124.337826) (xy 98.205768 -124.338081)
			(xy 98.214323 -124.337313) (xy 98.218498 -124.336302) (xy 98.290925 -124.317029) (xy 98.437789 -124.287065)
			(xy 98.58633 -124.267002) (xy 98.735881 -124.256928) (xy 98.810826 -124.256292) (xy 98.877092 -124.256784)
			(xy 99.00939 -124.264637) (xy 99.14099 -124.280313) (xy 99.271431 -124.303758) (xy 99.400254 -124.334889)
			(xy 99.527007 -124.373596) (xy 99.651243 -124.419745) (xy 99.772528 -124.473172) (xy 99.890435 -124.533691)
			(xy 100.004549 -124.601088) (xy 100.114471 -124.675127) (xy 100.219813 -124.755547) (xy 100.320206 -124.842067)
			(xy 100.415298 -124.934382) (xy 100.504754 -125.032169) (xy 100.588259 -125.135083) (xy 100.665522 -125.242763)
			(xy 100.736269 -125.354831) (xy 100.800254 -125.470893) (xy 100.85725 -125.590542) (xy 100.907059 -125.713357)
			(xy 100.949504 -125.838908) (xy 100.984438 -125.966752) (xy 101.011736 -126.096441) (xy 101.031304 -126.22752)
			(xy 101.043072 -126.359527) (xy 101.046999 -126.492) (xy 101.045065 -126.557239) (xy 108.081775 -126.557239)
			(xy 108.081775 -126.426761) (xy 108.089653 -126.29652) (xy 108.105381 -126.166993) (xy 108.1289 -126.038651)
			(xy 108.160126 -125.911964) (xy 108.198944 -125.787393) (xy 108.245213 -125.665394) (xy 108.298764 -125.54641)
			(xy 108.3594 -125.430877) (xy 108.426902 -125.319217) (xy 108.501023 -125.211835) (xy 108.581493 -125.109125)
			(xy 108.668016 -125.01146) (xy 108.760279 -124.919199) (xy 108.857945 -124.832676) (xy 108.960656 -124.752208)
			(xy 109.068038 -124.678088) (xy 109.1797 -124.610588) (xy 109.295234 -124.549952) (xy 109.414218 -124.496403)
			(xy 109.536218 -124.450136) (xy 109.660789 -124.411319) (xy 109.787477 -124.380095) (xy 109.915818 -124.356577)
			(xy 110.045346 -124.340851) (xy 110.175587 -124.332974) (xy 110.240826 -124.332492) (xy 110.242858 -124.332492)
			(xy 110.280546 -124.332676) (xy 110.355874 -124.335344) (xy 110.39348 -124.337826) (xy 110.397768 -124.338081)
			(xy 110.406323 -124.337313) (xy 110.410498 -124.336302) (xy 110.482925 -124.317029) (xy 110.629789 -124.287065)
			(xy 110.77833 -124.267002) (xy 110.927881 -124.256928) (xy 111.002826 -124.256292) (xy 111.069092 -124.256784)
			(xy 111.20139 -124.264637) (xy 111.33299 -124.280313) (xy 111.463431 -124.303758) (xy 111.592254 -124.334889)
			(xy 111.719007 -124.373596) (xy 111.843243 -124.419745) (xy 111.964528 -124.473172) (xy 112.082435 -124.533691)
			(xy 112.196549 -124.601088) (xy 112.306471 -124.675127) (xy 112.411813 -124.755547) (xy 112.512206 -124.842067)
			(xy 112.607298 -124.934382) (xy 112.696754 -125.032169) (xy 112.780259 -125.135083) (xy 112.857522 -125.242763)
			(xy 112.928269 -125.354831) (xy 112.992254 -125.470893) (xy 113.04925 -125.590542) (xy 113.099059 -125.713357)
			(xy 113.141504 -125.838908) (xy 113.176438 -125.966752) (xy 113.203736 -126.096441) (xy 113.223304 -126.22752)
			(xy 113.235072 -126.359527) (xy 113.238999 -126.492) (xy 113.237065 -126.557239) (xy 123.697984 -126.557239)
			(xy 123.697984 -126.426761) (xy 123.705862 -126.296522) (xy 123.72159 -126.166997) (xy 123.745109 -126.038657)
			(xy 123.776334 -125.911971) (xy 123.815151 -125.787402) (xy 123.861419 -125.665403) (xy 123.914969 -125.546421)
			(xy 123.975605 -125.43089) (xy 124.043105 -125.31923) (xy 124.117225 -125.211849) (xy 124.197692 -125.10914)
			(xy 124.284215 -125.011476) (xy 124.376476 -124.919215) (xy 124.47414 -124.832692) (xy 124.576849 -124.752225)
			(xy 124.68423 -124.678105) (xy 124.79589 -124.610605) (xy 124.911421 -124.549969) (xy 125.030403 -124.496419)
			(xy 125.152402 -124.450151) (xy 125.276971 -124.411334) (xy 125.403657 -124.380109) (xy 125.531997 -124.35659)
			(xy 125.661522 -124.340862) (xy 125.791761 -124.332984) (xy 125.857 -124.332492) (xy 125.859032 -124.332492)
			(xy 125.89672 -124.332677) (xy 125.972048 -124.335344) (xy 126.009654 -124.337826) (xy 126.013942 -124.338075)
			(xy 126.022497 -124.337311) (xy 126.026672 -124.336302) (xy 126.0991 -124.317035) (xy 126.245964 -124.28707)
			(xy 126.394505 -124.267004) (xy 126.544055 -124.256929) (xy 126.619 -124.256292) (xy 126.685266 -124.256783)
			(xy 126.817565 -124.264634) (xy 126.949167 -124.280309) (xy 127.079609 -124.303753) (xy 127.208433 -124.334883)
			(xy 127.335187 -124.37359) (xy 127.459425 -124.419738) (xy 127.580711 -124.473164) (xy 127.698619 -124.533682)
			(xy 127.812735 -124.601079) (xy 127.922658 -124.675118) (xy 128.028002 -124.755538) (xy 128.128396 -124.842058)
			(xy 128.223489 -124.934373) (xy 128.312946 -125.03216) (xy 128.396453 -125.135074) (xy 128.473716 -125.242755)
			(xy 128.544465 -125.354823) (xy 128.60845 -125.470886) (xy 128.665448 -125.590536) (xy 128.715257 -125.713352)
			(xy 128.757703 -125.838903) (xy 128.792637 -125.966748) (xy 128.819935 -126.096438) (xy 128.839503 -126.227518)
			(xy 128.851272 -126.359526) (xy 128.855199 -126.492) (xy 128.853265 -126.557239) (xy 135.889984 -126.557239)
			(xy 135.889984 -126.426761) (xy 135.897862 -126.296522) (xy 135.91359 -126.166997) (xy 135.937109 -126.038657)
			(xy 135.968334 -125.911971) (xy 136.007151 -125.787402) (xy 136.053419 -125.665403) (xy 136.106969 -125.546421)
			(xy 136.167605 -125.43089) (xy 136.235105 -125.31923) (xy 136.309225 -125.211849) (xy 136.389692 -125.10914)
			(xy 136.476215 -125.011476) (xy 136.568476 -124.919215) (xy 136.66614 -124.832692) (xy 136.768849 -124.752225)
			(xy 136.87623 -124.678105) (xy 136.98789 -124.610605) (xy 137.103421 -124.549969) (xy 137.222403 -124.496419)
			(xy 137.344402 -124.450151) (xy 137.468971 -124.411334) (xy 137.595657 -124.380109) (xy 137.723997 -124.35659)
			(xy 137.853522 -124.340862) (xy 137.983761 -124.332984) (xy 138.049 -124.332492) (xy 138.051032 -124.332492)
			(xy 138.08872 -124.332677) (xy 138.164048 -124.335344) (xy 138.201654 -124.337826) (xy 138.205942 -124.338075)
			(xy 138.214497 -124.337311) (xy 138.218672 -124.336302) (xy 138.2911 -124.317035) (xy 138.437964 -124.28707)
			(xy 138.586505 -124.267004) (xy 138.736055 -124.256929) (xy 138.811 -124.256292) (xy 138.877266 -124.256783)
			(xy 139.009565 -124.264634) (xy 139.141167 -124.280309) (xy 139.271609 -124.303753) (xy 139.400433 -124.334883)
			(xy 139.527187 -124.37359) (xy 139.651425 -124.419738) (xy 139.772711 -124.473164) (xy 139.890619 -124.533682)
			(xy 140.004735 -124.601079) (xy 140.114658 -124.675118) (xy 140.220002 -124.755538) (xy 140.320396 -124.842058)
			(xy 140.415489 -124.934373) (xy 140.504946 -125.03216) (xy 140.588453 -125.135074) (xy 140.665716 -125.242755)
			(xy 140.736465 -125.354823) (xy 140.80045 -125.470886) (xy 140.857448 -125.590536) (xy 140.907257 -125.713352)
			(xy 140.949703 -125.838903) (xy 140.984637 -125.966748) (xy 141.011935 -126.096438) (xy 141.031503 -126.227518)
			(xy 141.043272 -126.359526) (xy 141.047199 -126.492) (xy 141.045265 -126.557239) (xy 148.081984 -126.557239)
			(xy 148.081984 -126.426761) (xy 148.089862 -126.296522) (xy 148.10559 -126.166997) (xy 148.129109 -126.038657)
			(xy 148.160334 -125.911971) (xy 148.199151 -125.787402) (xy 148.245419 -125.665403) (xy 148.298969 -125.546421)
			(xy 148.359605 -125.43089) (xy 148.427105 -125.31923) (xy 148.501225 -125.211849) (xy 148.581692 -125.10914)
			(xy 148.668215 -125.011476) (xy 148.760476 -124.919215) (xy 148.85814 -124.832692) (xy 148.960849 -124.752225)
			(xy 149.06823 -124.678105) (xy 149.17989 -124.610605) (xy 149.295421 -124.549969) (xy 149.414403 -124.496419)
			(xy 149.536402 -124.450151) (xy 149.660971 -124.411334) (xy 149.787657 -124.380109) (xy 149.915997 -124.35659)
			(xy 150.045522 -124.340862) (xy 150.175761 -124.332984) (xy 150.241 -124.332492) (xy 150.243032 -124.332492)
			(xy 150.28072 -124.332677) (xy 150.356048 -124.335344) (xy 150.393654 -124.337826) (xy 150.397942 -124.338075)
			(xy 150.406497 -124.337311) (xy 150.410672 -124.336302) (xy 150.4831 -124.317035) (xy 150.629964 -124.28707)
			(xy 150.778505 -124.267004) (xy 150.928055 -124.256929) (xy 151.003 -124.256292) (xy 151.069266 -124.256783)
			(xy 151.201565 -124.264634) (xy 151.333167 -124.280309) (xy 151.463609 -124.303753) (xy 151.592433 -124.334883)
			(xy 151.719187 -124.37359) (xy 151.843425 -124.419738) (xy 151.964711 -124.473164) (xy 152.082619 -124.533682)
			(xy 152.196735 -124.601079) (xy 152.306658 -124.675118) (xy 152.412002 -124.755538) (xy 152.512396 -124.842058)
			(xy 152.607489 -124.934373) (xy 152.696946 -125.03216) (xy 152.780453 -125.135074) (xy 152.857716 -125.242755)
			(xy 152.928465 -125.354823) (xy 152.99245 -125.470886) (xy 153.049448 -125.590536) (xy 153.099257 -125.713352)
			(xy 153.141703 -125.838903) (xy 153.176637 -125.966748) (xy 153.203935 -126.096438) (xy 153.223503 -126.227518)
			(xy 153.235272 -126.359526) (xy 153.239199 -126.492) (xy 153.237265 -126.557238) (xy 163.698184 -126.557238)
			(xy 163.698184 -126.426762) (xy 163.706062 -126.296524) (xy 163.721789 -126.166999) (xy 163.745308 -126.03866)
			(xy 163.776533 -125.911975) (xy 163.81535 -125.787407) (xy 163.861617 -125.665409) (xy 163.915165 -125.546428)
			(xy 163.9758 -125.430897) (xy 164.0433 -125.319238) (xy 164.117419 -125.211858) (xy 164.197885 -125.109148)
			(xy 164.284406 -125.011485) (xy 164.376666 -124.919224) (xy 164.474328 -124.832702) (xy 164.577037 -124.752234)
			(xy 164.684416 -124.678114) (xy 164.796074 -124.610613) (xy 164.911605 -124.549977) (xy 165.030585 -124.496427)
			(xy 165.152582 -124.450158) (xy 165.27715 -124.41134) (xy 165.403835 -124.380114) (xy 165.532173 -124.356593)
			(xy 165.661698 -124.340865) (xy 165.791936 -124.332985) (xy 165.857174 -124.332492) (xy 165.859206 -124.332492)
			(xy 165.896894 -124.332678) (xy 165.972222 -124.335344) (xy 166.009828 -124.337826) (xy 166.014116 -124.338068)
			(xy 166.022671 -124.337308) (xy 166.026846 -124.336302) (xy 166.099276 -124.317041) (xy 166.246139 -124.287074)
			(xy 166.394679 -124.267007) (xy 166.544229 -124.25693) (xy 166.619174 -124.256292) (xy 166.685441 -124.256773)
			(xy 166.817742 -124.264623) (xy 166.949345 -124.280296) (xy 167.079789 -124.303739) (xy 167.208615 -124.334868)
			(xy 167.335371 -124.373574) (xy 167.459611 -124.419721) (xy 167.580899 -124.473148) (xy 167.698809 -124.533666)
			(xy 167.812926 -124.601062) (xy 167.922851 -124.675101) (xy 168.028196 -124.755521) (xy 168.128593 -124.842042)
			(xy 168.223687 -124.934358) (xy 168.313145 -125.032145) (xy 168.396654 -125.13506) (xy 168.473919 -125.242741)
			(xy 168.544669 -125.354811) (xy 168.608655 -125.470875) (xy 168.665654 -125.590526) (xy 168.715464 -125.713343)
			(xy 168.757911 -125.838895) (xy 168.792845 -125.966742) (xy 168.820144 -126.096434) (xy 168.839713 -126.227515)
			(xy 168.851481 -126.359525) (xy 168.855409 -126.492) (xy 168.853475 -126.557238) (xy 175.890184 -126.557238)
			(xy 175.890184 -126.426762) (xy 175.898062 -126.296524) (xy 175.913789 -126.166999) (xy 175.937308 -126.03866)
			(xy 175.968533 -125.911975) (xy 176.00735 -125.787407) (xy 176.053617 -125.665409) (xy 176.107165 -125.546428)
			(xy 176.1678 -125.430897) (xy 176.2353 -125.319238) (xy 176.309419 -125.211858) (xy 176.389885 -125.109148)
			(xy 176.476406 -125.011485) (xy 176.568666 -124.919224) (xy 176.666328 -124.832702) (xy 176.769037 -124.752234)
			(xy 176.876416 -124.678114) (xy 176.988074 -124.610613) (xy 177.103605 -124.549977) (xy 177.222585 -124.496427)
			(xy 177.344582 -124.450158) (xy 177.46915 -124.41134) (xy 177.595835 -124.380114) (xy 177.724173 -124.356593)
			(xy 177.853698 -124.340865) (xy 177.983936 -124.332985) (xy 178.049174 -124.332492) (xy 178.051206 -124.332492)
			(xy 178.088894 -124.332678) (xy 178.164222 -124.335344) (xy 178.201828 -124.337826) (xy 178.206116 -124.338068)
			(xy 178.214671 -124.337308) (xy 178.218846 -124.336302) (xy 178.291276 -124.317041) (xy 178.438139 -124.287074)
			(xy 178.586679 -124.267007) (xy 178.736229 -124.25693) (xy 178.811174 -124.256292) (xy 178.877441 -124.256773)
			(xy 179.009742 -124.264623) (xy 179.141345 -124.280296) (xy 179.271789 -124.303739) (xy 179.400615 -124.334868)
			(xy 179.527371 -124.373574) (xy 179.651611 -124.419721) (xy 179.772899 -124.473148) (xy 179.890809 -124.533666)
			(xy 180.004926 -124.601062) (xy 180.114851 -124.675101) (xy 180.220196 -124.755521) (xy 180.320593 -124.842042)
			(xy 180.415687 -124.934358) (xy 180.505145 -125.032145) (xy 180.588654 -125.13506) (xy 180.665919 -125.242741)
			(xy 180.736669 -125.354811) (xy 180.800655 -125.470875) (xy 180.857654 -125.590526) (xy 180.907464 -125.713343)
			(xy 180.949911 -125.838895) (xy 180.984845 -125.966742) (xy 181.012144 -126.096434) (xy 181.031713 -126.227515)
			(xy 181.043481 -126.359525) (xy 181.047409 -126.492) (xy 181.045475 -126.557238) (xy 188.082184 -126.557238)
			(xy 188.082184 -126.426762) (xy 188.090062 -126.296524) (xy 188.105789 -126.166999) (xy 188.129308 -126.03866)
			(xy 188.160533 -125.911975) (xy 188.19935 -125.787407) (xy 188.245617 -125.665409) (xy 188.299165 -125.546428)
			(xy 188.3598 -125.430897) (xy 188.4273 -125.319238) (xy 188.501419 -125.211858) (xy 188.581885 -125.109148)
			(xy 188.668406 -125.011485) (xy 188.760666 -124.919224) (xy 188.858328 -124.832702) (xy 188.961037 -124.752234)
			(xy 189.068416 -124.678114) (xy 189.180074 -124.610613) (xy 189.295605 -124.549977) (xy 189.414585 -124.496427)
			(xy 189.536582 -124.450158) (xy 189.66115 -124.41134) (xy 189.787835 -124.380114) (xy 189.916173 -124.356593)
			(xy 190.045698 -124.340865) (xy 190.175936 -124.332985) (xy 190.241174 -124.332492) (xy 190.243206 -124.332492)
			(xy 190.280894 -124.332678) (xy 190.356222 -124.335344) (xy 190.393828 -124.337826) (xy 190.398116 -124.338068)
			(xy 190.406671 -124.337308) (xy 190.410846 -124.336302) (xy 190.483276 -124.317041) (xy 190.630139 -124.287074)
			(xy 190.778679 -124.267007) (xy 190.928229 -124.25693) (xy 191.003174 -124.256292) (xy 191.069441 -124.256773)
			(xy 191.201742 -124.264623) (xy 191.333345 -124.280296) (xy 191.463789 -124.303739) (xy 191.592615 -124.334868)
			(xy 191.719371 -124.373574) (xy 191.843611 -124.419721) (xy 191.964899 -124.473148) (xy 192.082809 -124.533666)
			(xy 192.196926 -124.601062) (xy 192.306851 -124.675101) (xy 192.412196 -124.755521) (xy 192.512593 -124.842042)
			(xy 192.607687 -124.934358) (xy 192.697145 -125.032145) (xy 192.780654 -125.13506) (xy 192.857919 -125.242741)
			(xy 192.928669 -125.354811) (xy 192.992655 -125.470875) (xy 193.049654 -125.590526) (xy 193.099464 -125.713343)
			(xy 193.141911 -125.838895) (xy 193.176845 -125.966742) (xy 193.204144 -126.096434) (xy 193.223713 -126.227515)
			(xy 193.235481 -126.359525) (xy 193.239409 -126.492) (xy 193.235481 -126.624475) (xy 193.223713 -126.756485)
			(xy 193.204144 -126.887566) (xy 193.176845 -127.017258) (xy 193.141911 -127.145105) (xy 193.099464 -127.270657)
			(xy 193.049654 -127.393474) (xy 192.992655 -127.513125) (xy 192.928669 -127.629189) (xy 192.857919 -127.741259)
			(xy 192.780654 -127.84894) (xy 192.697145 -127.951855) (xy 192.607687 -128.049642) (xy 192.512593 -128.141958)
			(xy 192.412196 -128.228479) (xy 192.306851 -128.308899) (xy 192.196926 -128.382938) (xy 192.082809 -128.450334)
			(xy 191.964899 -128.510852) (xy 191.843611 -128.564279) (xy 191.719371 -128.610426) (xy 191.592615 -128.649132)
			(xy 191.463789 -128.680261) (xy 191.333345 -128.703704) (xy 191.201742 -128.719377) (xy 191.069441 -128.727227)
			(xy 191.003174 -128.727708) (xy 190.928229 -128.727072) (xy 190.778677 -128.71701) (xy 190.630135 -128.696948)
			(xy 190.483272 -128.666976) (xy 190.410846 -128.647698) (xy 190.406672 -128.646683) (xy 190.398116 -128.645919)
			(xy 190.393828 -128.646174) (xy 190.356222 -128.648659) (xy 190.280894 -128.651327) (xy 190.243206 -128.651508)
			(xy 190.241174 -128.651508) (xy 190.175936 -128.651015) (xy 190.045698 -128.643135) (xy 189.916173 -128.627407)
			(xy 189.787835 -128.603886) (xy 189.66115 -128.57266) (xy 189.536582 -128.533842) (xy 189.414585 -128.487573)
			(xy 189.295605 -128.434023) (xy 189.180074 -128.373387) (xy 189.068416 -128.305886) (xy 188.961037 -128.231766)
			(xy 188.858328 -128.151298) (xy 188.760666 -128.064776) (xy 188.668406 -127.972515) (xy 188.581885 -127.874852)
			(xy 188.501419 -127.772142) (xy 188.4273 -127.664762) (xy 188.3598 -127.553103) (xy 188.299165 -127.437572)
			(xy 188.245617 -127.318591) (xy 188.19935 -127.196593) (xy 188.160533 -127.072025) (xy 188.129308 -126.94534)
			(xy 188.105789 -126.817001) (xy 188.090062 -126.687476) (xy 188.082184 -126.557238) (xy 181.045475 -126.557238)
			(xy 181.043481 -126.624475) (xy 181.031713 -126.756485) (xy 181.012144 -126.887566) (xy 180.984845 -127.017258)
			(xy 180.949911 -127.145105) (xy 180.907464 -127.270657) (xy 180.857654 -127.393474) (xy 180.800655 -127.513125)
			(xy 180.736669 -127.629189) (xy 180.665919 -127.741259) (xy 180.588654 -127.84894) (xy 180.505145 -127.951855)
			(xy 180.415687 -128.049642) (xy 180.320593 -128.141958) (xy 180.220196 -128.228479) (xy 180.114851 -128.308899)
			(xy 180.004926 -128.382938) (xy 179.890809 -128.450334) (xy 179.772899 -128.510852) (xy 179.651611 -128.564279)
			(xy 179.527371 -128.610426) (xy 179.400615 -128.649132) (xy 179.271789 -128.680261) (xy 179.141345 -128.703704)
			(xy 179.009742 -128.719377) (xy 178.877441 -128.727227) (xy 178.811174 -128.727708) (xy 178.736229 -128.727072)
			(xy 178.586677 -128.71701) (xy 178.438135 -128.696948) (xy 178.291272 -128.666976) (xy 178.218846 -128.647698)
			(xy 178.214672 -128.646683) (xy 178.206116 -128.645919) (xy 178.201828 -128.646174) (xy 178.164222 -128.648659)
			(xy 178.088894 -128.651327) (xy 178.051206 -128.651508) (xy 178.049174 -128.651508) (xy 177.983936 -128.651015)
			(xy 177.853698 -128.643135) (xy 177.724173 -128.627407) (xy 177.595835 -128.603886) (xy 177.46915 -128.57266)
			(xy 177.344582 -128.533842) (xy 177.222585 -128.487573) (xy 177.103605 -128.434023) (xy 176.988074 -128.373387)
			(xy 176.876416 -128.305886) (xy 176.769037 -128.231766) (xy 176.666328 -128.151298) (xy 176.568666 -128.064776)
			(xy 176.476406 -127.972515) (xy 176.389885 -127.874852) (xy 176.309419 -127.772142) (xy 176.2353 -127.664762)
			(xy 176.1678 -127.553103) (xy 176.107165 -127.437572) (xy 176.053617 -127.318591) (xy 176.00735 -127.196593)
			(xy 175.968533 -127.072025) (xy 175.937308 -126.94534) (xy 175.913789 -126.817001) (xy 175.898062 -126.687476)
			(xy 175.890184 -126.557238) (xy 168.853475 -126.557238) (xy 168.851481 -126.624475) (xy 168.839713 -126.756485)
			(xy 168.820144 -126.887566) (xy 168.792845 -127.017258) (xy 168.757911 -127.145105) (xy 168.715464 -127.270657)
			(xy 168.665654 -127.393474) (xy 168.608655 -127.513125) (xy 168.544669 -127.629189) (xy 168.473919 -127.741259)
			(xy 168.396654 -127.84894) (xy 168.313145 -127.951855) (xy 168.223687 -128.049642) (xy 168.128593 -128.141958)
			(xy 168.028196 -128.228479) (xy 167.922851 -128.308899) (xy 167.812926 -128.382938) (xy 167.698809 -128.450334)
			(xy 167.580899 -128.510852) (xy 167.459611 -128.564279) (xy 167.335371 -128.610426) (xy 167.208615 -128.649132)
			(xy 167.079789 -128.680261) (xy 166.949345 -128.703704) (xy 166.817742 -128.719377) (xy 166.685441 -128.727227)
			(xy 166.619174 -128.727708) (xy 166.544229 -128.727072) (xy 166.394677 -128.71701) (xy 166.246135 -128.696948)
			(xy 166.099272 -128.666976) (xy 166.026846 -128.647698) (xy 166.022672 -128.646683) (xy 166.014116 -128.645919)
			(xy 166.009828 -128.646174) (xy 165.972222 -128.648659) (xy 165.896894 -128.651327) (xy 165.859206 -128.651508)
			(xy 165.857174 -128.651508) (xy 165.791936 -128.651015) (xy 165.661698 -128.643135) (xy 165.532173 -128.627407)
			(xy 165.403835 -128.603886) (xy 165.27715 -128.57266) (xy 165.152582 -128.533842) (xy 165.030585 -128.487573)
			(xy 164.911605 -128.434023) (xy 164.796074 -128.373387) (xy 164.684416 -128.305886) (xy 164.577037 -128.231766)
			(xy 164.474328 -128.151298) (xy 164.376666 -128.064776) (xy 164.284406 -127.972515) (xy 164.197885 -127.874852)
			(xy 164.117419 -127.772142) (xy 164.0433 -127.664762) (xy 163.9758 -127.553103) (xy 163.915165 -127.437572)
			(xy 163.861617 -127.318591) (xy 163.81535 -127.196593) (xy 163.776533 -127.072025) (xy 163.745308 -126.94534)
			(xy 163.721789 -126.817001) (xy 163.706062 -126.687476) (xy 163.698184 -126.557238) (xy 153.237265 -126.557238)
			(xy 153.235272 -126.624474) (xy 153.223503 -126.756482) (xy 153.203935 -126.887562) (xy 153.176637 -127.017252)
			(xy 153.141703 -127.145097) (xy 153.099257 -127.270648) (xy 153.049448 -127.393464) (xy 152.99245 -127.513114)
			(xy 152.928465 -127.629177) (xy 152.857716 -127.741245) (xy 152.780453 -127.848926) (xy 152.696946 -127.95184)
			(xy 152.607489 -128.049627) (xy 152.512396 -128.141942) (xy 152.412002 -128.228462) (xy 152.306658 -128.308882)
			(xy 152.196735 -128.382921) (xy 152.082619 -128.450318) (xy 151.964711 -128.510836) (xy 151.843425 -128.564262)
			(xy 151.719187 -128.61041) (xy 151.592433 -128.649117) (xy 151.463609 -128.680247) (xy 151.333167 -128.703691)
			(xy 151.201565 -128.719366) (xy 151.069266 -128.727217) (xy 151.003 -128.727708) (xy 150.928055 -128.727089)
			(xy 150.778502 -128.717023) (xy 150.62996 -128.696956) (xy 150.483098 -128.666978) (xy 150.410672 -128.647698)
			(xy 150.406496 -128.64669) (xy 150.397942 -128.645921) (xy 150.393654 -128.646174) (xy 150.356048 -128.648662)
			(xy 150.28072 -128.651328) (xy 150.243032 -128.651508) (xy 150.241 -128.651508) (xy 150.175761 -128.651016)
			(xy 150.045522 -128.643138) (xy 149.915997 -128.62741) (xy 149.787657 -128.603891) (xy 149.660971 -128.572666)
			(xy 149.536402 -128.533849) (xy 149.414403 -128.487581) (xy 149.295421 -128.434031) (xy 149.17989 -128.373395)
			(xy 149.06823 -128.305895) (xy 148.960849 -128.231775) (xy 148.85814 -128.151308) (xy 148.760476 -128.064785)
			(xy 148.668215 -127.972524) (xy 148.581692 -127.87486) (xy 148.501225 -127.772151) (xy 148.427105 -127.66477)
			(xy 148.359605 -127.55311) (xy 148.298969 -127.437579) (xy 148.245419 -127.318597) (xy 148.199151 -127.196598)
			(xy 148.160334 -127.072029) (xy 148.129109 -126.945343) (xy 148.10559 -126.817003) (xy 148.089862 -126.687478)
			(xy 148.081984 -126.557239) (xy 141.045265 -126.557239) (xy 141.043272 -126.624474) (xy 141.031503 -126.756482)
			(xy 141.011935 -126.887562) (xy 140.984637 -127.017252) (xy 140.949703 -127.145097) (xy 140.907257 -127.270648)
			(xy 140.857448 -127.393464) (xy 140.80045 -127.513114) (xy 140.736465 -127.629177) (xy 140.665716 -127.741245)
			(xy 140.588453 -127.848926) (xy 140.504946 -127.95184) (xy 140.415489 -128.049627) (xy 140.320396 -128.141942)
			(xy 140.220002 -128.228462) (xy 140.114658 -128.308882) (xy 140.004735 -128.382921) (xy 139.890619 -128.450318)
			(xy 139.772711 -128.510836) (xy 139.651425 -128.564262) (xy 139.527187 -128.61041) (xy 139.400433 -128.649117)
			(xy 139.271609 -128.680247) (xy 139.141167 -128.703691) (xy 139.009565 -128.719366) (xy 138.877266 -128.727217)
			(xy 138.811 -128.727708) (xy 138.736055 -128.727089) (xy 138.586502 -128.717023) (xy 138.43796 -128.696956)
			(xy 138.291098 -128.666978) (xy 138.218672 -128.647698) (xy 138.214496 -128.64669) (xy 138.205942 -128.645921)
			(xy 138.201654 -128.646174) (xy 138.164048 -128.648662) (xy 138.08872 -128.651328) (xy 138.051032 -128.651508)
			(xy 138.049 -128.651508) (xy 137.983761 -128.651016) (xy 137.853522 -128.643138) (xy 137.723997 -128.62741)
			(xy 137.595657 -128.603891) (xy 137.468971 -128.572666) (xy 137.344402 -128.533849) (xy 137.222403 -128.487581)
			(xy 137.103421 -128.434031) (xy 136.98789 -128.373395) (xy 136.87623 -128.305895) (xy 136.768849 -128.231775)
			(xy 136.66614 -128.151308) (xy 136.568476 -128.064785) (xy 136.476215 -127.972524) (xy 136.389692 -127.87486)
			(xy 136.309225 -127.772151) (xy 136.235105 -127.66477) (xy 136.167605 -127.55311) (xy 136.106969 -127.437579)
			(xy 136.053419 -127.318597) (xy 136.007151 -127.196598) (xy 135.968334 -127.072029) (xy 135.937109 -126.945343)
			(xy 135.91359 -126.817003) (xy 135.897862 -126.687478) (xy 135.889984 -126.557239) (xy 128.853265 -126.557239)
			(xy 128.851272 -126.624474) (xy 128.839503 -126.756482) (xy 128.819935 -126.887562) (xy 128.792637 -127.017252)
			(xy 128.757703 -127.145097) (xy 128.715257 -127.270648) (xy 128.665448 -127.393464) (xy 128.60845 -127.513114)
			(xy 128.544465 -127.629177) (xy 128.473716 -127.741245) (xy 128.396453 -127.848926) (xy 128.312946 -127.95184)
			(xy 128.223489 -128.049627) (xy 128.128396 -128.141942) (xy 128.028002 -128.228462) (xy 127.922658 -128.308882)
			(xy 127.812735 -128.382921) (xy 127.698619 -128.450318) (xy 127.580711 -128.510836) (xy 127.459425 -128.564262)
			(xy 127.335187 -128.61041) (xy 127.208433 -128.649117) (xy 127.079609 -128.680247) (xy 126.949167 -128.703691)
			(xy 126.817565 -128.719366) (xy 126.685266 -128.727217) (xy 126.619 -128.727708) (xy 126.544055 -128.727089)
			(xy 126.394502 -128.717023) (xy 126.24596 -128.696956) (xy 126.099098 -128.666978) (xy 126.026672 -128.647698)
			(xy 126.022496 -128.64669) (xy 126.013942 -128.645921) (xy 126.009654 -128.646174) (xy 125.972048 -128.648662)
			(xy 125.89672 -128.651328) (xy 125.859032 -128.651508) (xy 125.857 -128.651508) (xy 125.791761 -128.651016)
			(xy 125.661522 -128.643138) (xy 125.531997 -128.62741) (xy 125.403657 -128.603891) (xy 125.276971 -128.572666)
			(xy 125.152402 -128.533849) (xy 125.030403 -128.487581) (xy 124.911421 -128.434031) (xy 124.79589 -128.373395)
			(xy 124.68423 -128.305895) (xy 124.576849 -128.231775) (xy 124.47414 -128.151308) (xy 124.376476 -128.064785)
			(xy 124.284215 -127.972524) (xy 124.197692 -127.87486) (xy 124.117225 -127.772151) (xy 124.043105 -127.66477)
			(xy 123.975605 -127.55311) (xy 123.914969 -127.437579) (xy 123.861419 -127.318597) (xy 123.815151 -127.196598)
			(xy 123.776334 -127.072029) (xy 123.745109 -126.945343) (xy 123.72159 -126.817003) (xy 123.705862 -126.687478)
			(xy 123.697984 -126.557239) (xy 113.237065 -126.557239) (xy 113.235072 -126.624473) (xy 113.223304 -126.75648)
			(xy 113.203736 -126.887559) (xy 113.176438 -127.017248) (xy 113.141504 -127.145092) (xy 113.099059 -127.270643)
			(xy 113.04925 -127.393458) (xy 112.992254 -127.513107) (xy 112.928269 -127.629169) (xy 112.857522 -127.741237)
			(xy 112.780259 -127.848917) (xy 112.696754 -127.951831) (xy 112.607298 -128.049618) (xy 112.512206 -128.141933)
			(xy 112.411813 -128.228453) (xy 112.306471 -128.308873) (xy 112.196549 -128.382912) (xy 112.082435 -128.450309)
			(xy 111.964528 -128.510828) (xy 111.843243 -128.564255) (xy 111.719007 -128.610404) (xy 111.592254 -128.649111)
			(xy 111.463431 -128.680242) (xy 111.33299 -128.703687) (xy 111.20139 -128.719363) (xy 111.069092 -128.727216)
			(xy 111.002826 -128.727708) (xy 110.927881 -128.727083) (xy 110.778328 -128.717018) (xy 110.629787 -128.696953)
			(xy 110.482924 -128.666977) (xy 110.410498 -128.647698) (xy 110.406321 -128.646696) (xy 110.397768 -128.645923)
			(xy 110.39348 -128.646174) (xy 110.355874 -128.648661) (xy 110.280546 -128.651328) (xy 110.242858 -128.651508)
			(xy 110.240826 -128.651508) (xy 110.175587 -128.651026) (xy 110.045346 -128.643149) (xy 109.915818 -128.627423)
			(xy 109.787477 -128.603905) (xy 109.660789 -128.572681) (xy 109.536218 -128.533864) (xy 109.414218 -128.487597)
			(xy 109.295234 -128.434048) (xy 109.1797 -128.373412) (xy 109.068038 -128.305912) (xy 108.960656 -128.231792)
			(xy 108.857945 -128.151324) (xy 108.760279 -128.064801) (xy 108.668016 -127.97254) (xy 108.581493 -127.874875)
			(xy 108.501023 -127.772165) (xy 108.426902 -127.664783) (xy 108.3594 -127.553123) (xy 108.298764 -127.43759)
			(xy 108.245213 -127.318606) (xy 108.198944 -127.196607) (xy 108.160126 -127.072036) (xy 108.1289 -126.945349)
			(xy 108.105381 -126.817007) (xy 108.089653 -126.68748) (xy 108.081775 -126.557239) (xy 101.045065 -126.557239)
			(xy 101.043072 -126.624473) (xy 101.031304 -126.75648) (xy 101.011736 -126.887559) (xy 100.984438 -127.017248)
			(xy 100.949504 -127.145092) (xy 100.907059 -127.270643) (xy 100.85725 -127.393458) (xy 100.800254 -127.513107)
			(xy 100.736269 -127.629169) (xy 100.665522 -127.741237) (xy 100.588259 -127.848917) (xy 100.504754 -127.951831)
			(xy 100.415298 -128.049618) (xy 100.320206 -128.141933) (xy 100.219813 -128.228453) (xy 100.114471 -128.308873)
			(xy 100.004549 -128.382912) (xy 99.890435 -128.450309) (xy 99.772528 -128.510828) (xy 99.651243 -128.564255)
			(xy 99.527007 -128.610404) (xy 99.400254 -128.649111) (xy 99.271431 -128.680242) (xy 99.14099 -128.703687)
			(xy 99.00939 -128.719363) (xy 98.877092 -128.727216) (xy 98.810826 -128.727708) (xy 98.735881 -128.727083)
			(xy 98.586328 -128.717018) (xy 98.437787 -128.696953) (xy 98.290924 -128.666977) (xy 98.218498 -128.647698)
			(xy 98.214321 -128.646696) (xy 98.205768 -128.645923) (xy 98.20148 -128.646174) (xy 98.163874 -128.648661)
			(xy 98.088546 -128.651328) (xy 98.050858 -128.651508) (xy 98.048826 -128.651508) (xy 97.983587 -128.651026)
			(xy 97.853346 -128.643149) (xy 97.723818 -128.627423) (xy 97.595477 -128.603905) (xy 97.468789 -128.572681)
			(xy 97.344218 -128.533864) (xy 97.222218 -128.487597) (xy 97.103234 -128.434048) (xy 96.9877 -128.373412)
			(xy 96.876038 -128.305912) (xy 96.768656 -128.231792) (xy 96.665945 -128.151324) (xy 96.568279 -128.064801)
			(xy 96.476016 -127.97254) (xy 96.389493 -127.874875) (xy 96.309023 -127.772165) (xy 96.234902 -127.664783)
			(xy 96.1674 -127.553123) (xy 96.106764 -127.43759) (xy 96.053213 -127.318606) (xy 96.006944 -127.196607)
			(xy 95.968126 -127.072036) (xy 95.9369 -126.945349) (xy 95.913381 -126.817007) (xy 95.897653 -126.68748)
			(xy 95.889775 -126.557239) (xy 88.853065 -126.557239) (xy 88.851072 -126.624473) (xy 88.839304 -126.75648)
			(xy 88.819736 -126.887559) (xy 88.792438 -127.017248) (xy 88.757504 -127.145092) (xy 88.715059 -127.270643)
			(xy 88.66525 -127.393458) (xy 88.608254 -127.513107) (xy 88.544269 -127.629169) (xy 88.473522 -127.741237)
			(xy 88.396259 -127.848917) (xy 88.312754 -127.951831) (xy 88.223298 -128.049618) (xy 88.128206 -128.141933)
			(xy 88.027813 -128.228453) (xy 87.922471 -128.308873) (xy 87.812549 -128.382912) (xy 87.698435 -128.450309)
			(xy 87.580528 -128.510828) (xy 87.459243 -128.564255) (xy 87.335007 -128.610404) (xy 87.208254 -128.649111)
			(xy 87.079431 -128.680242) (xy 86.94899 -128.703687) (xy 86.81739 -128.719363) (xy 86.685092 -128.727216)
			(xy 86.618826 -128.727708) (xy 86.543881 -128.727083) (xy 86.394328 -128.717018) (xy 86.245787 -128.696953)
			(xy 86.098924 -128.666977) (xy 86.026498 -128.647698) (xy 86.022321 -128.646696) (xy 86.013768 -128.645923)
			(xy 86.00948 -128.646174) (xy 85.971874 -128.648661) (xy 85.896546 -128.651328) (xy 85.858858 -128.651508)
			(xy 85.856826 -128.651508) (xy 85.791587 -128.651026) (xy 85.661346 -128.643149) (xy 85.531818 -128.627423)
			(xy 85.403477 -128.603905) (xy 85.276789 -128.572681) (xy 85.152218 -128.533864) (xy 85.030218 -128.487597)
			(xy 84.911234 -128.434048) (xy 84.7957 -128.373412) (xy 84.684038 -128.305912) (xy 84.576656 -128.231792)
			(xy 84.473945 -128.151324) (xy 84.376279 -128.064801) (xy 84.284016 -127.97254) (xy 84.197493 -127.874875)
			(xy 84.117023 -127.772165) (xy 84.042902 -127.664783) (xy 83.9754 -127.553123) (xy 83.914764 -127.43759)
			(xy 83.861213 -127.318606) (xy 83.814944 -127.196607) (xy 83.776126 -127.072036) (xy 83.7449 -126.945349)
			(xy 83.721381 -126.817007) (xy 83.705653 -126.68748) (xy 83.697775 -126.557239) (xy 73.237165 -126.557239)
			(xy 73.235172 -126.624474) (xy 73.223403 -126.756482) (xy 73.203836 -126.887561) (xy 73.176537 -127.017251)
			(xy 73.141603 -127.145096) (xy 73.099157 -127.270647) (xy 73.049348 -127.393463) (xy 72.992351 -127.513112)
			(xy 72.928366 -127.629175) (xy 72.857617 -127.741243) (xy 72.780354 -127.848924) (xy 72.696848 -127.951838)
			(xy 72.607391 -128.049625) (xy 72.512299 -128.14194) (xy 72.411904 -128.22846) (xy 72.306561 -128.30888)
			(xy 72.196639 -128.382919) (xy 72.082523 -128.450316) (xy 71.964615 -128.510834) (xy 71.843329 -128.564261)
			(xy 71.719092 -128.610409) (xy 71.592338 -128.649116) (xy 71.463514 -128.680246) (xy 71.333072 -128.70369)
			(xy 71.201471 -128.719365) (xy 71.069172 -128.727217) (xy 71.002906 -128.727708) (xy 70.927961 -128.727087)
			(xy 70.778408 -128.717022) (xy 70.629866 -128.696955) (xy 70.483004 -128.666978) (xy 70.410578 -128.647698)
			(xy 70.406402 -128.646691) (xy 70.397848 -128.645922) (xy 70.39356 -128.646174) (xy 70.355954 -128.648662)
			(xy 70.280626 -128.651328) (xy 70.242938 -128.651508) (xy 70.240906 -128.651508) (xy 70.175667 -128.651025)
			(xy 70.045427 -128.643148) (xy 69.9159 -128.62742) (xy 69.78756 -128.603901) (xy 69.660873 -128.572676)
			(xy 69.536303 -128.533859) (xy 69.414304 -128.487591) (xy 69.295321 -128.434042) (xy 69.179788 -128.373406)
			(xy 69.068128 -128.305905) (xy 68.960746 -128.231785) (xy 68.858036 -128.151317) (xy 68.760372 -128.064794)
			(xy 68.66811 -127.972533) (xy 68.581587 -127.874868) (xy 68.501119 -127.772159) (xy 68.426998 -127.664777)
			(xy 68.359497 -127.553117) (xy 68.298861 -127.437584) (xy 68.245311 -127.318602) (xy 68.199043 -127.196603)
			(xy 68.160225 -127.072033) (xy 68.129 -126.945346) (xy 68.10548 -126.817005) (xy 68.089753 -126.687479)
			(xy 68.081875 -126.557239) (xy 61.045165 -126.557239) (xy 61.043172 -126.624474) (xy 61.031403 -126.756482)
			(xy 61.011836 -126.887561) (xy 60.984537 -127.017251) (xy 60.949603 -127.145096) (xy 60.907157 -127.270647)
			(xy 60.857348 -127.393463) (xy 60.800351 -127.513112) (xy 60.736366 -127.629175) (xy 60.665617 -127.741243)
			(xy 60.588354 -127.848924) (xy 60.504848 -127.951838) (xy 60.415391 -128.049625) (xy 60.320299 -128.14194)
			(xy 60.219904 -128.22846) (xy 60.114561 -128.30888) (xy 60.004639 -128.382919) (xy 59.890523 -128.450316)
			(xy 59.772615 -128.510834) (xy 59.651329 -128.564261) (xy 59.527092 -128.610409) (xy 59.400338 -128.649116)
			(xy 59.271514 -128.680246) (xy 59.141072 -128.70369) (xy 59.009471 -128.719365) (xy 58.877172 -128.727217)
			(xy 58.810906 -128.727708) (xy 58.735961 -128.727087) (xy 58.586408 -128.717022) (xy 58.437866 -128.696955)
			(xy 58.291004 -128.666978) (xy 58.218578 -128.647698) (xy 58.214402 -128.646691) (xy 58.205848 -128.645922)
			(xy 58.20156 -128.646174) (xy 58.163954 -128.648662) (xy 58.088626 -128.651328) (xy 58.050938 -128.651508)
			(xy 58.048906 -128.651508) (xy 57.983667 -128.651025) (xy 57.853427 -128.643148) (xy 57.7239 -128.62742)
			(xy 57.59556 -128.603901) (xy 57.468873 -128.572676) (xy 57.344303 -128.533859) (xy 57.222304 -128.487591)
			(xy 57.103321 -128.434042) (xy 56.987788 -128.373406) (xy 56.876128 -128.305905) (xy 56.768746 -128.231785)
			(xy 56.666036 -128.151317) (xy 56.568372 -128.064794) (xy 56.47611 -127.972533) (xy 56.389587 -127.874868)
			(xy 56.309119 -127.772159) (xy 56.234998 -127.664777) (xy 56.167497 -127.553117) (xy 56.106861 -127.437584)
			(xy 56.053311 -127.318602) (xy 56.007043 -127.196603) (xy 55.968225 -127.072033) (xy 55.937 -126.945346)
			(xy 55.91348 -126.817005) (xy 55.897753 -126.687479) (xy 55.889875 -126.557239) (xy 48.853165 -126.557239)
			(xy 48.851172 -126.624474) (xy 48.839403 -126.756482) (xy 48.819836 -126.887561) (xy 48.792537 -127.017251)
			(xy 48.757603 -127.145096) (xy 48.715157 -127.270647) (xy 48.665348 -127.393463) (xy 48.608351 -127.513112)
			(xy 48.544366 -127.629175) (xy 48.473617 -127.741243) (xy 48.396354 -127.848924) (xy 48.312848 -127.951838)
			(xy 48.223391 -128.049625) (xy 48.128299 -128.14194) (xy 48.027904 -128.22846) (xy 47.922561 -128.30888)
			(xy 47.812639 -128.382919) (xy 47.698523 -128.450316) (xy 47.580615 -128.510834) (xy 47.459329 -128.564261)
			(xy 47.335092 -128.610409) (xy 47.208338 -128.649116) (xy 47.079514 -128.680246) (xy 46.949072 -128.70369)
			(xy 46.817471 -128.719365) (xy 46.685172 -128.727217) (xy 46.618906 -128.727708) (xy 46.543961 -128.727087)
			(xy 46.394408 -128.717022) (xy 46.245866 -128.696955) (xy 46.099004 -128.666978) (xy 46.026578 -128.647698)
			(xy 46.022402 -128.646691) (xy 46.013848 -128.645922) (xy 46.00956 -128.646174) (xy 45.971954 -128.648662)
			(xy 45.896626 -128.651328) (xy 45.858938 -128.651508) (xy 45.856906 -128.651508) (xy 45.791667 -128.651025)
			(xy 45.661427 -128.643148) (xy 45.5319 -128.62742) (xy 45.40356 -128.603901) (xy 45.276873 -128.572676)
			(xy 45.152303 -128.533859) (xy 45.030304 -128.487591) (xy 44.911321 -128.434042) (xy 44.795788 -128.373406)
			(xy 44.684128 -128.305905) (xy 44.576746 -128.231785) (xy 44.474036 -128.151317) (xy 44.376372 -128.064794)
			(xy 44.28411 -127.972533) (xy 44.197587 -127.874868) (xy 44.117119 -127.772159) (xy 44.042998 -127.664777)
			(xy 43.975497 -127.553117) (xy 43.914861 -127.437584) (xy 43.861311 -127.318602) (xy 43.815043 -127.196603)
			(xy 43.776225 -127.072033) (xy 43.745 -126.945346) (xy 43.72148 -126.817005) (xy 43.705753 -126.687479)
			(xy 43.697875 -126.557239) (xy 37.531802 -126.557239) (xy 37.531802 -131.637239) (xy 43.697875 -131.637239)
			(xy 43.697875 -131.506761) (xy 43.705753 -131.376521) (xy 43.72148 -131.246995) (xy 43.745 -131.118654)
			(xy 43.776225 -130.991967) (xy 43.815043 -130.867397) (xy 43.861311 -130.745398) (xy 43.914861 -130.626416)
			(xy 43.975497 -130.510883) (xy 44.042998 -130.399223) (xy 44.117119 -130.291841) (xy 44.197587 -130.189132)
			(xy 44.28411 -130.091467) (xy 44.376372 -129.999206) (xy 44.474036 -129.912683) (xy 44.576746 -129.832215)
			(xy 44.684128 -129.758095) (xy 44.795788 -129.690594) (xy 44.911321 -129.629958) (xy 45.030304 -129.576409)
			(xy 45.152303 -129.530141) (xy 45.276873 -129.491324) (xy 45.40356 -129.460099) (xy 45.5319 -129.43658)
			(xy 45.661427 -129.420852) (xy 45.791667 -129.412975) (xy 45.856906 -129.412492) (xy 45.858938 -129.412492)
			(xy 45.896626 -129.412677) (xy 45.971954 -129.415344) (xy 46.00956 -129.417826) (xy 46.013848 -129.418076)
			(xy 46.022403 -129.417311) (xy 46.026578 -129.416302) (xy 46.099006 -129.397033) (xy 46.24587 -129.367069)
			(xy 46.394411 -129.347004) (xy 46.543961 -129.336929) (xy 46.618906 -129.336292) (xy 46.685172 -129.336783)
			(xy 46.817471 -129.344635) (xy 46.949072 -129.36031) (xy 47.079514 -129.383754) (xy 47.208338 -129.414884)
			(xy 47.335092 -129.453591) (xy 47.459329 -129.499739) (xy 47.580615 -129.553166) (xy 47.698523 -129.613684)
			(xy 47.812639 -129.681081) (xy 47.922561 -129.75512) (xy 48.027904 -129.83554) (xy 48.128299 -129.92206)
			(xy 48.223391 -130.014375) (xy 48.312848 -130.112162) (xy 48.396354 -130.215076) (xy 48.473617 -130.322757)
			(xy 48.544366 -130.434825) (xy 48.608351 -130.550888) (xy 48.665348 -130.670537) (xy 48.715157 -130.793353)
			(xy 48.757603 -130.918904) (xy 48.792537 -131.046749) (xy 48.819836 -131.176439) (xy 48.839403 -131.307518)
			(xy 48.851172 -131.439526) (xy 48.855099 -131.572) (xy 48.853165 -131.637239) (xy 55.889875 -131.637239)
			(xy 55.889875 -131.506761) (xy 55.897753 -131.376521) (xy 55.91348 -131.246995) (xy 55.937 -131.118654)
			(xy 55.968225 -130.991967) (xy 56.007043 -130.867397) (xy 56.053311 -130.745398) (xy 56.106861 -130.626416)
			(xy 56.167497 -130.510883) (xy 56.234998 -130.399223) (xy 56.309119 -130.291841) (xy 56.389587 -130.189132)
			(xy 56.47611 -130.091467) (xy 56.568372 -129.999206) (xy 56.666036 -129.912683) (xy 56.768746 -129.832215)
			(xy 56.876128 -129.758095) (xy 56.987788 -129.690594) (xy 57.103321 -129.629958) (xy 57.222304 -129.576409)
			(xy 57.344303 -129.530141) (xy 57.468873 -129.491324) (xy 57.59556 -129.460099) (xy 57.7239 -129.43658)
			(xy 57.853427 -129.420852) (xy 57.983667 -129.412975) (xy 58.048906 -129.412492) (xy 58.050938 -129.412492)
			(xy 58.088626 -129.412677) (xy 58.163954 -129.415344) (xy 58.20156 -129.417826) (xy 58.205848 -129.418076)
			(xy 58.214403 -129.417311) (xy 58.218578 -129.416302) (xy 58.291006 -129.397033) (xy 58.43787 -129.367069)
			(xy 58.586411 -129.347004) (xy 58.735961 -129.336929) (xy 58.810906 -129.336292) (xy 58.877172 -129.336783)
			(xy 59.009471 -129.344635) (xy 59.141072 -129.36031) (xy 59.271514 -129.383754) (xy 59.400338 -129.414884)
			(xy 59.527092 -129.453591) (xy 59.651329 -129.499739) (xy 59.772615 -129.553166) (xy 59.890523 -129.613684)
			(xy 60.004639 -129.681081) (xy 60.114561 -129.75512) (xy 60.219904 -129.83554) (xy 60.320299 -129.92206)
			(xy 60.415391 -130.014375) (xy 60.504848 -130.112162) (xy 60.588354 -130.215076) (xy 60.665617 -130.322757)
			(xy 60.736366 -130.434825) (xy 60.800351 -130.550888) (xy 60.857348 -130.670537) (xy 60.907157 -130.793353)
			(xy 60.949603 -130.918904) (xy 60.984537 -131.046749) (xy 61.011836 -131.176439) (xy 61.031403 -131.307518)
			(xy 61.043172 -131.439526) (xy 61.047099 -131.572) (xy 61.045165 -131.637239) (xy 68.081875 -131.637239)
			(xy 68.081875 -131.506761) (xy 68.089753 -131.376521) (xy 68.10548 -131.246995) (xy 68.129 -131.118654)
			(xy 68.160225 -130.991967) (xy 68.199043 -130.867397) (xy 68.245311 -130.745398) (xy 68.298861 -130.626416)
			(xy 68.359497 -130.510883) (xy 68.426998 -130.399223) (xy 68.501119 -130.291841) (xy 68.581587 -130.189132)
			(xy 68.66811 -130.091467) (xy 68.760372 -129.999206) (xy 68.858036 -129.912683) (xy 68.960746 -129.832215)
			(xy 69.068128 -129.758095) (xy 69.179788 -129.690594) (xy 69.295321 -129.629958) (xy 69.414304 -129.576409)
			(xy 69.536303 -129.530141) (xy 69.660873 -129.491324) (xy 69.78756 -129.460099) (xy 69.9159 -129.43658)
			(xy 70.045427 -129.420852) (xy 70.175667 -129.412975) (xy 70.240906 -129.412492) (xy 70.242938 -129.412492)
			(xy 70.280626 -129.412677) (xy 70.355954 -129.415344) (xy 70.39356 -129.417826) (xy 70.397848 -129.418076)
			(xy 70.406403 -129.417311) (xy 70.410578 -129.416302) (xy 70.483006 -129.397033) (xy 70.62987 -129.367069)
			(xy 70.778411 -129.347004) (xy 70.927961 -129.336929) (xy 71.002906 -129.336292) (xy 71.069172 -129.336783)
			(xy 71.201471 -129.344635) (xy 71.333072 -129.36031) (xy 71.463514 -129.383754) (xy 71.592338 -129.414884)
			(xy 71.719092 -129.453591) (xy 71.843329 -129.499739) (xy 71.964615 -129.553166) (xy 72.082523 -129.613684)
			(xy 72.196639 -129.681081) (xy 72.306561 -129.75512) (xy 72.411904 -129.83554) (xy 72.512299 -129.92206)
			(xy 72.607391 -130.014375) (xy 72.696848 -130.112162) (xy 72.780354 -130.215076) (xy 72.857617 -130.322757)
			(xy 72.928366 -130.434825) (xy 72.992351 -130.550888) (xy 73.049348 -130.670537) (xy 73.099157 -130.793353)
			(xy 73.141603 -130.918904) (xy 73.176537 -131.046749) (xy 73.203836 -131.176439) (xy 73.223403 -131.307518)
			(xy 73.235172 -131.439526) (xy 73.239099 -131.572) (xy 73.237165 -131.637239) (xy 83.697775 -131.637239)
			(xy 83.697775 -131.506761) (xy 83.705653 -131.37652) (xy 83.721381 -131.246993) (xy 83.7449 -131.118651)
			(xy 83.776126 -130.991964) (xy 83.814944 -130.867393) (xy 83.861213 -130.745394) (xy 83.914764 -130.62641)
			(xy 83.9754 -130.510877) (xy 84.042902 -130.399217) (xy 84.117023 -130.291835) (xy 84.197493 -130.189125)
			(xy 84.284016 -130.09146) (xy 84.376279 -129.999199) (xy 84.473945 -129.912676) (xy 84.576656 -129.832208)
			(xy 84.684038 -129.758088) (xy 84.7957 -129.690588) (xy 84.911234 -129.629952) (xy 85.030218 -129.576403)
			(xy 85.152218 -129.530136) (xy 85.276789 -129.491319) (xy 85.403477 -129.460095) (xy 85.531818 -129.436577)
			(xy 85.661346 -129.420851) (xy 85.791587 -129.412974) (xy 85.856826 -129.412492) (xy 85.858858 -129.412492)
			(xy 85.896546 -129.412676) (xy 85.971874 -129.415344) (xy 86.00948 -129.417826) (xy 86.013768 -129.418081)
			(xy 86.022323 -129.417313) (xy 86.026498 -129.416302) (xy 86.098925 -129.397029) (xy 86.245789 -129.367065)
			(xy 86.39433 -129.347002) (xy 86.543881 -129.336928) (xy 86.618826 -129.336292) (xy 86.685092 -129.336784)
			(xy 86.81739 -129.344637) (xy 86.94899 -129.360313) (xy 87.079431 -129.383758) (xy 87.208254 -129.414889)
			(xy 87.335007 -129.453596) (xy 87.459243 -129.499745) (xy 87.580528 -129.553172) (xy 87.698435 -129.613691)
			(xy 87.812549 -129.681088) (xy 87.922471 -129.755127) (xy 88.027813 -129.835547) (xy 88.128206 -129.922067)
			(xy 88.223298 -130.014382) (xy 88.312754 -130.112169) (xy 88.396259 -130.215083) (xy 88.473522 -130.322763)
			(xy 88.544269 -130.434831) (xy 88.608254 -130.550893) (xy 88.66525 -130.670542) (xy 88.715059 -130.793357)
			(xy 88.757504 -130.918908) (xy 88.792438 -131.046752) (xy 88.819736 -131.176441) (xy 88.839304 -131.30752)
			(xy 88.851072 -131.439527) (xy 88.854999 -131.572) (xy 88.853065 -131.637239) (xy 95.889775 -131.637239)
			(xy 95.889775 -131.506761) (xy 95.897653 -131.37652) (xy 95.913381 -131.246993) (xy 95.9369 -131.118651)
			(xy 95.968126 -130.991964) (xy 96.006944 -130.867393) (xy 96.053213 -130.745394) (xy 96.106764 -130.62641)
			(xy 96.1674 -130.510877) (xy 96.234902 -130.399217) (xy 96.309023 -130.291835) (xy 96.389493 -130.189125)
			(xy 96.476016 -130.09146) (xy 96.568279 -129.999199) (xy 96.665945 -129.912676) (xy 96.768656 -129.832208)
			(xy 96.876038 -129.758088) (xy 96.9877 -129.690588) (xy 97.103234 -129.629952) (xy 97.222218 -129.576403)
			(xy 97.344218 -129.530136) (xy 97.468789 -129.491319) (xy 97.595477 -129.460095) (xy 97.723818 -129.436577)
			(xy 97.853346 -129.420851) (xy 97.983587 -129.412974) (xy 98.048826 -129.412492) (xy 98.050858 -129.412492)
			(xy 98.088546 -129.412676) (xy 98.163874 -129.415344) (xy 98.20148 -129.417826) (xy 98.205768 -129.418081)
			(xy 98.214323 -129.417313) (xy 98.218498 -129.416302) (xy 98.290925 -129.397029) (xy 98.437789 -129.367065)
			(xy 98.58633 -129.347002) (xy 98.735881 -129.336928) (xy 98.810826 -129.336292) (xy 98.877092 -129.336784)
			(xy 99.00939 -129.344637) (xy 99.14099 -129.360313) (xy 99.271431 -129.383758) (xy 99.400254 -129.414889)
			(xy 99.527007 -129.453596) (xy 99.651243 -129.499745) (xy 99.772528 -129.553172) (xy 99.890435 -129.613691)
			(xy 100.004549 -129.681088) (xy 100.114471 -129.755127) (xy 100.219813 -129.835547) (xy 100.320206 -129.922067)
			(xy 100.415298 -130.014382) (xy 100.504754 -130.112169) (xy 100.588259 -130.215083) (xy 100.665522 -130.322763)
			(xy 100.736269 -130.434831) (xy 100.800254 -130.550893) (xy 100.85725 -130.670542) (xy 100.907059 -130.793357)
			(xy 100.949504 -130.918908) (xy 100.984438 -131.046752) (xy 101.011736 -131.176441) (xy 101.031304 -131.30752)
			(xy 101.043072 -131.439527) (xy 101.046999 -131.572) (xy 101.045065 -131.637239) (xy 108.081775 -131.637239)
			(xy 108.081775 -131.506761) (xy 108.089653 -131.37652) (xy 108.105381 -131.246993) (xy 108.1289 -131.118651)
			(xy 108.160126 -130.991964) (xy 108.198944 -130.867393) (xy 108.245213 -130.745394) (xy 108.298764 -130.62641)
			(xy 108.3594 -130.510877) (xy 108.426902 -130.399217) (xy 108.501023 -130.291835) (xy 108.581493 -130.189125)
			(xy 108.668016 -130.09146) (xy 108.760279 -129.999199) (xy 108.857945 -129.912676) (xy 108.960656 -129.832208)
			(xy 109.068038 -129.758088) (xy 109.1797 -129.690588) (xy 109.295234 -129.629952) (xy 109.414218 -129.576403)
			(xy 109.536218 -129.530136) (xy 109.660789 -129.491319) (xy 109.787477 -129.460095) (xy 109.915818 -129.436577)
			(xy 110.045346 -129.420851) (xy 110.175587 -129.412974) (xy 110.240826 -129.412492) (xy 110.242858 -129.412492)
			(xy 110.280546 -129.412676) (xy 110.355874 -129.415344) (xy 110.39348 -129.417826) (xy 110.397768 -129.418081)
			(xy 110.406323 -129.417313) (xy 110.410498 -129.416302) (xy 110.482925 -129.397029) (xy 110.629789 -129.367065)
			(xy 110.77833 -129.347002) (xy 110.927881 -129.336928) (xy 111.002826 -129.336292) (xy 111.069092 -129.336784)
			(xy 111.20139 -129.344637) (xy 111.33299 -129.360313) (xy 111.463431 -129.383758) (xy 111.592254 -129.414889)
			(xy 111.719007 -129.453596) (xy 111.843243 -129.499745) (xy 111.964528 -129.553172) (xy 112.082435 -129.613691)
			(xy 112.196549 -129.681088) (xy 112.306471 -129.755127) (xy 112.411813 -129.835547) (xy 112.512206 -129.922067)
			(xy 112.607298 -130.014382) (xy 112.696754 -130.112169) (xy 112.780259 -130.215083) (xy 112.857522 -130.322763)
			(xy 112.928269 -130.434831) (xy 112.992254 -130.550893) (xy 113.04925 -130.670542) (xy 113.099059 -130.793357)
			(xy 113.141504 -130.918908) (xy 113.176438 -131.046752) (xy 113.203736 -131.176441) (xy 113.223304 -131.30752)
			(xy 113.235072 -131.439527) (xy 113.238999 -131.572) (xy 113.237065 -131.637239) (xy 123.697984 -131.637239)
			(xy 123.697984 -131.506761) (xy 123.705862 -131.376522) (xy 123.72159 -131.246997) (xy 123.745109 -131.118657)
			(xy 123.776334 -130.991971) (xy 123.815151 -130.867402) (xy 123.861419 -130.745403) (xy 123.914969 -130.626421)
			(xy 123.975605 -130.51089) (xy 124.043105 -130.39923) (xy 124.117225 -130.291849) (xy 124.197692 -130.18914)
			(xy 124.284215 -130.091476) (xy 124.376476 -129.999215) (xy 124.47414 -129.912692) (xy 124.576849 -129.832225)
			(xy 124.68423 -129.758105) (xy 124.79589 -129.690605) (xy 124.911421 -129.629969) (xy 125.030403 -129.576419)
			(xy 125.152402 -129.530151) (xy 125.276971 -129.491334) (xy 125.403657 -129.460109) (xy 125.531997 -129.43659)
			(xy 125.661522 -129.420862) (xy 125.791761 -129.412984) (xy 125.857 -129.412492) (xy 125.859032 -129.412492)
			(xy 125.89672 -129.412677) (xy 125.972048 -129.415344) (xy 126.009654 -129.417826) (xy 126.013942 -129.418075)
			(xy 126.022497 -129.417311) (xy 126.026672 -129.416302) (xy 126.0991 -129.397035) (xy 126.245964 -129.36707)
			(xy 126.394505 -129.347004) (xy 126.544055 -129.336929) (xy 126.619 -129.336292) (xy 126.685266 -129.336783)
			(xy 126.817565 -129.344634) (xy 126.949167 -129.360309) (xy 127.079609 -129.383753) (xy 127.208433 -129.414883)
			(xy 127.335187 -129.45359) (xy 127.459425 -129.499738) (xy 127.580711 -129.553164) (xy 127.698619 -129.613682)
			(xy 127.812735 -129.681079) (xy 127.922658 -129.755118) (xy 128.028002 -129.835538) (xy 128.128396 -129.922058)
			(xy 128.223489 -130.014373) (xy 128.312946 -130.11216) (xy 128.396453 -130.215074) (xy 128.473716 -130.322755)
			(xy 128.544465 -130.434823) (xy 128.60845 -130.550886) (xy 128.665448 -130.670536) (xy 128.715257 -130.793352)
			(xy 128.757703 -130.918903) (xy 128.792637 -131.046748) (xy 128.819935 -131.176438) (xy 128.839503 -131.307518)
			(xy 128.851272 -131.439526) (xy 128.855199 -131.572) (xy 128.853265 -131.637239) (xy 135.889984 -131.637239)
			(xy 135.889984 -131.506761) (xy 135.897862 -131.376522) (xy 135.91359 -131.246997) (xy 135.937109 -131.118657)
			(xy 135.968334 -130.991971) (xy 136.007151 -130.867402) (xy 136.053419 -130.745403) (xy 136.106969 -130.626421)
			(xy 136.167605 -130.51089) (xy 136.235105 -130.39923) (xy 136.309225 -130.291849) (xy 136.389692 -130.18914)
			(xy 136.476215 -130.091476) (xy 136.568476 -129.999215) (xy 136.66614 -129.912692) (xy 136.768849 -129.832225)
			(xy 136.87623 -129.758105) (xy 136.98789 -129.690605) (xy 137.103421 -129.629969) (xy 137.222403 -129.576419)
			(xy 137.344402 -129.530151) (xy 137.468971 -129.491334) (xy 137.595657 -129.460109) (xy 137.723997 -129.43659)
			(xy 137.853522 -129.420862) (xy 137.983761 -129.412984) (xy 138.049 -129.412492) (xy 138.051032 -129.412492)
			(xy 138.08872 -129.412677) (xy 138.164048 -129.415344) (xy 138.201654 -129.417826) (xy 138.205942 -129.418075)
			(xy 138.214497 -129.417311) (xy 138.218672 -129.416302) (xy 138.2911 -129.397035) (xy 138.437964 -129.36707)
			(xy 138.586505 -129.347004) (xy 138.736055 -129.336929) (xy 138.811 -129.336292) (xy 138.877266 -129.336783)
			(xy 139.009565 -129.344634) (xy 139.141167 -129.360309) (xy 139.271609 -129.383753) (xy 139.400433 -129.414883)
			(xy 139.527187 -129.45359) (xy 139.651425 -129.499738) (xy 139.772711 -129.553164) (xy 139.890619 -129.613682)
			(xy 140.004735 -129.681079) (xy 140.114658 -129.755118) (xy 140.220002 -129.835538) (xy 140.320396 -129.922058)
			(xy 140.415489 -130.014373) (xy 140.504946 -130.11216) (xy 140.588453 -130.215074) (xy 140.665716 -130.322755)
			(xy 140.736465 -130.434823) (xy 140.80045 -130.550886) (xy 140.857448 -130.670536) (xy 140.907257 -130.793352)
			(xy 140.949703 -130.918903) (xy 140.984637 -131.046748) (xy 141.011935 -131.176438) (xy 141.031503 -131.307518)
			(xy 141.043272 -131.439526) (xy 141.047199 -131.572) (xy 141.045265 -131.637239) (xy 148.081984 -131.637239)
			(xy 148.081984 -131.506761) (xy 148.089862 -131.376522) (xy 148.10559 -131.246997) (xy 148.129109 -131.118657)
			(xy 148.160334 -130.991971) (xy 148.199151 -130.867402) (xy 148.245419 -130.745403) (xy 148.298969 -130.626421)
			(xy 148.359605 -130.51089) (xy 148.427105 -130.39923) (xy 148.501225 -130.291849) (xy 148.581692 -130.18914)
			(xy 148.668215 -130.091476) (xy 148.760476 -129.999215) (xy 148.85814 -129.912692) (xy 148.960849 -129.832225)
			(xy 149.06823 -129.758105) (xy 149.17989 -129.690605) (xy 149.295421 -129.629969) (xy 149.414403 -129.576419)
			(xy 149.536402 -129.530151) (xy 149.660971 -129.491334) (xy 149.787657 -129.460109) (xy 149.915997 -129.43659)
			(xy 150.045522 -129.420862) (xy 150.175761 -129.412984) (xy 150.241 -129.412492) (xy 150.243032 -129.412492)
			(xy 150.28072 -129.412677) (xy 150.356048 -129.415344) (xy 150.393654 -129.417826) (xy 150.397942 -129.418075)
			(xy 150.406497 -129.417311) (xy 150.410672 -129.416302) (xy 150.4831 -129.397035) (xy 150.629964 -129.36707)
			(xy 150.778505 -129.347004) (xy 150.928055 -129.336929) (xy 151.003 -129.336292) (xy 151.069266 -129.336783)
			(xy 151.201565 -129.344634) (xy 151.333167 -129.360309) (xy 151.463609 -129.383753) (xy 151.592433 -129.414883)
			(xy 151.719187 -129.45359) (xy 151.843425 -129.499738) (xy 151.964711 -129.553164) (xy 152.082619 -129.613682)
			(xy 152.196735 -129.681079) (xy 152.306658 -129.755118) (xy 152.412002 -129.835538) (xy 152.512396 -129.922058)
			(xy 152.607489 -130.014373) (xy 152.696946 -130.11216) (xy 152.780453 -130.215074) (xy 152.857716 -130.322755)
			(xy 152.928465 -130.434823) (xy 152.99245 -130.550886) (xy 153.049448 -130.670536) (xy 153.099257 -130.793352)
			(xy 153.141703 -130.918903) (xy 153.176637 -131.046748) (xy 153.203935 -131.176438) (xy 153.223503 -131.307518)
			(xy 153.235272 -131.439526) (xy 153.239199 -131.572) (xy 153.237265 -131.637238) (xy 163.698184 -131.637238)
			(xy 163.698184 -131.506762) (xy 163.706062 -131.376524) (xy 163.721789 -131.246999) (xy 163.745308 -131.11866)
			(xy 163.776533 -130.991975) (xy 163.81535 -130.867407) (xy 163.861617 -130.745409) (xy 163.915165 -130.626428)
			(xy 163.9758 -130.510897) (xy 164.0433 -130.399238) (xy 164.117419 -130.291858) (xy 164.197885 -130.189148)
			(xy 164.284406 -130.091485) (xy 164.376666 -129.999224) (xy 164.474328 -129.912702) (xy 164.577037 -129.832234)
			(xy 164.684416 -129.758114) (xy 164.796074 -129.690613) (xy 164.911605 -129.629977) (xy 165.030585 -129.576427)
			(xy 165.152582 -129.530158) (xy 165.27715 -129.49134) (xy 165.403835 -129.460114) (xy 165.532173 -129.436593)
			(xy 165.661698 -129.420865) (xy 165.791936 -129.412985) (xy 165.857174 -129.412492) (xy 165.859206 -129.412492)
			(xy 165.896894 -129.412678) (xy 165.972222 -129.415344) (xy 166.009828 -129.417826) (xy 166.014116 -129.418068)
			(xy 166.022671 -129.417308) (xy 166.026846 -129.416302) (xy 166.099276 -129.397041) (xy 166.246139 -129.367074)
			(xy 166.394679 -129.347007) (xy 166.544229 -129.33693) (xy 166.619174 -129.336292) (xy 166.685441 -129.336773)
			(xy 166.817742 -129.344623) (xy 166.949345 -129.360296) (xy 167.079789 -129.383739) (xy 167.208615 -129.414868)
			(xy 167.335371 -129.453574) (xy 167.459611 -129.499721) (xy 167.580899 -129.553148) (xy 167.698809 -129.613666)
			(xy 167.812926 -129.681062) (xy 167.922851 -129.755101) (xy 168.028196 -129.835521) (xy 168.128593 -129.922042)
			(xy 168.223687 -130.014358) (xy 168.313145 -130.112145) (xy 168.396654 -130.21506) (xy 168.473919 -130.322741)
			(xy 168.544669 -130.434811) (xy 168.608655 -130.550875) (xy 168.665654 -130.670526) (xy 168.715464 -130.793343)
			(xy 168.757911 -130.918895) (xy 168.792845 -131.046742) (xy 168.820144 -131.176434) (xy 168.839713 -131.307515)
			(xy 168.851481 -131.439525) (xy 168.855409 -131.572) (xy 168.853475 -131.637238) (xy 175.890184 -131.637238)
			(xy 175.890184 -131.506762) (xy 175.898062 -131.376524) (xy 175.913789 -131.246999) (xy 175.937308 -131.11866)
			(xy 175.968533 -130.991975) (xy 176.00735 -130.867407) (xy 176.053617 -130.745409) (xy 176.107165 -130.626428)
			(xy 176.1678 -130.510897) (xy 176.2353 -130.399238) (xy 176.309419 -130.291858) (xy 176.389885 -130.189148)
			(xy 176.476406 -130.091485) (xy 176.568666 -129.999224) (xy 176.666328 -129.912702) (xy 176.769037 -129.832234)
			(xy 176.876416 -129.758114) (xy 176.988074 -129.690613) (xy 177.103605 -129.629977) (xy 177.222585 -129.576427)
			(xy 177.344582 -129.530158) (xy 177.46915 -129.49134) (xy 177.595835 -129.460114) (xy 177.724173 -129.436593)
			(xy 177.853698 -129.420865) (xy 177.983936 -129.412985) (xy 178.049174 -129.412492) (xy 178.051206 -129.412492)
			(xy 178.088894 -129.412678) (xy 178.164222 -129.415344) (xy 178.201828 -129.417826) (xy 178.206116 -129.418068)
			(xy 178.214671 -129.417308) (xy 178.218846 -129.416302) (xy 178.291276 -129.397041) (xy 178.438139 -129.367074)
			(xy 178.586679 -129.347007) (xy 178.736229 -129.33693) (xy 178.811174 -129.336292) (xy 178.877441 -129.336773)
			(xy 179.009742 -129.344623) (xy 179.141345 -129.360296) (xy 179.271789 -129.383739) (xy 179.400615 -129.414868)
			(xy 179.527371 -129.453574) (xy 179.651611 -129.499721) (xy 179.772899 -129.553148) (xy 179.890809 -129.613666)
			(xy 180.004926 -129.681062) (xy 180.114851 -129.755101) (xy 180.220196 -129.835521) (xy 180.320593 -129.922042)
			(xy 180.415687 -130.014358) (xy 180.505145 -130.112145) (xy 180.588654 -130.21506) (xy 180.665919 -130.322741)
			(xy 180.736669 -130.434811) (xy 180.800655 -130.550875) (xy 180.857654 -130.670526) (xy 180.907464 -130.793343)
			(xy 180.949911 -130.918895) (xy 180.984845 -131.046742) (xy 181.012144 -131.176434) (xy 181.031713 -131.307515)
			(xy 181.043481 -131.439525) (xy 181.047409 -131.572) (xy 181.045475 -131.637238) (xy 188.082184 -131.637238)
			(xy 188.082184 -131.506762) (xy 188.090062 -131.376524) (xy 188.105789 -131.246999) (xy 188.129308 -131.11866)
			(xy 188.160533 -130.991975) (xy 188.19935 -130.867407) (xy 188.245617 -130.745409) (xy 188.299165 -130.626428)
			(xy 188.3598 -130.510897) (xy 188.4273 -130.399238) (xy 188.501419 -130.291858) (xy 188.581885 -130.189148)
			(xy 188.668406 -130.091485) (xy 188.760666 -129.999224) (xy 188.858328 -129.912702) (xy 188.961037 -129.832234)
			(xy 189.068416 -129.758114) (xy 189.180074 -129.690613) (xy 189.295605 -129.629977) (xy 189.414585 -129.576427)
			(xy 189.536582 -129.530158) (xy 189.66115 -129.49134) (xy 189.787835 -129.460114) (xy 189.916173 -129.436593)
			(xy 190.045698 -129.420865) (xy 190.175936 -129.412985) (xy 190.241174 -129.412492) (xy 190.243206 -129.412492)
			(xy 190.280894 -129.412678) (xy 190.356222 -129.415344) (xy 190.393828 -129.417826) (xy 190.398116 -129.418068)
			(xy 190.406671 -129.417308) (xy 190.410846 -129.416302) (xy 190.483276 -129.397041) (xy 190.630139 -129.367074)
			(xy 190.778679 -129.347007) (xy 190.928229 -129.33693) (xy 191.003174 -129.336292) (xy 191.069441 -129.336773)
			(xy 191.201742 -129.344623) (xy 191.333345 -129.360296) (xy 191.463789 -129.383739) (xy 191.592615 -129.414868)
			(xy 191.719371 -129.453574) (xy 191.843611 -129.499721) (xy 191.964899 -129.553148) (xy 192.082809 -129.613666)
			(xy 192.196926 -129.681062) (xy 192.306851 -129.755101) (xy 192.412196 -129.835521) (xy 192.512593 -129.922042)
			(xy 192.607687 -130.014358) (xy 192.697145 -130.112145) (xy 192.780654 -130.21506) (xy 192.857919 -130.322741)
			(xy 192.928669 -130.434811) (xy 192.992655 -130.550875) (xy 193.049654 -130.670526) (xy 193.099464 -130.793343)
			(xy 193.141911 -130.918895) (xy 193.176845 -131.046742) (xy 193.204144 -131.176434) (xy 193.223713 -131.307515)
			(xy 193.235481 -131.439525) (xy 193.239409 -131.572) (xy 193.235481 -131.704475) (xy 193.223713 -131.836485)
			(xy 193.204144 -131.967566) (xy 193.176845 -132.097258) (xy 193.141911 -132.225105) (xy 193.099464 -132.350657)
			(xy 193.049654 -132.473474) (xy 192.992655 -132.593125) (xy 192.928669 -132.709189) (xy 192.857919 -132.821259)
			(xy 192.780654 -132.92894) (xy 192.697145 -133.031855) (xy 192.607687 -133.129642) (xy 192.512593 -133.221958)
			(xy 192.412196 -133.308479) (xy 192.306851 -133.388899) (xy 192.196926 -133.462938) (xy 192.082809 -133.530334)
			(xy 191.964899 -133.590852) (xy 191.843611 -133.644279) (xy 191.719371 -133.690426) (xy 191.592615 -133.729132)
			(xy 191.463789 -133.760261) (xy 191.333345 -133.783704) (xy 191.201742 -133.799377) (xy 191.069441 -133.807227)
			(xy 191.003174 -133.807708) (xy 190.928229 -133.807072) (xy 190.778677 -133.79701) (xy 190.630135 -133.776948)
			(xy 190.483272 -133.746976) (xy 190.410846 -133.727698) (xy 190.406672 -133.726683) (xy 190.398116 -133.725919)
			(xy 190.393828 -133.726174) (xy 190.356222 -133.728659) (xy 190.280894 -133.731327) (xy 190.243206 -133.731508)
			(xy 190.241174 -133.731508) (xy 190.175936 -133.731015) (xy 190.045698 -133.723135) (xy 189.916173 -133.707407)
			(xy 189.787835 -133.683886) (xy 189.66115 -133.65266) (xy 189.536582 -133.613842) (xy 189.414585 -133.567573)
			(xy 189.295605 -133.514023) (xy 189.180074 -133.453387) (xy 189.068416 -133.385886) (xy 188.961037 -133.311766)
			(xy 188.858328 -133.231298) (xy 188.760666 -133.144776) (xy 188.668406 -133.052515) (xy 188.581885 -132.954852)
			(xy 188.501419 -132.852142) (xy 188.4273 -132.744762) (xy 188.3598 -132.633103) (xy 188.299165 -132.517572)
			(xy 188.245617 -132.398591) (xy 188.19935 -132.276593) (xy 188.160533 -132.152025) (xy 188.129308 -132.02534)
			(xy 188.105789 -131.897001) (xy 188.090062 -131.767476) (xy 188.082184 -131.637238) (xy 181.045475 -131.637238)
			(xy 181.043481 -131.704475) (xy 181.031713 -131.836485) (xy 181.012144 -131.967566) (xy 180.984845 -132.097258)
			(xy 180.949911 -132.225105) (xy 180.907464 -132.350657) (xy 180.857654 -132.473474) (xy 180.800655 -132.593125)
			(xy 180.736669 -132.709189) (xy 180.665919 -132.821259) (xy 180.588654 -132.92894) (xy 180.505145 -133.031855)
			(xy 180.415687 -133.129642) (xy 180.320593 -133.221958) (xy 180.220196 -133.308479) (xy 180.114851 -133.388899)
			(xy 180.004926 -133.462938) (xy 179.890809 -133.530334) (xy 179.772899 -133.590852) (xy 179.651611 -133.644279)
			(xy 179.527371 -133.690426) (xy 179.400615 -133.729132) (xy 179.271789 -133.760261) (xy 179.141345 -133.783704)
			(xy 179.009742 -133.799377) (xy 178.877441 -133.807227) (xy 178.811174 -133.807708) (xy 178.736229 -133.807072)
			(xy 178.586677 -133.79701) (xy 178.438135 -133.776948) (xy 178.291272 -133.746976) (xy 178.218846 -133.727698)
			(xy 178.214672 -133.726683) (xy 178.206116 -133.725919) (xy 178.201828 -133.726174) (xy 178.164222 -133.728659)
			(xy 178.088894 -133.731327) (xy 178.051206 -133.731508) (xy 178.049174 -133.731508) (xy 177.983936 -133.731015)
			(xy 177.853698 -133.723135) (xy 177.724173 -133.707407) (xy 177.595835 -133.683886) (xy 177.46915 -133.65266)
			(xy 177.344582 -133.613842) (xy 177.222585 -133.567573) (xy 177.103605 -133.514023) (xy 176.988074 -133.453387)
			(xy 176.876416 -133.385886) (xy 176.769037 -133.311766) (xy 176.666328 -133.231298) (xy 176.568666 -133.144776)
			(xy 176.476406 -133.052515) (xy 176.389885 -132.954852) (xy 176.309419 -132.852142) (xy 176.2353 -132.744762)
			(xy 176.1678 -132.633103) (xy 176.107165 -132.517572) (xy 176.053617 -132.398591) (xy 176.00735 -132.276593)
			(xy 175.968533 -132.152025) (xy 175.937308 -132.02534) (xy 175.913789 -131.897001) (xy 175.898062 -131.767476)
			(xy 175.890184 -131.637238) (xy 168.853475 -131.637238) (xy 168.851481 -131.704475) (xy 168.839713 -131.836485)
			(xy 168.820144 -131.967566) (xy 168.792845 -132.097258) (xy 168.757911 -132.225105) (xy 168.715464 -132.350657)
			(xy 168.665654 -132.473474) (xy 168.608655 -132.593125) (xy 168.544669 -132.709189) (xy 168.473919 -132.821259)
			(xy 168.396654 -132.92894) (xy 168.313145 -133.031855) (xy 168.223687 -133.129642) (xy 168.128593 -133.221958)
			(xy 168.028196 -133.308479) (xy 167.922851 -133.388899) (xy 167.812926 -133.462938) (xy 167.698809 -133.530334)
			(xy 167.580899 -133.590852) (xy 167.459611 -133.644279) (xy 167.335371 -133.690426) (xy 167.208615 -133.729132)
			(xy 167.079789 -133.760261) (xy 166.949345 -133.783704) (xy 166.817742 -133.799377) (xy 166.685441 -133.807227)
			(xy 166.619174 -133.807708) (xy 166.544229 -133.807072) (xy 166.394677 -133.79701) (xy 166.246135 -133.776948)
			(xy 166.099272 -133.746976) (xy 166.026846 -133.727698) (xy 166.022672 -133.726683) (xy 166.014116 -133.725919)
			(xy 166.009828 -133.726174) (xy 165.972222 -133.728659) (xy 165.896894 -133.731327) (xy 165.859206 -133.731508)
			(xy 165.857174 -133.731508) (xy 165.791936 -133.731015) (xy 165.661698 -133.723135) (xy 165.532173 -133.707407)
			(xy 165.403835 -133.683886) (xy 165.27715 -133.65266) (xy 165.152582 -133.613842) (xy 165.030585 -133.567573)
			(xy 164.911605 -133.514023) (xy 164.796074 -133.453387) (xy 164.684416 -133.385886) (xy 164.577037 -133.311766)
			(xy 164.474328 -133.231298) (xy 164.376666 -133.144776) (xy 164.284406 -133.052515) (xy 164.197885 -132.954852)
			(xy 164.117419 -132.852142) (xy 164.0433 -132.744762) (xy 163.9758 -132.633103) (xy 163.915165 -132.517572)
			(xy 163.861617 -132.398591) (xy 163.81535 -132.276593) (xy 163.776533 -132.152025) (xy 163.745308 -132.02534)
			(xy 163.721789 -131.897001) (xy 163.706062 -131.767476) (xy 163.698184 -131.637238) (xy 153.237265 -131.637238)
			(xy 153.235272 -131.704474) (xy 153.223503 -131.836482) (xy 153.203935 -131.967562) (xy 153.176637 -132.097252)
			(xy 153.141703 -132.225097) (xy 153.099257 -132.350648) (xy 153.049448 -132.473464) (xy 152.99245 -132.593114)
			(xy 152.928465 -132.709177) (xy 152.857716 -132.821245) (xy 152.780453 -132.928926) (xy 152.696946 -133.03184)
			(xy 152.607489 -133.129627) (xy 152.512396 -133.221942) (xy 152.412002 -133.308462) (xy 152.306658 -133.388882)
			(xy 152.196735 -133.462921) (xy 152.082619 -133.530318) (xy 151.964711 -133.590836) (xy 151.843425 -133.644262)
			(xy 151.719187 -133.69041) (xy 151.592433 -133.729117) (xy 151.463609 -133.760247) (xy 151.333167 -133.783691)
			(xy 151.201565 -133.799366) (xy 151.069266 -133.807217) (xy 151.003 -133.807708) (xy 150.928055 -133.807089)
			(xy 150.778502 -133.797023) (xy 150.62996 -133.776956) (xy 150.483098 -133.746978) (xy 150.410672 -133.727698)
			(xy 150.406496 -133.72669) (xy 150.397942 -133.725921) (xy 150.393654 -133.726174) (xy 150.356048 -133.728662)
			(xy 150.28072 -133.731328) (xy 150.243032 -133.731508) (xy 150.241 -133.731508) (xy 150.175761 -133.731016)
			(xy 150.045522 -133.723138) (xy 149.915997 -133.70741) (xy 149.787657 -133.683891) (xy 149.660971 -133.652666)
			(xy 149.536402 -133.613849) (xy 149.414403 -133.567581) (xy 149.295421 -133.514031) (xy 149.17989 -133.453395)
			(xy 149.06823 -133.385895) (xy 148.960849 -133.311775) (xy 148.85814 -133.231308) (xy 148.760476 -133.144785)
			(xy 148.668215 -133.052524) (xy 148.581692 -132.95486) (xy 148.501225 -132.852151) (xy 148.427105 -132.74477)
			(xy 148.359605 -132.63311) (xy 148.298969 -132.517579) (xy 148.245419 -132.398597) (xy 148.199151 -132.276598)
			(xy 148.160334 -132.152029) (xy 148.129109 -132.025343) (xy 148.10559 -131.897003) (xy 148.089862 -131.767478)
			(xy 148.081984 -131.637239) (xy 141.045265 -131.637239) (xy 141.043272 -131.704474) (xy 141.031503 -131.836482)
			(xy 141.011935 -131.967562) (xy 140.984637 -132.097252) (xy 140.949703 -132.225097) (xy 140.907257 -132.350648)
			(xy 140.857448 -132.473464) (xy 140.80045 -132.593114) (xy 140.736465 -132.709177) (xy 140.665716 -132.821245)
			(xy 140.588453 -132.928926) (xy 140.504946 -133.03184) (xy 140.415489 -133.129627) (xy 140.320396 -133.221942)
			(xy 140.220002 -133.308462) (xy 140.114658 -133.388882) (xy 140.004735 -133.462921) (xy 139.890619 -133.530318)
			(xy 139.772711 -133.590836) (xy 139.651425 -133.644262) (xy 139.527187 -133.69041) (xy 139.400433 -133.729117)
			(xy 139.271609 -133.760247) (xy 139.141167 -133.783691) (xy 139.009565 -133.799366) (xy 138.877266 -133.807217)
			(xy 138.811 -133.807708) (xy 138.736055 -133.807089) (xy 138.586502 -133.797023) (xy 138.43796 -133.776956)
			(xy 138.291098 -133.746978) (xy 138.218672 -133.727698) (xy 138.214496 -133.72669) (xy 138.205942 -133.725921)
			(xy 138.201654 -133.726174) (xy 138.164048 -133.728662) (xy 138.08872 -133.731328) (xy 138.051032 -133.731508)
			(xy 138.049 -133.731508) (xy 137.983761 -133.731016) (xy 137.853522 -133.723138) (xy 137.723997 -133.70741)
			(xy 137.595657 -133.683891) (xy 137.468971 -133.652666) (xy 137.344402 -133.613849) (xy 137.222403 -133.567581)
			(xy 137.103421 -133.514031) (xy 136.98789 -133.453395) (xy 136.87623 -133.385895) (xy 136.768849 -133.311775)
			(xy 136.66614 -133.231308) (xy 136.568476 -133.144785) (xy 136.476215 -133.052524) (xy 136.389692 -132.95486)
			(xy 136.309225 -132.852151) (xy 136.235105 -132.74477) (xy 136.167605 -132.63311) (xy 136.106969 -132.517579)
			(xy 136.053419 -132.398597) (xy 136.007151 -132.276598) (xy 135.968334 -132.152029) (xy 135.937109 -132.025343)
			(xy 135.91359 -131.897003) (xy 135.897862 -131.767478) (xy 135.889984 -131.637239) (xy 128.853265 -131.637239)
			(xy 128.851272 -131.704474) (xy 128.839503 -131.836482) (xy 128.819935 -131.967562) (xy 128.792637 -132.097252)
			(xy 128.757703 -132.225097) (xy 128.715257 -132.350648) (xy 128.665448 -132.473464) (xy 128.60845 -132.593114)
			(xy 128.544465 -132.709177) (xy 128.473716 -132.821245) (xy 128.396453 -132.928926) (xy 128.312946 -133.03184)
			(xy 128.223489 -133.129627) (xy 128.128396 -133.221942) (xy 128.028002 -133.308462) (xy 127.922658 -133.388882)
			(xy 127.812735 -133.462921) (xy 127.698619 -133.530318) (xy 127.580711 -133.590836) (xy 127.459425 -133.644262)
			(xy 127.335187 -133.69041) (xy 127.208433 -133.729117) (xy 127.079609 -133.760247) (xy 126.949167 -133.783691)
			(xy 126.817565 -133.799366) (xy 126.685266 -133.807217) (xy 126.619 -133.807708) (xy 126.544055 -133.807089)
			(xy 126.394502 -133.797023) (xy 126.24596 -133.776956) (xy 126.099098 -133.746978) (xy 126.026672 -133.727698)
			(xy 126.022496 -133.72669) (xy 126.013942 -133.725921) (xy 126.009654 -133.726174) (xy 125.972048 -133.728662)
			(xy 125.89672 -133.731328) (xy 125.859032 -133.731508) (xy 125.857 -133.731508) (xy 125.791761 -133.731016)
			(xy 125.661522 -133.723138) (xy 125.531997 -133.70741) (xy 125.403657 -133.683891) (xy 125.276971 -133.652666)
			(xy 125.152402 -133.613849) (xy 125.030403 -133.567581) (xy 124.911421 -133.514031) (xy 124.79589 -133.453395)
			(xy 124.68423 -133.385895) (xy 124.576849 -133.311775) (xy 124.47414 -133.231308) (xy 124.376476 -133.144785)
			(xy 124.284215 -133.052524) (xy 124.197692 -132.95486) (xy 124.117225 -132.852151) (xy 124.043105 -132.74477)
			(xy 123.975605 -132.63311) (xy 123.914969 -132.517579) (xy 123.861419 -132.398597) (xy 123.815151 -132.276598)
			(xy 123.776334 -132.152029) (xy 123.745109 -132.025343) (xy 123.72159 -131.897003) (xy 123.705862 -131.767478)
			(xy 123.697984 -131.637239) (xy 113.237065 -131.637239) (xy 113.235072 -131.704473) (xy 113.223304 -131.83648)
			(xy 113.203736 -131.967559) (xy 113.176438 -132.097248) (xy 113.141504 -132.225092) (xy 113.099059 -132.350643)
			(xy 113.04925 -132.473458) (xy 112.992254 -132.593107) (xy 112.928269 -132.709169) (xy 112.857522 -132.821237)
			(xy 112.780259 -132.928917) (xy 112.696754 -133.031831) (xy 112.607298 -133.129618) (xy 112.512206 -133.221933)
			(xy 112.411813 -133.308453) (xy 112.306471 -133.388873) (xy 112.196549 -133.462912) (xy 112.082435 -133.530309)
			(xy 111.964528 -133.590828) (xy 111.843243 -133.644255) (xy 111.719007 -133.690404) (xy 111.592254 -133.729111)
			(xy 111.463431 -133.760242) (xy 111.33299 -133.783687) (xy 111.20139 -133.799363) (xy 111.069092 -133.807216)
			(xy 111.002826 -133.807708) (xy 110.927881 -133.807083) (xy 110.778328 -133.797018) (xy 110.629787 -133.776953)
			(xy 110.482924 -133.746977) (xy 110.410498 -133.727698) (xy 110.406321 -133.726696) (xy 110.397768 -133.725923)
			(xy 110.39348 -133.726174) (xy 110.355874 -133.728661) (xy 110.280546 -133.731328) (xy 110.242858 -133.731508)
			(xy 110.240826 -133.731508) (xy 110.175587 -133.731026) (xy 110.045346 -133.723149) (xy 109.915818 -133.707423)
			(xy 109.787477 -133.683905) (xy 109.660789 -133.652681) (xy 109.536218 -133.613864) (xy 109.414218 -133.567597)
			(xy 109.295234 -133.514048) (xy 109.1797 -133.453412) (xy 109.068038 -133.385912) (xy 108.960656 -133.311792)
			(xy 108.857945 -133.231324) (xy 108.760279 -133.144801) (xy 108.668016 -133.05254) (xy 108.581493 -132.954875)
			(xy 108.501023 -132.852165) (xy 108.426902 -132.744783) (xy 108.3594 -132.633123) (xy 108.298764 -132.51759)
			(xy 108.245213 -132.398606) (xy 108.198944 -132.276607) (xy 108.160126 -132.152036) (xy 108.1289 -132.025349)
			(xy 108.105381 -131.897007) (xy 108.089653 -131.76748) (xy 108.081775 -131.637239) (xy 101.045065 -131.637239)
			(xy 101.043072 -131.704473) (xy 101.031304 -131.83648) (xy 101.011736 -131.967559) (xy 100.984438 -132.097248)
			(xy 100.949504 -132.225092) (xy 100.907059 -132.350643) (xy 100.85725 -132.473458) (xy 100.800254 -132.593107)
			(xy 100.736269 -132.709169) (xy 100.665522 -132.821237) (xy 100.588259 -132.928917) (xy 100.504754 -133.031831)
			(xy 100.415298 -133.129618) (xy 100.320206 -133.221933) (xy 100.219813 -133.308453) (xy 100.114471 -133.388873)
			(xy 100.004549 -133.462912) (xy 99.890435 -133.530309) (xy 99.772528 -133.590828) (xy 99.651243 -133.644255)
			(xy 99.527007 -133.690404) (xy 99.400254 -133.729111) (xy 99.271431 -133.760242) (xy 99.14099 -133.783687)
			(xy 99.00939 -133.799363) (xy 98.877092 -133.807216) (xy 98.810826 -133.807708) (xy 98.735881 -133.807083)
			(xy 98.586328 -133.797018) (xy 98.437787 -133.776953) (xy 98.290924 -133.746977) (xy 98.218498 -133.727698)
			(xy 98.214321 -133.726696) (xy 98.205768 -133.725923) (xy 98.20148 -133.726174) (xy 98.163874 -133.728661)
			(xy 98.088546 -133.731328) (xy 98.050858 -133.731508) (xy 98.048826 -133.731508) (xy 97.983587 -133.731026)
			(xy 97.853346 -133.723149) (xy 97.723818 -133.707423) (xy 97.595477 -133.683905) (xy 97.468789 -133.652681)
			(xy 97.344218 -133.613864) (xy 97.222218 -133.567597) (xy 97.103234 -133.514048) (xy 96.9877 -133.453412)
			(xy 96.876038 -133.385912) (xy 96.768656 -133.311792) (xy 96.665945 -133.231324) (xy 96.568279 -133.144801)
			(xy 96.476016 -133.05254) (xy 96.389493 -132.954875) (xy 96.309023 -132.852165) (xy 96.234902 -132.744783)
			(xy 96.1674 -132.633123) (xy 96.106764 -132.51759) (xy 96.053213 -132.398606) (xy 96.006944 -132.276607)
			(xy 95.968126 -132.152036) (xy 95.9369 -132.025349) (xy 95.913381 -131.897007) (xy 95.897653 -131.76748)
			(xy 95.889775 -131.637239) (xy 88.853065 -131.637239) (xy 88.851072 -131.704473) (xy 88.839304 -131.83648)
			(xy 88.819736 -131.967559) (xy 88.792438 -132.097248) (xy 88.757504 -132.225092) (xy 88.715059 -132.350643)
			(xy 88.66525 -132.473458) (xy 88.608254 -132.593107) (xy 88.544269 -132.709169) (xy 88.473522 -132.821237)
			(xy 88.396259 -132.928917) (xy 88.312754 -133.031831) (xy 88.223298 -133.129618) (xy 88.128206 -133.221933)
			(xy 88.027813 -133.308453) (xy 87.922471 -133.388873) (xy 87.812549 -133.462912) (xy 87.698435 -133.530309)
			(xy 87.580528 -133.590828) (xy 87.459243 -133.644255) (xy 87.335007 -133.690404) (xy 87.208254 -133.729111)
			(xy 87.079431 -133.760242) (xy 86.94899 -133.783687) (xy 86.81739 -133.799363) (xy 86.685092 -133.807216)
			(xy 86.618826 -133.807708) (xy 86.543881 -133.807083) (xy 86.394328 -133.797018) (xy 86.245787 -133.776953)
			(xy 86.098924 -133.746977) (xy 86.026498 -133.727698) (xy 86.022321 -133.726696) (xy 86.013768 -133.725923)
			(xy 86.00948 -133.726174) (xy 85.971874 -133.728661) (xy 85.896546 -133.731328) (xy 85.858858 -133.731508)
			(xy 85.856826 -133.731508) (xy 85.791587 -133.731026) (xy 85.661346 -133.723149) (xy 85.531818 -133.707423)
			(xy 85.403477 -133.683905) (xy 85.276789 -133.652681) (xy 85.152218 -133.613864) (xy 85.030218 -133.567597)
			(xy 84.911234 -133.514048) (xy 84.7957 -133.453412) (xy 84.684038 -133.385912) (xy 84.576656 -133.311792)
			(xy 84.473945 -133.231324) (xy 84.376279 -133.144801) (xy 84.284016 -133.05254) (xy 84.197493 -132.954875)
			(xy 84.117023 -132.852165) (xy 84.042902 -132.744783) (xy 83.9754 -132.633123) (xy 83.914764 -132.51759)
			(xy 83.861213 -132.398606) (xy 83.814944 -132.276607) (xy 83.776126 -132.152036) (xy 83.7449 -132.025349)
			(xy 83.721381 -131.897007) (xy 83.705653 -131.76748) (xy 83.697775 -131.637239) (xy 73.237165 -131.637239)
			(xy 73.235172 -131.704474) (xy 73.223403 -131.836482) (xy 73.203836 -131.967561) (xy 73.176537 -132.097251)
			(xy 73.141603 -132.225096) (xy 73.099157 -132.350647) (xy 73.049348 -132.473463) (xy 72.992351 -132.593112)
			(xy 72.928366 -132.709175) (xy 72.857617 -132.821243) (xy 72.780354 -132.928924) (xy 72.696848 -133.031838)
			(xy 72.607391 -133.129625) (xy 72.512299 -133.22194) (xy 72.411904 -133.30846) (xy 72.306561 -133.38888)
			(xy 72.196639 -133.462919) (xy 72.082523 -133.530316) (xy 71.964615 -133.590834) (xy 71.843329 -133.644261)
			(xy 71.719092 -133.690409) (xy 71.592338 -133.729116) (xy 71.463514 -133.760246) (xy 71.333072 -133.78369)
			(xy 71.201471 -133.799365) (xy 71.069172 -133.807217) (xy 71.002906 -133.807708) (xy 70.927961 -133.807087)
			(xy 70.778408 -133.797022) (xy 70.629866 -133.776955) (xy 70.483004 -133.746978) (xy 70.410578 -133.727698)
			(xy 70.406402 -133.726691) (xy 70.397848 -133.725922) (xy 70.39356 -133.726174) (xy 70.355954 -133.728662)
			(xy 70.280626 -133.731328) (xy 70.242938 -133.731508) (xy 70.240906 -133.731508) (xy 70.175667 -133.731025)
			(xy 70.045427 -133.723148) (xy 69.9159 -133.70742) (xy 69.78756 -133.683901) (xy 69.660873 -133.652676)
			(xy 69.536303 -133.613859) (xy 69.414304 -133.567591) (xy 69.295321 -133.514042) (xy 69.179788 -133.453406)
			(xy 69.068128 -133.385905) (xy 68.960746 -133.311785) (xy 68.858036 -133.231317) (xy 68.760372 -133.144794)
			(xy 68.66811 -133.052533) (xy 68.581587 -132.954868) (xy 68.501119 -132.852159) (xy 68.426998 -132.744777)
			(xy 68.359497 -132.633117) (xy 68.298861 -132.517584) (xy 68.245311 -132.398602) (xy 68.199043 -132.276603)
			(xy 68.160225 -132.152033) (xy 68.129 -132.025346) (xy 68.10548 -131.897005) (xy 68.089753 -131.767479)
			(xy 68.081875 -131.637239) (xy 61.045165 -131.637239) (xy 61.043172 -131.704474) (xy 61.031403 -131.836482)
			(xy 61.011836 -131.967561) (xy 60.984537 -132.097251) (xy 60.949603 -132.225096) (xy 60.907157 -132.350647)
			(xy 60.857348 -132.473463) (xy 60.800351 -132.593112) (xy 60.736366 -132.709175) (xy 60.665617 -132.821243)
			(xy 60.588354 -132.928924) (xy 60.504848 -133.031838) (xy 60.415391 -133.129625) (xy 60.320299 -133.22194)
			(xy 60.219904 -133.30846) (xy 60.114561 -133.38888) (xy 60.004639 -133.462919) (xy 59.890523 -133.530316)
			(xy 59.772615 -133.590834) (xy 59.651329 -133.644261) (xy 59.527092 -133.690409) (xy 59.400338 -133.729116)
			(xy 59.271514 -133.760246) (xy 59.141072 -133.78369) (xy 59.009471 -133.799365) (xy 58.877172 -133.807217)
			(xy 58.810906 -133.807708) (xy 58.735961 -133.807087) (xy 58.586408 -133.797022) (xy 58.437866 -133.776955)
			(xy 58.291004 -133.746978) (xy 58.218578 -133.727698) (xy 58.214402 -133.726691) (xy 58.205848 -133.725922)
			(xy 58.20156 -133.726174) (xy 58.163954 -133.728662) (xy 58.088626 -133.731328) (xy 58.050938 -133.731508)
			(xy 58.048906 -133.731508) (xy 57.983667 -133.731025) (xy 57.853427 -133.723148) (xy 57.7239 -133.70742)
			(xy 57.59556 -133.683901) (xy 57.468873 -133.652676) (xy 57.344303 -133.613859) (xy 57.222304 -133.567591)
			(xy 57.103321 -133.514042) (xy 56.987788 -133.453406) (xy 56.876128 -133.385905) (xy 56.768746 -133.311785)
			(xy 56.666036 -133.231317) (xy 56.568372 -133.144794) (xy 56.47611 -133.052533) (xy 56.389587 -132.954868)
			(xy 56.309119 -132.852159) (xy 56.234998 -132.744777) (xy 56.167497 -132.633117) (xy 56.106861 -132.517584)
			(xy 56.053311 -132.398602) (xy 56.007043 -132.276603) (xy 55.968225 -132.152033) (xy 55.937 -132.025346)
			(xy 55.91348 -131.897005) (xy 55.897753 -131.767479) (xy 55.889875 -131.637239) (xy 48.853165 -131.637239)
			(xy 48.851172 -131.704474) (xy 48.839403 -131.836482) (xy 48.819836 -131.967561) (xy 48.792537 -132.097251)
			(xy 48.757603 -132.225096) (xy 48.715157 -132.350647) (xy 48.665348 -132.473463) (xy 48.608351 -132.593112)
			(xy 48.544366 -132.709175) (xy 48.473617 -132.821243) (xy 48.396354 -132.928924) (xy 48.312848 -133.031838)
			(xy 48.223391 -133.129625) (xy 48.128299 -133.22194) (xy 48.027904 -133.30846) (xy 47.922561 -133.38888)
			(xy 47.812639 -133.462919) (xy 47.698523 -133.530316) (xy 47.580615 -133.590834) (xy 47.459329 -133.644261)
			(xy 47.335092 -133.690409) (xy 47.208338 -133.729116) (xy 47.079514 -133.760246) (xy 46.949072 -133.78369)
			(xy 46.817471 -133.799365) (xy 46.685172 -133.807217) (xy 46.618906 -133.807708) (xy 46.543961 -133.807087)
			(xy 46.394408 -133.797022) (xy 46.245866 -133.776955) (xy 46.099004 -133.746978) (xy 46.026578 -133.727698)
			(xy 46.022402 -133.726691) (xy 46.013848 -133.725922) (xy 46.00956 -133.726174) (xy 45.971954 -133.728662)
			(xy 45.896626 -133.731328) (xy 45.858938 -133.731508) (xy 45.856906 -133.731508) (xy 45.791667 -133.731025)
			(xy 45.661427 -133.723148) (xy 45.5319 -133.70742) (xy 45.40356 -133.683901) (xy 45.276873 -133.652676)
			(xy 45.152303 -133.613859) (xy 45.030304 -133.567591) (xy 44.911321 -133.514042) (xy 44.795788 -133.453406)
			(xy 44.684128 -133.385905) (xy 44.576746 -133.311785) (xy 44.474036 -133.231317) (xy 44.376372 -133.144794)
			(xy 44.28411 -133.052533) (xy 44.197587 -132.954868) (xy 44.117119 -132.852159) (xy 44.042998 -132.744777)
			(xy 43.975497 -132.633117) (xy 43.914861 -132.517584) (xy 43.861311 -132.398602) (xy 43.815043 -132.276603)
			(xy 43.776225 -132.152033) (xy 43.745 -132.025346) (xy 43.72148 -131.897005) (xy 43.705753 -131.767479)
			(xy 43.697875 -131.637239) (xy 37.531802 -131.637239) (xy 37.531802 -137.693908) (xy 41.132252 -137.693908)
			(xy 41.132252 -136.1186) (xy 41.132834 -136.101909) (xy 41.141461 -136.069662) (xy 41.15813 -136.040741)
			(xy 41.181706 -136.017109) (xy 41.21059 -136.000374) (xy 41.242817 -135.991673) (xy 41.259506 -135.991092)
			(xy 42.834306 -135.991092) (xy 42.850971 -135.991583) (xy 42.883166 -136.000201) (xy 42.912039 -136.016851)
			(xy 42.935625 -136.0404) (xy 42.952321 -136.069246) (xy 42.960991 -136.101428) (xy 42.96156 -136.118092)
			(xy 42.96156 -136.906) (xy 44.353486 -136.906) (xy 44.357505 -136.758915) (xy 44.36955 -136.612269)
			(xy 44.389585 -136.466499) (xy 44.417551 -136.322042) (xy 44.453364 -136.179327) (xy 44.496918 -136.03878)
			(xy 44.548081 -135.900822) (xy 44.606702 -135.765863) (xy 44.672605 -135.634308) (xy 44.745594 -135.506547)
			(xy 44.825451 -135.382963) (xy 44.911938 -135.263924) (xy 45.004796 -135.149786) (xy 45.103748 -135.040889)
			(xy 45.2085 -134.937559) (xy 45.318738 -134.840103) (xy 45.434134 -134.748812) (xy 45.554343 -134.663959)
			(xy 45.679006 -134.585798) (xy 45.807752 -134.514561) (xy 45.940196 -134.45046) (xy 46.075942 -134.393689)
			(xy 46.214586 -134.344414) (xy 46.355715 -134.302785) (xy 46.498905 -134.268925) (xy 46.643732 -134.242934)
			(xy 46.789761 -134.224892) (xy 46.936558 -134.21485) (xy 47.083684 -134.212841) (xy 47.230701 -134.218868)
			(xy 47.377169 -134.232916) (xy 47.522651 -134.25494) (xy 47.666713 -134.284877) (xy 47.808926 -134.322636)
			(xy 47.948864 -134.368105) (xy 48.086111 -134.421147) (xy 48.220256 -134.481606) (xy 48.350899 -134.5493)
			(xy 48.477651 -134.624027) (xy 48.600133 -134.705565) (xy 48.717979 -134.793669) (xy 48.830838 -134.888078)
			(xy 48.938373 -134.988509) (xy 49.040264 -135.094662) (xy 49.136205 -135.206221) (xy 49.225911 -135.322853)
			(xy 49.309114 -135.44421) (xy 49.385565 -135.569929) (xy 49.455037 -135.699635) (xy 49.517323 -135.832942)
			(xy 49.572235 -135.969452) (xy 49.619611 -136.108756) (xy 49.659309 -136.250439) (xy 49.69121 -136.39408)
			(xy 49.71522 -136.539247) (xy 49.731266 -136.68551) (xy 49.739302 -136.83243) (xy 49.739804 -136.906)
			(xy 49.739302 -136.97957) (xy 49.731266 -137.12649) (xy 49.71522 -137.272753) (xy 49.69121 -137.41792)
			(xy 49.659309 -137.561561) (xy 49.622227 -137.693908) (xy 53.324252 -137.693908) (xy 53.324252 -136.1186)
			(xy 53.324834 -136.101909) (xy 53.333461 -136.069662) (xy 53.35013 -136.040741) (xy 53.373706 -136.017109)
			(xy 53.40259 -136.000374) (xy 53.434817 -135.991673) (xy 53.451506 -135.991092) (xy 55.026306 -135.991092)
			(xy 55.042971 -135.991583) (xy 55.075166 -136.000201) (xy 55.104039 -136.016851) (xy 55.127625 -136.0404)
			(xy 55.144321 -136.069246) (xy 55.152991 -136.101428) (xy 55.15356 -136.118092) (xy 55.15356 -136.906)
			(xy 56.545486 -136.906) (xy 56.549505 -136.758915) (xy 56.56155 -136.612269) (xy 56.581585 -136.466499)
			(xy 56.609551 -136.322042) (xy 56.645364 -136.179327) (xy 56.688918 -136.03878) (xy 56.740081 -135.900822)
			(xy 56.798702 -135.765863) (xy 56.864605 -135.634308) (xy 56.937594 -135.506547) (xy 57.017451 -135.382963)
			(xy 57.103938 -135.263924) (xy 57.196796 -135.149786) (xy 57.295748 -135.040889) (xy 57.4005 -134.937559)
			(xy 57.510738 -134.840103) (xy 57.626134 -134.748812) (xy 57.746343 -134.663959) (xy 57.871006 -134.585798)
			(xy 57.999752 -134.514561) (xy 58.132196 -134.45046) (xy 58.267942 -134.393689) (xy 58.406586 -134.344414)
			(xy 58.547715 -134.302785) (xy 58.690905 -134.268925) (xy 58.835732 -134.242934) (xy 58.981761 -134.224892)
			(xy 59.128558 -134.21485) (xy 59.275684 -134.212841) (xy 59.422701 -134.218868) (xy 59.569169 -134.232916)
			(xy 59.714651 -134.25494) (xy 59.858713 -134.284877) (xy 60.000926 -134.322636) (xy 60.140864 -134.368105)
			(xy 60.278111 -134.421147) (xy 60.412256 -134.481606) (xy 60.542899 -134.5493) (xy 60.669651 -134.624027)
			(xy 60.792133 -134.705565) (xy 60.909979 -134.793669) (xy 61.022838 -134.888078) (xy 61.130373 -134.988509)
			(xy 61.232264 -135.094662) (xy 61.328205 -135.206221) (xy 61.417911 -135.322853) (xy 61.501114 -135.44421)
			(xy 61.577565 -135.569929) (xy 61.647037 -135.699635) (xy 61.709323 -135.832942) (xy 61.764235 -135.969452)
			(xy 61.811611 -136.108756) (xy 61.851309 -136.250439) (xy 61.88321 -136.39408) (xy 61.90722 -136.539247)
			(xy 61.923266 -136.68551) (xy 61.931302 -136.83243) (xy 61.931804 -136.906) (xy 61.931302 -136.97957)
			(xy 61.923266 -137.12649) (xy 61.90722 -137.272753) (xy 61.88321 -137.41792) (xy 61.851309 -137.561561)
			(xy 61.814227 -137.693908) (xy 65.516252 -137.693908) (xy 65.516252 -136.1186) (xy 65.516834 -136.101909)
			(xy 65.525461 -136.069662) (xy 65.54213 -136.040741) (xy 65.565706 -136.017109) (xy 65.59459 -136.000374)
			(xy 65.626817 -135.991673) (xy 65.643506 -135.991092) (xy 67.218306 -135.991092) (xy 67.234971 -135.991583)
			(xy 67.267166 -136.000201) (xy 67.296039 -136.016851) (xy 67.319625 -136.0404) (xy 67.336321 -136.069246)
			(xy 67.344991 -136.101428) (xy 67.34556 -136.118092) (xy 67.34556 -136.906) (xy 68.737486 -136.906)
			(xy 68.741505 -136.758915) (xy 68.75355 -136.612269) (xy 68.773585 -136.466499) (xy 68.801551 -136.322042)
			(xy 68.837364 -136.179327) (xy 68.880918 -136.03878) (xy 68.932081 -135.900822) (xy 68.990702 -135.765863)
			(xy 69.056605 -135.634308) (xy 69.129594 -135.506547) (xy 69.209451 -135.382963) (xy 69.295938 -135.263924)
			(xy 69.388796 -135.149786) (xy 69.487748 -135.040889) (xy 69.5925 -134.937559) (xy 69.702738 -134.840103)
			(xy 69.818134 -134.748812) (xy 69.938343 -134.663959) (xy 70.063006 -134.585798) (xy 70.191752 -134.514561)
			(xy 70.324196 -134.45046) (xy 70.459942 -134.393689) (xy 70.598586 -134.344414) (xy 70.739715 -134.302785)
			(xy 70.882905 -134.268925) (xy 71.027732 -134.242934) (xy 71.173761 -134.224892) (xy 71.320558 -134.21485)
			(xy 71.467684 -134.212841) (xy 71.614701 -134.218868) (xy 71.761169 -134.232916) (xy 71.906651 -134.25494)
			(xy 72.050713 -134.284877) (xy 72.192926 -134.322636) (xy 72.332864 -134.368105) (xy 72.470111 -134.421147)
			(xy 72.604256 -134.481606) (xy 72.734899 -134.5493) (xy 72.861651 -134.624027) (xy 72.984133 -134.705565)
			(xy 73.101979 -134.793669) (xy 73.214838 -134.888078) (xy 73.322373 -134.988509) (xy 73.424264 -135.094662)
			(xy 73.520205 -135.206221) (xy 73.609911 -135.322853) (xy 73.693114 -135.44421) (xy 73.769565 -135.569929)
			(xy 73.839037 -135.699635) (xy 73.901323 -135.832942) (xy 73.956235 -135.969452) (xy 74.003611 -136.108756)
			(xy 74.043309 -136.250439) (xy 74.07521 -136.39408) (xy 74.09922 -136.539247) (xy 74.115266 -136.68551)
			(xy 74.123302 -136.83243) (xy 74.123804 -136.906) (xy 74.123302 -136.97957) (xy 74.115266 -137.12649)
			(xy 74.09922 -137.272753) (xy 74.07521 -137.41792) (xy 74.043309 -137.561561) (xy 74.006227 -137.693908)
			(xy 81.132172 -137.693908) (xy 81.132172 -136.1186) (xy 81.132734 -136.101908) (xy 81.141363 -136.069658)
			(xy 81.158035 -136.040734) (xy 81.181616 -136.017102) (xy 81.210504 -136.000369) (xy 81.242735 -135.99167)
			(xy 81.259426 -135.991092) (xy 82.834226 -135.991092) (xy 82.850892 -135.991565) (xy 82.883088 -136.000189)
			(xy 82.91196 -136.016843) (xy 82.935546 -136.040395) (xy 82.952241 -136.069243) (xy 82.960911 -136.101427)
			(xy 82.96148 -136.118092) (xy 82.96148 -136.906) (xy 84.353406 -136.906) (xy 84.357425 -136.758915)
			(xy 84.36947 -136.612269) (xy 84.389505 -136.466499) (xy 84.417471 -136.322042) (xy 84.453284 -136.179327)
			(xy 84.496838 -136.03878) (xy 84.548001 -135.900822) (xy 84.606622 -135.765863) (xy 84.672525 -135.634308)
			(xy 84.745514 -135.506547) (xy 84.825371 -135.382963) (xy 84.911858 -135.263924) (xy 85.004716 -135.149786)
			(xy 85.103668 -135.040889) (xy 85.20842 -134.937559) (xy 85.318658 -134.840103) (xy 85.434054 -134.748812)
			(xy 85.554263 -134.663959) (xy 85.678926 -134.585798) (xy 85.807672 -134.514561) (xy 85.940116 -134.45046)
			(xy 86.075862 -134.393689) (xy 86.214506 -134.344414) (xy 86.355635 -134.302785) (xy 86.498825 -134.268925)
			(xy 86.643652 -134.242934) (xy 86.789681 -134.224892) (xy 86.936478 -134.21485) (xy 87.083604 -134.212841)
			(xy 87.230621 -134.218868) (xy 87.377089 -134.232916) (xy 87.522571 -134.25494) (xy 87.666633 -134.284877)
			(xy 87.808846 -134.322636) (xy 87.948784 -134.368105) (xy 88.086031 -134.421147) (xy 88.220176 -134.481606)
			(xy 88.350819 -134.5493) (xy 88.477571 -134.624027) (xy 88.600053 -134.705565) (xy 88.717899 -134.793669)
			(xy 88.830758 -134.888078) (xy 88.938293 -134.988509) (xy 89.040184 -135.094662) (xy 89.136125 -135.206221)
			(xy 89.225831 -135.322853) (xy 89.309034 -135.44421) (xy 89.385485 -135.569929) (xy 89.454957 -135.699635)
			(xy 89.517243 -135.832942) (xy 89.572155 -135.969452) (xy 89.619531 -136.108756) (xy 89.659229 -136.250439)
			(xy 89.69113 -136.39408) (xy 89.71514 -136.539247) (xy 89.731186 -136.68551) (xy 89.739222 -136.83243)
			(xy 89.739724 -136.906) (xy 89.739222 -136.97957) (xy 89.731186 -137.12649) (xy 89.71514 -137.272753)
			(xy 89.69113 -137.41792) (xy 89.659229 -137.561561) (xy 89.622147 -137.693908) (xy 93.324172 -137.693908)
			(xy 93.324172 -136.1186) (xy 93.324734 -136.101908) (xy 93.333363 -136.069658) (xy 93.350035 -136.040734)
			(xy 93.373616 -136.017102) (xy 93.402504 -136.000369) (xy 93.434735 -135.99167) (xy 93.451426 -135.991092)
			(xy 95.026226 -135.991092) (xy 95.042892 -135.991565) (xy 95.075088 -136.000189) (xy 95.10396 -136.016843)
			(xy 95.127546 -136.040395) (xy 95.144241 -136.069243) (xy 95.152911 -136.101427) (xy 95.15348 -136.118092)
			(xy 95.15348 -136.906) (xy 96.545406 -136.906) (xy 96.549425 -136.758915) (xy 96.56147 -136.612269)
			(xy 96.581505 -136.466499) (xy 96.609471 -136.322042) (xy 96.645284 -136.179327) (xy 96.688838 -136.03878)
			(xy 96.740001 -135.900822) (xy 96.798622 -135.765863) (xy 96.864525 -135.634308) (xy 96.937514 -135.506547)
			(xy 97.017371 -135.382963) (xy 97.103858 -135.263924) (xy 97.196716 -135.149786) (xy 97.295668 -135.040889)
			(xy 97.40042 -134.937559) (xy 97.510658 -134.840103) (xy 97.626054 -134.748812) (xy 97.746263 -134.663959)
			(xy 97.870926 -134.585798) (xy 97.999672 -134.514561) (xy 98.132116 -134.45046) (xy 98.267862 -134.393689)
			(xy 98.406506 -134.344414) (xy 98.547635 -134.302785) (xy 98.690825 -134.268925) (xy 98.835652 -134.242934)
			(xy 98.981681 -134.224892) (xy 99.128478 -134.21485) (xy 99.275604 -134.212841) (xy 99.422621 -134.218868)
			(xy 99.569089 -134.232916) (xy 99.714571 -134.25494) (xy 99.858633 -134.284877) (xy 100.000846 -134.322636)
			(xy 100.140784 -134.368105) (xy 100.278031 -134.421147) (xy 100.412176 -134.481606) (xy 100.542819 -134.5493)
			(xy 100.669571 -134.624027) (xy 100.792053 -134.705565) (xy 100.909899 -134.793669) (xy 101.022758 -134.888078)
			(xy 101.130293 -134.988509) (xy 101.232184 -135.094662) (xy 101.328125 -135.206221) (xy 101.417831 -135.322853)
			(xy 101.501034 -135.44421) (xy 101.577485 -135.569929) (xy 101.646957 -135.699635) (xy 101.709243 -135.832942)
			(xy 101.764155 -135.969452) (xy 101.811531 -136.108756) (xy 101.851229 -136.250439) (xy 101.88313 -136.39408)
			(xy 101.90714 -136.539247) (xy 101.923186 -136.68551) (xy 101.931222 -136.83243) (xy 101.931724 -136.906)
			(xy 101.931222 -136.97957) (xy 101.923186 -137.12649) (xy 101.90714 -137.272753) (xy 101.88313 -137.41792)
			(xy 101.851229 -137.561561) (xy 101.814147 -137.693908) (xy 105.516172 -137.693908) (xy 105.516172 -136.1186)
			(xy 105.516734 -136.101908) (xy 105.525363 -136.069658) (xy 105.542035 -136.040734) (xy 105.565616 -136.017102)
			(xy 105.594504 -136.000369) (xy 105.626735 -135.99167) (xy 105.643426 -135.991092) (xy 107.218226 -135.991092)
			(xy 107.234892 -135.991565) (xy 107.267088 -136.000189) (xy 107.29596 -136.016843) (xy 107.319546 -136.040395)
			(xy 107.336241 -136.069243) (xy 107.344911 -136.101427) (xy 107.34548 -136.118092) (xy 107.34548 -136.906)
			(xy 108.737406 -136.906) (xy 108.741425 -136.758915) (xy 108.75347 -136.612269) (xy 108.773505 -136.466499)
			(xy 108.801471 -136.322042) (xy 108.837284 -136.179327) (xy 108.880838 -136.03878) (xy 108.932001 -135.900822)
			(xy 108.990622 -135.765863) (xy 109.056525 -135.634308) (xy 109.129514 -135.506547) (xy 109.209371 -135.382963)
			(xy 109.295858 -135.263924) (xy 109.388716 -135.149786) (xy 109.487668 -135.040889) (xy 109.59242 -134.937559)
			(xy 109.702658 -134.840103) (xy 109.818054 -134.748812) (xy 109.938263 -134.663959) (xy 110.062926 -134.585798)
			(xy 110.191672 -134.514561) (xy 110.324116 -134.45046) (xy 110.459862 -134.393689) (xy 110.598506 -134.344414)
			(xy 110.739635 -134.302785) (xy 110.882825 -134.268925) (xy 111.027652 -134.242934) (xy 111.173681 -134.224892)
			(xy 111.320478 -134.21485) (xy 111.467604 -134.212841) (xy 111.614621 -134.218868) (xy 111.761089 -134.232916)
			(xy 111.906571 -134.25494) (xy 112.050633 -134.284877) (xy 112.192846 -134.322636) (xy 112.332784 -134.368105)
			(xy 112.470031 -134.421147) (xy 112.604176 -134.481606) (xy 112.734819 -134.5493) (xy 112.861571 -134.624027)
			(xy 112.984053 -134.705565) (xy 113.101899 -134.793669) (xy 113.214758 -134.888078) (xy 113.322293 -134.988509)
			(xy 113.424184 -135.094662) (xy 113.520125 -135.206221) (xy 113.609831 -135.322853) (xy 113.693034 -135.44421)
			(xy 113.769485 -135.569929) (xy 113.838957 -135.699635) (xy 113.901243 -135.832942) (xy 113.956155 -135.969452)
			(xy 114.003531 -136.108756) (xy 114.043229 -136.250439) (xy 114.07513 -136.39408) (xy 114.09914 -136.539247)
			(xy 114.115186 -136.68551) (xy 114.123222 -136.83243) (xy 114.123724 -136.906) (xy 114.123222 -136.97957)
			(xy 114.115186 -137.12649) (xy 114.09914 -137.272753) (xy 114.07513 -137.41792) (xy 114.043229 -137.561561)
			(xy 114.006289 -137.6934) (xy 121.132092 -137.6934) (xy 121.132092 -136.1186) (xy 121.132638 -136.101885)
			(xy 121.14129 -136.069594) (xy 121.158005 -136.040643) (xy 121.181643 -136.017005) (xy 121.210594 -136.00029)
			(xy 121.242885 -135.991638) (xy 121.2596 -135.991092) (xy 122.8344 -135.991092) (xy 122.851115 -135.991638)
			(xy 122.883406 -136.00029) (xy 122.912357 -136.017005) (xy 122.935995 -136.040643) (xy 122.95271 -136.069594)
			(xy 122.961362 -136.101885) (xy 122.961908 -136.1186) (xy 122.961908 -136.906) (xy 124.35358 -136.906)
			(xy 124.357599 -136.758915) (xy 124.369644 -136.612269) (xy 124.389679 -136.466499) (xy 124.417645 -136.322042)
			(xy 124.453458 -136.179327) (xy 124.497012 -136.03878) (xy 124.548175 -135.900822) (xy 124.606796 -135.765863)
			(xy 124.672699 -135.634308) (xy 124.745688 -135.506547) (xy 124.825545 -135.382963) (xy 124.912032 -135.263924)
			(xy 125.00489 -135.149786) (xy 125.103842 -135.040889) (xy 125.208594 -134.937559) (xy 125.318832 -134.840103)
			(xy 125.434228 -134.748812) (xy 125.554437 -134.663959) (xy 125.6791 -134.585798) (xy 125.807846 -134.514561)
			(xy 125.94029 -134.45046) (xy 126.076036 -134.393689) (xy 126.21468 -134.344414) (xy 126.355809 -134.302785)
			(xy 126.498999 -134.268925) (xy 126.643826 -134.242934) (xy 126.789855 -134.224892) (xy 126.936652 -134.21485)
			(xy 127.083778 -134.212841) (xy 127.230795 -134.218868) (xy 127.377263 -134.232916) (xy 127.522745 -134.25494)
			(xy 127.666807 -134.284877) (xy 127.80902 -134.322636) (xy 127.948958 -134.368105) (xy 128.086205 -134.421147)
			(xy 128.22035 -134.481606) (xy 128.350993 -134.5493) (xy 128.477745 -134.624027) (xy 128.600227 -134.705565)
			(xy 128.718073 -134.793669) (xy 128.830932 -134.888078) (xy 128.938467 -134.988509) (xy 129.040358 -135.094662)
			(xy 129.136299 -135.206221) (xy 129.226005 -135.322853) (xy 129.309208 -135.44421) (xy 129.385659 -135.569929)
			(xy 129.455131 -135.699635) (xy 129.517417 -135.832942) (xy 129.572329 -135.969452) (xy 129.619705 -136.108756)
			(xy 129.659403 -136.250439) (xy 129.691304 -136.39408) (xy 129.715314 -136.539247) (xy 129.73136 -136.68551)
			(xy 129.739396 -136.83243) (xy 129.739898 -136.906) (xy 129.739396 -136.97957) (xy 129.73136 -137.12649)
			(xy 129.715314 -137.272753) (xy 129.691304 -137.41792) (xy 129.659403 -137.561561) (xy 129.622463 -137.6934)
			(xy 133.324092 -137.6934) (xy 133.324092 -136.1186) (xy 133.324638 -136.101885) (xy 133.33329 -136.069594)
			(xy 133.350005 -136.040643) (xy 133.373643 -136.017005) (xy 133.402594 -136.00029) (xy 133.434885 -135.991638)
			(xy 133.4516 -135.991092) (xy 135.0264 -135.991092) (xy 135.043115 -135.991638) (xy 135.075406 -136.00029)
			(xy 135.104357 -136.017005) (xy 135.127995 -136.040643) (xy 135.14471 -136.069594) (xy 135.153362 -136.101885)
			(xy 135.153908 -136.1186) (xy 135.153908 -136.906) (xy 136.54558 -136.906) (xy 136.549599 -136.758915)
			(xy 136.561644 -136.612269) (xy 136.581679 -136.466499) (xy 136.609645 -136.322042) (xy 136.645458 -136.179327)
			(xy 136.689012 -136.03878) (xy 136.740175 -135.900822) (xy 136.798796 -135.765863) (xy 136.864699 -135.634308)
			(xy 136.937688 -135.506547) (xy 137.017545 -135.382963) (xy 137.104032 -135.263924) (xy 137.19689 -135.149786)
			(xy 137.295842 -135.040889) (xy 137.400594 -134.937559) (xy 137.510832 -134.840103) (xy 137.626228 -134.748812)
			(xy 137.746437 -134.663959) (xy 137.8711 -134.585798) (xy 137.999846 -134.514561) (xy 138.13229 -134.45046)
			(xy 138.268036 -134.393689) (xy 138.40668 -134.344414) (xy 138.547809 -134.302785) (xy 138.690999 -134.268925)
			(xy 138.835826 -134.242934) (xy 138.981855 -134.224892) (xy 139.128652 -134.21485) (xy 139.275778 -134.212841)
			(xy 139.422795 -134.218868) (xy 139.569263 -134.232916) (xy 139.714745 -134.25494) (xy 139.858807 -134.284877)
			(xy 140.00102 -134.322636) (xy 140.140958 -134.368105) (xy 140.278205 -134.421147) (xy 140.41235 -134.481606)
			(xy 140.542993 -134.5493) (xy 140.669745 -134.624027) (xy 140.792227 -134.705565) (xy 140.910073 -134.793669)
			(xy 141.022932 -134.888078) (xy 141.130467 -134.988509) (xy 141.232358 -135.094662) (xy 141.328299 -135.206221)
			(xy 141.418005 -135.322853) (xy 141.501208 -135.44421) (xy 141.577659 -135.569929) (xy 141.647131 -135.699635)
			(xy 141.709417 -135.832942) (xy 141.764329 -135.969452) (xy 141.811705 -136.108756) (xy 141.851403 -136.250439)
			(xy 141.883304 -136.39408) (xy 141.907314 -136.539247) (xy 141.92336 -136.68551) (xy 141.931396 -136.83243)
			(xy 141.931898 -136.906) (xy 141.931396 -136.97957) (xy 141.92336 -137.12649) (xy 141.907314 -137.272753)
			(xy 141.883304 -137.41792) (xy 141.851403 -137.561561) (xy 141.814463 -137.6934) (xy 145.516092 -137.6934)
			(xy 145.516092 -136.1186) (xy 145.516638 -136.101885) (xy 145.52529 -136.069594) (xy 145.542005 -136.040643)
			(xy 145.565643 -136.017005) (xy 145.594594 -136.00029) (xy 145.626885 -135.991638) (xy 145.6436 -135.991092)
			(xy 147.2184 -135.991092) (xy 147.235115 -135.991638) (xy 147.267406 -136.00029) (xy 147.296357 -136.017005)
			(xy 147.319995 -136.040643) (xy 147.33671 -136.069594) (xy 147.345362 -136.101885) (xy 147.345908 -136.1186)
			(xy 147.345908 -136.906) (xy 148.73758 -136.906) (xy 148.741599 -136.758915) (xy 148.753644 -136.612269)
			(xy 148.773679 -136.466499) (xy 148.801645 -136.322042) (xy 148.837458 -136.179327) (xy 148.881012 -136.03878)
			(xy 148.932175 -135.900822) (xy 148.990796 -135.765863) (xy 149.056699 -135.634308) (xy 149.129688 -135.506547)
			(xy 149.209545 -135.382963) (xy 149.296032 -135.263924) (xy 149.38889 -135.149786) (xy 149.487842 -135.040889)
			(xy 149.592594 -134.937559) (xy 149.702832 -134.840103) (xy 149.818228 -134.748812) (xy 149.938437 -134.663959)
			(xy 150.0631 -134.585798) (xy 150.191846 -134.514561) (xy 150.32429 -134.45046) (xy 150.460036 -134.393689)
			(xy 150.59868 -134.344414) (xy 150.739809 -134.302785) (xy 150.882999 -134.268925) (xy 151.027826 -134.242934)
			(xy 151.173855 -134.224892) (xy 151.320652 -134.21485) (xy 151.467778 -134.212841) (xy 151.614795 -134.218868)
			(xy 151.761263 -134.232916) (xy 151.906745 -134.25494) (xy 152.050807 -134.284877) (xy 152.19302 -134.322636)
			(xy 152.332958 -134.368105) (xy 152.470205 -134.421147) (xy 152.60435 -134.481606) (xy 152.734993 -134.5493)
			(xy 152.861745 -134.624027) (xy 152.984227 -134.705565) (xy 153.102073 -134.793669) (xy 153.214932 -134.888078)
			(xy 153.322467 -134.988509) (xy 153.424358 -135.094662) (xy 153.520299 -135.206221) (xy 153.610005 -135.322853)
			(xy 153.693208 -135.44421) (xy 153.769659 -135.569929) (xy 153.839131 -135.699635) (xy 153.901417 -135.832942)
			(xy 153.956329 -135.969452) (xy 154.003705 -136.108756) (xy 154.043403 -136.250439) (xy 154.075304 -136.39408)
			(xy 154.099314 -136.539247) (xy 154.11536 -136.68551) (xy 154.123396 -136.83243) (xy 154.123898 -136.906)
			(xy 154.123396 -136.97957) (xy 154.11536 -137.12649) (xy 154.099314 -137.272753) (xy 154.075304 -137.41792)
			(xy 154.043403 -137.561561) (xy 154.006321 -137.693908) (xy 161.13252 -137.693908) (xy 161.13252 -136.1186)
			(xy 161.133035 -136.101904) (xy 161.141668 -136.069647) (xy 161.158347 -136.040718) (xy 161.181938 -136.017085)
			(xy 161.210837 -136.000355) (xy 161.243079 -135.991665) (xy 161.259774 -135.991092) (xy 162.834574 -135.991092)
			(xy 162.851237 -135.991611) (xy 162.883432 -136.000222) (xy 162.912305 -136.016865) (xy 162.935892 -136.040409)
			(xy 162.952588 -136.069251) (xy 162.961259 -136.10143) (xy 162.961828 -136.118092) (xy 162.961828 -136.906)
			(xy 164.353754 -136.906) (xy 164.357773 -136.758915) (xy 164.369818 -136.612269) (xy 164.389853 -136.466499)
			(xy 164.417819 -136.322042) (xy 164.453632 -136.179327) (xy 164.497186 -136.03878) (xy 164.548349 -135.900822)
			(xy 164.60697 -135.765863) (xy 164.672873 -135.634308) (xy 164.745862 -135.506547) (xy 164.825719 -135.382963)
			(xy 164.912206 -135.263924) (xy 165.005064 -135.149786) (xy 165.104016 -135.040889) (xy 165.208768 -134.937559)
			(xy 165.319006 -134.840103) (xy 165.434402 -134.748812) (xy 165.554611 -134.663959) (xy 165.679274 -134.585798)
			(xy 165.80802 -134.514561) (xy 165.940464 -134.45046) (xy 166.07621 -134.393689) (xy 166.214854 -134.344414)
			(xy 166.355983 -134.302785) (xy 166.499173 -134.268925) (xy 166.644 -134.242934) (xy 166.790029 -134.224892)
			(xy 166.936826 -134.21485) (xy 167.083952 -134.212841) (xy 167.230969 -134.218868) (xy 167.377437 -134.232916)
			(xy 167.522919 -134.25494) (xy 167.666981 -134.284877) (xy 167.809194 -134.322636) (xy 167.949132 -134.368105)
			(xy 168.086379 -134.421147) (xy 168.220524 -134.481606) (xy 168.351167 -134.5493) (xy 168.477919 -134.624027)
			(xy 168.600401 -134.705565) (xy 168.718247 -134.793669) (xy 168.831106 -134.888078) (xy 168.938641 -134.988509)
			(xy 169.040532 -135.094662) (xy 169.136473 -135.206221) (xy 169.226179 -135.322853) (xy 169.309382 -135.44421)
			(xy 169.385833 -135.569929) (xy 169.455305 -135.699635) (xy 169.517591 -135.832942) (xy 169.572503 -135.969452)
			(xy 169.619879 -136.108756) (xy 169.659577 -136.250439) (xy 169.691478 -136.39408) (xy 169.715488 -136.539247)
			(xy 169.731534 -136.68551) (xy 169.73957 -136.83243) (xy 169.740072 -136.906) (xy 169.73957 -136.97957)
			(xy 169.731534 -137.12649) (xy 169.715488 -137.272753) (xy 169.691478 -137.41792) (xy 169.659577 -137.561561)
			(xy 169.622495 -137.693908) (xy 173.32452 -137.693908) (xy 173.32452 -136.1186) (xy 173.325035 -136.101904)
			(xy 173.333668 -136.069647) (xy 173.350347 -136.040718) (xy 173.373938 -136.017085) (xy 173.402837 -136.000355)
			(xy 173.435079 -135.991665) (xy 173.451774 -135.991092) (xy 175.026574 -135.991092) (xy 175.043237 -135.991611)
			(xy 175.075432 -136.000222) (xy 175.104305 -136.016865) (xy 175.127892 -136.040409) (xy 175.144588 -136.069251)
			(xy 175.153259 -136.10143) (xy 175.153828 -136.118092) (xy 175.153828 -136.906) (xy 176.545754 -136.906)
			(xy 176.549773 -136.758915) (xy 176.561818 -136.612269) (xy 176.581853 -136.466499) (xy 176.609819 -136.322042)
			(xy 176.645632 -136.179327) (xy 176.689186 -136.03878) (xy 176.740349 -135.900822) (xy 176.79897 -135.765863)
			(xy 176.864873 -135.634308) (xy 176.937862 -135.506547) (xy 177.017719 -135.382963) (xy 177.104206 -135.263924)
			(xy 177.197064 -135.149786) (xy 177.296016 -135.040889) (xy 177.400768 -134.937559) (xy 177.511006 -134.840103)
			(xy 177.626402 -134.748812) (xy 177.746611 -134.663959) (xy 177.871274 -134.585798) (xy 178.00002 -134.514561)
			(xy 178.132464 -134.45046) (xy 178.26821 -134.393689) (xy 178.406854 -134.344414) (xy 178.547983 -134.302785)
			(xy 178.691173 -134.268925) (xy 178.836 -134.242934) (xy 178.982029 -134.224892) (xy 179.128826 -134.21485)
			(xy 179.275952 -134.212841) (xy 179.422969 -134.218868) (xy 179.569437 -134.232916) (xy 179.714919 -134.25494)
			(xy 179.858981 -134.284877) (xy 180.001194 -134.322636) (xy 180.141132 -134.368105) (xy 180.278379 -134.421147)
			(xy 180.412524 -134.481606) (xy 180.543167 -134.5493) (xy 180.669919 -134.624027) (xy 180.792401 -134.705565)
			(xy 180.910247 -134.793669) (xy 181.023106 -134.888078) (xy 181.130641 -134.988509) (xy 181.232532 -135.094662)
			(xy 181.328473 -135.206221) (xy 181.418179 -135.322853) (xy 181.501382 -135.44421) (xy 181.577833 -135.569929)
			(xy 181.647305 -135.699635) (xy 181.709591 -135.832942) (xy 181.764503 -135.969452) (xy 181.811879 -136.108756)
			(xy 181.851577 -136.250439) (xy 181.883478 -136.39408) (xy 181.907488 -136.539247) (xy 181.923534 -136.68551)
			(xy 181.93157 -136.83243) (xy 181.932072 -136.906) (xy 181.93157 -136.97957) (xy 181.923534 -137.12649)
			(xy 181.907488 -137.272753) (xy 181.883478 -137.41792) (xy 181.851577 -137.561561) (xy 181.814495 -137.693908)
			(xy 185.51652 -137.693908) (xy 185.51652 -136.1186) (xy 185.517035 -136.101904) (xy 185.525668 -136.069647)
			(xy 185.542347 -136.040718) (xy 185.565938 -136.017085) (xy 185.594837 -136.000355) (xy 185.627079 -135.991665)
			(xy 185.643774 -135.991092) (xy 187.218574 -135.991092) (xy 187.235237 -135.991611) (xy 187.267432 -136.000222)
			(xy 187.296305 -136.016865) (xy 187.319892 -136.040409) (xy 187.336588 -136.069251) (xy 187.345259 -136.10143)
			(xy 187.345828 -136.118092) (xy 187.345828 -136.906) (xy 188.737754 -136.906) (xy 188.741773 -136.758915)
			(xy 188.753818 -136.612269) (xy 188.773853 -136.466499) (xy 188.801819 -136.322042) (xy 188.837632 -136.179327)
			(xy 188.881186 -136.03878) (xy 188.932349 -135.900822) (xy 188.99097 -135.765863) (xy 189.056873 -135.634308)
			(xy 189.129862 -135.506547) (xy 189.209719 -135.382963) (xy 189.296206 -135.263924) (xy 189.389064 -135.149786)
			(xy 189.488016 -135.040889) (xy 189.592768 -134.937559) (xy 189.703006 -134.840103) (xy 189.818402 -134.748812)
			(xy 189.938611 -134.663959) (xy 190.063274 -134.585798) (xy 190.19202 -134.514561) (xy 190.324464 -134.45046)
			(xy 190.46021 -134.393689) (xy 190.598854 -134.344414) (xy 190.739983 -134.302785) (xy 190.883173 -134.268925)
			(xy 191.028 -134.242934) (xy 191.174029 -134.224892) (xy 191.320826 -134.21485) (xy 191.467952 -134.212841)
			(xy 191.614969 -134.218868) (xy 191.761437 -134.232916) (xy 191.906919 -134.25494) (xy 192.050981 -134.284877)
			(xy 192.193194 -134.322636) (xy 192.333132 -134.368105) (xy 192.470379 -134.421147) (xy 192.604524 -134.481606)
			(xy 192.735167 -134.5493) (xy 192.861919 -134.624027) (xy 192.984401 -134.705565) (xy 193.102247 -134.793669)
			(xy 193.215106 -134.888078) (xy 193.322641 -134.988509) (xy 193.424532 -135.094662) (xy 193.520473 -135.206221)
			(xy 193.610179 -135.322853) (xy 193.693382 -135.44421) (xy 193.769833 -135.569929) (xy 193.839305 -135.699635)
			(xy 193.901591 -135.832942) (xy 193.956503 -135.969452) (xy 194.003879 -136.108756) (xy 194.043577 -136.250439)
			(xy 194.075478 -136.39408) (xy 194.099488 -136.539247) (xy 194.115534 -136.68551) (xy 194.12357 -136.83243)
			(xy 194.124072 -136.906) (xy 194.12357 -136.97957) (xy 194.115534 -137.12649) (xy 194.099488 -137.272753)
			(xy 194.075478 -137.41792) (xy 194.043577 -137.561561) (xy 194.003879 -137.703244) (xy 193.956503 -137.842548)
			(xy 193.901591 -137.979058) (xy 193.839305 -138.112365) (xy 193.769833 -138.242071) (xy 193.693382 -138.36779)
			(xy 193.610179 -138.489147) (xy 193.520473 -138.605779) (xy 193.424532 -138.717338) (xy 193.322641 -138.823491)
			(xy 193.215106 -138.923922) (xy 193.102247 -139.018331) (xy 192.984401 -139.106435) (xy 192.861919 -139.187973)
			(xy 192.735167 -139.2627) (xy 192.604524 -139.330394) (xy 192.470379 -139.390853) (xy 192.333132 -139.443895)
			(xy 192.193194 -139.489364) (xy 192.050981 -139.527123) (xy 191.906919 -139.55706) (xy 191.761437 -139.579084)
			(xy 191.614969 -139.593132) (xy 191.467952 -139.599159) (xy 191.320826 -139.59715) (xy 191.174029 -139.587108)
			(xy 191.028 -139.569066) (xy 190.883173 -139.543075) (xy 190.739983 -139.509215) (xy 190.598854 -139.467586)
			(xy 190.46021 -139.418311) (xy 190.324464 -139.36154) (xy 190.19202 -139.297439) (xy 190.063274 -139.226202)
			(xy 189.938611 -139.148041) (xy 189.818402 -139.063188) (xy 189.703006 -138.971897) (xy 189.592768 -138.874441)
			(xy 189.488016 -138.771111) (xy 189.389064 -138.662214) (xy 189.296206 -138.548076) (xy 189.209719 -138.429037)
			(xy 189.129862 -138.305453) (xy 189.056873 -138.177692) (xy 188.99097 -138.046137) (xy 188.932349 -137.911178)
			(xy 188.881186 -137.77322) (xy 188.837632 -137.632673) (xy 188.801819 -137.489958) (xy 188.773853 -137.345501)
			(xy 188.753818 -137.199731) (xy 188.741773 -137.053085) (xy 188.737754 -136.906) (xy 187.345828 -136.906)
			(xy 187.345828 -137.6934) (xy 187.345266 -137.710092) (xy 187.336637 -137.742342) (xy 187.319965 -137.771266)
			(xy 187.296384 -137.794898) (xy 187.267496 -137.811631) (xy 187.235265 -137.82033) (xy 187.218574 -137.820908)
			(xy 185.643774 -137.820908) (xy 185.627108 -137.820435) (xy 185.594912 -137.811811) (xy 185.56604 -137.795157)
			(xy 185.542454 -137.771605) (xy 185.525759 -137.742757) (xy 185.517089 -137.710573) (xy 185.51652 -137.693908)
			(xy 181.814495 -137.693908) (xy 181.811879 -137.703244) (xy 181.764503 -137.842548) (xy 181.709591 -137.979058)
			(xy 181.647305 -138.112365) (xy 181.577833 -138.242071) (xy 181.501382 -138.36779) (xy 181.418179 -138.489147)
			(xy 181.328473 -138.605779) (xy 181.232532 -138.717338) (xy 181.130641 -138.823491) (xy 181.023106 -138.923922)
			(xy 180.910247 -139.018331) (xy 180.792401 -139.106435) (xy 180.669919 -139.187973) (xy 180.543167 -139.2627)
			(xy 180.412524 -139.330394) (xy 180.278379 -139.390853) (xy 180.141132 -139.443895) (xy 180.001194 -139.489364)
			(xy 179.858981 -139.527123) (xy 179.714919 -139.55706) (xy 179.569437 -139.579084) (xy 179.422969 -139.593132)
			(xy 179.275952 -139.599159) (xy 179.128826 -139.59715) (xy 178.982029 -139.587108) (xy 178.836 -139.569066)
			(xy 178.691173 -139.543075) (xy 178.547983 -139.509215) (xy 178.406854 -139.467586) (xy 178.26821 -139.418311)
			(xy 178.132464 -139.36154) (xy 178.00002 -139.297439) (xy 177.871274 -139.226202) (xy 177.746611 -139.148041)
			(xy 177.626402 -139.063188) (xy 177.511006 -138.971897) (xy 177.400768 -138.874441) (xy 177.296016 -138.771111)
			(xy 177.197064 -138.662214) (xy 177.104206 -138.548076) (xy 177.017719 -138.429037) (xy 176.937862 -138.305453)
			(xy 176.864873 -138.177692) (xy 176.79897 -138.046137) (xy 176.740349 -137.911178) (xy 176.689186 -137.77322)
			(xy 176.645632 -137.632673) (xy 176.609819 -137.489958) (xy 176.581853 -137.345501) (xy 176.561818 -137.199731)
			(xy 176.549773 -137.053085) (xy 176.545754 -136.906) (xy 175.153828 -136.906) (xy 175.153828 -137.6934)
			(xy 175.153266 -137.710092) (xy 175.144637 -137.742342) (xy 175.127965 -137.771266) (xy 175.104384 -137.794898)
			(xy 175.075496 -137.811631) (xy 175.043265 -137.82033) (xy 175.026574 -137.820908) (xy 173.451774 -137.820908)
			(xy 173.435108 -137.820435) (xy 173.402912 -137.811811) (xy 173.37404 -137.795157) (xy 173.350454 -137.771605)
			(xy 173.333759 -137.742757) (xy 173.325089 -137.710573) (xy 173.32452 -137.693908) (xy 169.622495 -137.693908)
			(xy 169.619879 -137.703244) (xy 169.572503 -137.842548) (xy 169.517591 -137.979058) (xy 169.455305 -138.112365)
			(xy 169.385833 -138.242071) (xy 169.309382 -138.36779) (xy 169.226179 -138.489147) (xy 169.136473 -138.605779)
			(xy 169.040532 -138.717338) (xy 168.938641 -138.823491) (xy 168.831106 -138.923922) (xy 168.718247 -139.018331)
			(xy 168.600401 -139.106435) (xy 168.477919 -139.187973) (xy 168.351167 -139.2627) (xy 168.220524 -139.330394)
			(xy 168.086379 -139.390853) (xy 167.949132 -139.443895) (xy 167.809194 -139.489364) (xy 167.666981 -139.527123)
			(xy 167.522919 -139.55706) (xy 167.377437 -139.579084) (xy 167.230969 -139.593132) (xy 167.083952 -139.599159)
			(xy 166.936826 -139.59715) (xy 166.790029 -139.587108) (xy 166.644 -139.569066) (xy 166.499173 -139.543075)
			(xy 166.355983 -139.509215) (xy 166.214854 -139.467586) (xy 166.07621 -139.418311) (xy 165.940464 -139.36154)
			(xy 165.80802 -139.297439) (xy 165.679274 -139.226202) (xy 165.554611 -139.148041) (xy 165.434402 -139.063188)
			(xy 165.319006 -138.971897) (xy 165.208768 -138.874441) (xy 165.104016 -138.771111) (xy 165.005064 -138.662214)
			(xy 164.912206 -138.548076) (xy 164.825719 -138.429037) (xy 164.745862 -138.305453) (xy 164.672873 -138.177692)
			(xy 164.60697 -138.046137) (xy 164.548349 -137.911178) (xy 164.497186 -137.77322) (xy 164.453632 -137.632673)
			(xy 164.417819 -137.489958) (xy 164.389853 -137.345501) (xy 164.369818 -137.199731) (xy 164.357773 -137.053085)
			(xy 164.353754 -136.906) (xy 162.961828 -136.906) (xy 162.961828 -137.6934) (xy 162.961266 -137.710092)
			(xy 162.952637 -137.742342) (xy 162.935965 -137.771266) (xy 162.912384 -137.794898) (xy 162.883496 -137.811631)
			(xy 162.851265 -137.82033) (xy 162.834574 -137.820908) (xy 161.259774 -137.820908) (xy 161.243108 -137.820435)
			(xy 161.210912 -137.811811) (xy 161.18204 -137.795157) (xy 161.158454 -137.771605) (xy 161.141759 -137.742757)
			(xy 161.133089 -137.710573) (xy 161.13252 -137.693908) (xy 154.006321 -137.693908) (xy 154.003705 -137.703244)
			(xy 153.956329 -137.842548) (xy 153.901417 -137.979058) (xy 153.839131 -138.112365) (xy 153.769659 -138.242071)
			(xy 153.693208 -138.36779) (xy 153.610005 -138.489147) (xy 153.520299 -138.605779) (xy 153.424358 -138.717338)
			(xy 153.322467 -138.823491) (xy 153.214932 -138.923922) (xy 153.102073 -139.018331) (xy 152.984227 -139.106435)
			(xy 152.861745 -139.187973) (xy 152.734993 -139.2627) (xy 152.60435 -139.330394) (xy 152.470205 -139.390853)
			(xy 152.332958 -139.443895) (xy 152.19302 -139.489364) (xy 152.050807 -139.527123) (xy 151.906745 -139.55706)
			(xy 151.761263 -139.579084) (xy 151.614795 -139.593132) (xy 151.467778 -139.599159) (xy 151.320652 -139.59715)
			(xy 151.173855 -139.587108) (xy 151.027826 -139.569066) (xy 150.882999 -139.543075) (xy 150.739809 -139.509215)
			(xy 150.59868 -139.467586) (xy 150.460036 -139.418311) (xy 150.32429 -139.36154) (xy 150.191846 -139.297439)
			(xy 150.0631 -139.226202) (xy 149.938437 -139.148041) (xy 149.818228 -139.063188) (xy 149.702832 -138.971897)
			(xy 149.592594 -138.874441) (xy 149.487842 -138.771111) (xy 149.38889 -138.662214) (xy 149.296032 -138.548076)
			(xy 149.209545 -138.429037) (xy 149.129688 -138.305453) (xy 149.056699 -138.177692) (xy 148.990796 -138.046137)
			(xy 148.932175 -137.911178) (xy 148.881012 -137.77322) (xy 148.837458 -137.632673) (xy 148.801645 -137.489958)
			(xy 148.773679 -137.345501) (xy 148.753644 -137.199731) (xy 148.741599 -137.053085) (xy 148.73758 -136.906)
			(xy 147.345908 -136.906) (xy 147.345908 -137.6934) (xy 147.345362 -137.710115) (xy 147.33671 -137.742406)
			(xy 147.319995 -137.771357) (xy 147.296357 -137.794995) (xy 147.267406 -137.81171) (xy 147.235115 -137.820362)
			(xy 147.2184 -137.820908) (xy 145.6436 -137.820908) (xy 145.626885 -137.820362) (xy 145.594594 -137.81171)
			(xy 145.565643 -137.794995) (xy 145.542005 -137.771357) (xy 145.52529 -137.742406) (xy 145.516638 -137.710115)
			(xy 145.516092 -137.6934) (xy 141.814463 -137.6934) (xy 141.811705 -137.703244) (xy 141.764329 -137.842548)
			(xy 141.709417 -137.979058) (xy 141.647131 -138.112365) (xy 141.577659 -138.242071) (xy 141.501208 -138.36779)
			(xy 141.418005 -138.489147) (xy 141.328299 -138.605779) (xy 141.232358 -138.717338) (xy 141.130467 -138.823491)
			(xy 141.022932 -138.923922) (xy 140.910073 -139.018331) (xy 140.792227 -139.106435) (xy 140.669745 -139.187973)
			(xy 140.542993 -139.2627) (xy 140.41235 -139.330394) (xy 140.278205 -139.390853) (xy 140.140958 -139.443895)
			(xy 140.00102 -139.489364) (xy 139.858807 -139.527123) (xy 139.714745 -139.55706) (xy 139.569263 -139.579084)
			(xy 139.422795 -139.593132) (xy 139.275778 -139.599159) (xy 139.128652 -139.59715) (xy 138.981855 -139.587108)
			(xy 138.835826 -139.569066) (xy 138.690999 -139.543075) (xy 138.547809 -139.509215) (xy 138.40668 -139.467586)
			(xy 138.268036 -139.418311) (xy 138.13229 -139.36154) (xy 137.999846 -139.297439) (xy 137.8711 -139.226202)
			(xy 137.746437 -139.148041) (xy 137.626228 -139.063188) (xy 137.510832 -138.971897) (xy 137.400594 -138.874441)
			(xy 137.295842 -138.771111) (xy 137.19689 -138.662214) (xy 137.104032 -138.548076) (xy 137.017545 -138.429037)
			(xy 136.937688 -138.305453) (xy 136.864699 -138.177692) (xy 136.798796 -138.046137) (xy 136.740175 -137.911178)
			(xy 136.689012 -137.77322) (xy 136.645458 -137.632673) (xy 136.609645 -137.489958) (xy 136.581679 -137.345501)
			(xy 136.561644 -137.199731) (xy 136.549599 -137.053085) (xy 136.54558 -136.906) (xy 135.153908 -136.906)
			(xy 135.153908 -137.6934) (xy 135.153362 -137.710115) (xy 135.14471 -137.742406) (xy 135.127995 -137.771357)
			(xy 135.104357 -137.794995) (xy 135.075406 -137.81171) (xy 135.043115 -137.820362) (xy 135.0264 -137.820908)
			(xy 133.4516 -137.820908) (xy 133.434885 -137.820362) (xy 133.402594 -137.81171) (xy 133.373643 -137.794995)
			(xy 133.350005 -137.771357) (xy 133.33329 -137.742406) (xy 133.324638 -137.710115) (xy 133.324092 -137.6934)
			(xy 129.622463 -137.6934) (xy 129.619705 -137.703244) (xy 129.572329 -137.842548) (xy 129.517417 -137.979058)
			(xy 129.455131 -138.112365) (xy 129.385659 -138.242071) (xy 129.309208 -138.36779) (xy 129.226005 -138.489147)
			(xy 129.136299 -138.605779) (xy 129.040358 -138.717338) (xy 128.938467 -138.823491) (xy 128.830932 -138.923922)
			(xy 128.718073 -139.018331) (xy 128.600227 -139.106435) (xy 128.477745 -139.187973) (xy 128.350993 -139.2627)
			(xy 128.22035 -139.330394) (xy 128.086205 -139.390853) (xy 127.948958 -139.443895) (xy 127.80902 -139.489364)
			(xy 127.666807 -139.527123) (xy 127.522745 -139.55706) (xy 127.377263 -139.579084) (xy 127.230795 -139.593132)
			(xy 127.083778 -139.599159) (xy 126.936652 -139.59715) (xy 126.789855 -139.587108) (xy 126.643826 -139.569066)
			(xy 126.498999 -139.543075) (xy 126.355809 -139.509215) (xy 126.21468 -139.467586) (xy 126.076036 -139.418311)
			(xy 125.94029 -139.36154) (xy 125.807846 -139.297439) (xy 125.6791 -139.226202) (xy 125.554437 -139.148041)
			(xy 125.434228 -139.063188) (xy 125.318832 -138.971897) (xy 125.208594 -138.874441) (xy 125.103842 -138.771111)
			(xy 125.00489 -138.662214) (xy 124.912032 -138.548076) (xy 124.825545 -138.429037) (xy 124.745688 -138.305453)
			(xy 124.672699 -138.177692) (xy 124.606796 -138.046137) (xy 124.548175 -137.911178) (xy 124.497012 -137.77322)
			(xy 124.453458 -137.632673) (xy 124.417645 -137.489958) (xy 124.389679 -137.345501) (xy 124.369644 -137.199731)
			(xy 124.357599 -137.053085) (xy 124.35358 -136.906) (xy 122.961908 -136.906) (xy 122.961908 -137.6934)
			(xy 122.961362 -137.710115) (xy 122.95271 -137.742406) (xy 122.935995 -137.771357) (xy 122.912357 -137.794995)
			(xy 122.883406 -137.81171) (xy 122.851115 -137.820362) (xy 122.8344 -137.820908) (xy 121.2596 -137.820908)
			(xy 121.242885 -137.820362) (xy 121.210594 -137.81171) (xy 121.181643 -137.794995) (xy 121.158005 -137.771357)
			(xy 121.14129 -137.742406) (xy 121.132638 -137.710115) (xy 121.132092 -137.6934) (xy 114.006289 -137.6934)
			(xy 114.003531 -137.703244) (xy 113.956155 -137.842548) (xy 113.901243 -137.979058) (xy 113.838957 -138.112365)
			(xy 113.769485 -138.242071) (xy 113.693034 -138.36779) (xy 113.609831 -138.489147) (xy 113.520125 -138.605779)
			(xy 113.424184 -138.717338) (xy 113.322293 -138.823491) (xy 113.214758 -138.923922) (xy 113.101899 -139.018331)
			(xy 112.984053 -139.106435) (xy 112.861571 -139.187973) (xy 112.734819 -139.2627) (xy 112.604176 -139.330394)
			(xy 112.470031 -139.390853) (xy 112.332784 -139.443895) (xy 112.192846 -139.489364) (xy 112.050633 -139.527123)
			(xy 111.906571 -139.55706) (xy 111.761089 -139.579084) (xy 111.614621 -139.593132) (xy 111.467604 -139.599159)
			(xy 111.320478 -139.59715) (xy 111.173681 -139.587108) (xy 111.027652 -139.569066) (xy 110.882825 -139.543075)
			(xy 110.739635 -139.509215) (xy 110.598506 -139.467586) (xy 110.459862 -139.418311) (xy 110.324116 -139.36154)
			(xy 110.191672 -139.297439) (xy 110.062926 -139.226202) (xy 109.938263 -139.148041) (xy 109.818054 -139.063188)
			(xy 109.702658 -138.971897) (xy 109.59242 -138.874441) (xy 109.487668 -138.771111) (xy 109.388716 -138.662214)
			(xy 109.295858 -138.548076) (xy 109.209371 -138.429037) (xy 109.129514 -138.305453) (xy 109.056525 -138.177692)
			(xy 108.990622 -138.046137) (xy 108.932001 -137.911178) (xy 108.880838 -137.77322) (xy 108.837284 -137.632673)
			(xy 108.801471 -137.489958) (xy 108.773505 -137.345501) (xy 108.75347 -137.199731) (xy 108.741425 -137.053085)
			(xy 108.737406 -136.906) (xy 107.34548 -136.906) (xy 107.34548 -137.6934) (xy 107.344965 -137.710096)
			(xy 107.336332 -137.742353) (xy 107.319653 -137.771282) (xy 107.296062 -137.794915) (xy 107.267163 -137.811645)
			(xy 107.234921 -137.820335) (xy 107.218226 -137.820908) (xy 105.643426 -137.820908) (xy 105.626763 -137.820389)
			(xy 105.594568 -137.811778) (xy 105.565695 -137.795135) (xy 105.542108 -137.771591) (xy 105.525412 -137.742749)
			(xy 105.516741 -137.71057) (xy 105.516172 -137.693908) (xy 101.814147 -137.693908) (xy 101.811531 -137.703244)
			(xy 101.764155 -137.842548) (xy 101.709243 -137.979058) (xy 101.646957 -138.112365) (xy 101.577485 -138.242071)
			(xy 101.501034 -138.36779) (xy 101.417831 -138.489147) (xy 101.328125 -138.605779) (xy 101.232184 -138.717338)
			(xy 101.130293 -138.823491) (xy 101.022758 -138.923922) (xy 100.909899 -139.018331) (xy 100.792053 -139.106435)
			(xy 100.669571 -139.187973) (xy 100.542819 -139.2627) (xy 100.412176 -139.330394) (xy 100.278031 -139.390853)
			(xy 100.140784 -139.443895) (xy 100.000846 -139.489364) (xy 99.858633 -139.527123) (xy 99.714571 -139.55706)
			(xy 99.569089 -139.579084) (xy 99.422621 -139.593132) (xy 99.275604 -139.599159) (xy 99.128478 -139.59715)
			(xy 98.981681 -139.587108) (xy 98.835652 -139.569066) (xy 98.690825 -139.543075) (xy 98.547635 -139.509215)
			(xy 98.406506 -139.467586) (xy 98.267862 -139.418311) (xy 98.132116 -139.36154) (xy 97.999672 -139.297439)
			(xy 97.870926 -139.226202) (xy 97.746263 -139.148041) (xy 97.626054 -139.063188) (xy 97.510658 -138.971897)
			(xy 97.40042 -138.874441) (xy 97.295668 -138.771111) (xy 97.196716 -138.662214) (xy 97.103858 -138.548076)
			(xy 97.017371 -138.429037) (xy 96.937514 -138.305453) (xy 96.864525 -138.177692) (xy 96.798622 -138.046137)
			(xy 96.740001 -137.911178) (xy 96.688838 -137.77322) (xy 96.645284 -137.632673) (xy 96.609471 -137.489958)
			(xy 96.581505 -137.345501) (xy 96.56147 -137.199731) (xy 96.549425 -137.053085) (xy 96.545406 -136.906)
			(xy 95.15348 -136.906) (xy 95.15348 -137.6934) (xy 95.152965 -137.710096) (xy 95.144332 -137.742353)
			(xy 95.127653 -137.771282) (xy 95.104062 -137.794915) (xy 95.075163 -137.811645) (xy 95.042921 -137.820335)
			(xy 95.026226 -137.820908) (xy 93.451426 -137.820908) (xy 93.434763 -137.820389) (xy 93.402568 -137.811778)
			(xy 93.373695 -137.795135) (xy 93.350108 -137.771591) (xy 93.333412 -137.742749) (xy 93.324741 -137.71057)
			(xy 93.324172 -137.693908) (xy 89.622147 -137.693908) (xy 89.619531 -137.703244) (xy 89.572155 -137.842548)
			(xy 89.517243 -137.979058) (xy 89.454957 -138.112365) (xy 89.385485 -138.242071) (xy 89.309034 -138.36779)
			(xy 89.225831 -138.489147) (xy 89.136125 -138.605779) (xy 89.040184 -138.717338) (xy 88.938293 -138.823491)
			(xy 88.830758 -138.923922) (xy 88.717899 -139.018331) (xy 88.600053 -139.106435) (xy 88.477571 -139.187973)
			(xy 88.350819 -139.2627) (xy 88.220176 -139.330394) (xy 88.086031 -139.390853) (xy 87.948784 -139.443895)
			(xy 87.808846 -139.489364) (xy 87.666633 -139.527123) (xy 87.522571 -139.55706) (xy 87.377089 -139.579084)
			(xy 87.230621 -139.593132) (xy 87.083604 -139.599159) (xy 86.936478 -139.59715) (xy 86.789681 -139.587108)
			(xy 86.643652 -139.569066) (xy 86.498825 -139.543075) (xy 86.355635 -139.509215) (xy 86.214506 -139.467586)
			(xy 86.075862 -139.418311) (xy 85.940116 -139.36154) (xy 85.807672 -139.297439) (xy 85.678926 -139.226202)
			(xy 85.554263 -139.148041) (xy 85.434054 -139.063188) (xy 85.318658 -138.971897) (xy 85.20842 -138.874441)
			(xy 85.103668 -138.771111) (xy 85.004716 -138.662214) (xy 84.911858 -138.548076) (xy 84.825371 -138.429037)
			(xy 84.745514 -138.305453) (xy 84.672525 -138.177692) (xy 84.606622 -138.046137) (xy 84.548001 -137.911178)
			(xy 84.496838 -137.77322) (xy 84.453284 -137.632673) (xy 84.417471 -137.489958) (xy 84.389505 -137.345501)
			(xy 84.36947 -137.199731) (xy 84.357425 -137.053085) (xy 84.353406 -136.906) (xy 82.96148 -136.906)
			(xy 82.96148 -137.6934) (xy 82.960965 -137.710096) (xy 82.952332 -137.742353) (xy 82.935653 -137.771282)
			(xy 82.912062 -137.794915) (xy 82.883163 -137.811645) (xy 82.850921 -137.820335) (xy 82.834226 -137.820908)
			(xy 81.259426 -137.820908) (xy 81.242763 -137.820389) (xy 81.210568 -137.811778) (xy 81.181695 -137.795135)
			(xy 81.158108 -137.771591) (xy 81.141412 -137.742749) (xy 81.132741 -137.71057) (xy 81.132172 -137.693908)
			(xy 74.006227 -137.693908) (xy 74.003611 -137.703244) (xy 73.956235 -137.842548) (xy 73.901323 -137.979058)
			(xy 73.839037 -138.112365) (xy 73.769565 -138.242071) (xy 73.693114 -138.36779) (xy 73.609911 -138.489147)
			(xy 73.520205 -138.605779) (xy 73.424264 -138.717338) (xy 73.322373 -138.823491) (xy 73.214838 -138.923922)
			(xy 73.101979 -139.018331) (xy 72.984133 -139.106435) (xy 72.861651 -139.187973) (xy 72.734899 -139.2627)
			(xy 72.604256 -139.330394) (xy 72.470111 -139.390853) (xy 72.332864 -139.443895) (xy 72.192926 -139.489364)
			(xy 72.050713 -139.527123) (xy 71.906651 -139.55706) (xy 71.761169 -139.579084) (xy 71.614701 -139.593132)
			(xy 71.467684 -139.599159) (xy 71.320558 -139.59715) (xy 71.173761 -139.587108) (xy 71.027732 -139.569066)
			(xy 70.882905 -139.543075) (xy 70.739715 -139.509215) (xy 70.598586 -139.467586) (xy 70.459942 -139.418311)
			(xy 70.324196 -139.36154) (xy 70.191752 -139.297439) (xy 70.063006 -139.226202) (xy 69.938343 -139.148041)
			(xy 69.818134 -139.063188) (xy 69.702738 -138.971897) (xy 69.5925 -138.874441) (xy 69.487748 -138.771111)
			(xy 69.388796 -138.662214) (xy 69.295938 -138.548076) (xy 69.209451 -138.429037) (xy 69.129594 -138.305453)
			(xy 69.056605 -138.177692) (xy 68.990702 -138.046137) (xy 68.932081 -137.911178) (xy 68.880918 -137.77322)
			(xy 68.837364 -137.632673) (xy 68.801551 -137.489958) (xy 68.773585 -137.345501) (xy 68.75355 -137.199731)
			(xy 68.741505 -137.053085) (xy 68.737486 -136.906) (xy 67.34556 -136.906) (xy 67.34556 -137.6934)
			(xy 67.345065 -137.710098) (xy 67.33643 -137.742358) (xy 67.319748 -137.771288) (xy 67.296153 -137.794922)
			(xy 67.267249 -137.811651) (xy 67.235003 -137.820338) (xy 67.218306 -137.820908) (xy 65.643506 -137.820908)
			(xy 65.626842 -137.820407) (xy 65.594647 -137.811791) (xy 65.565774 -137.795143) (xy 65.542187 -137.771597)
			(xy 65.525491 -137.742752) (xy 65.516821 -137.710571) (xy 65.516252 -137.693908) (xy 61.814227 -137.693908)
			(xy 61.811611 -137.703244) (xy 61.764235 -137.842548) (xy 61.709323 -137.979058) (xy 61.647037 -138.112365)
			(xy 61.577565 -138.242071) (xy 61.501114 -138.36779) (xy 61.417911 -138.489147) (xy 61.328205 -138.605779)
			(xy 61.232264 -138.717338) (xy 61.130373 -138.823491) (xy 61.022838 -138.923922) (xy 60.909979 -139.018331)
			(xy 60.792133 -139.106435) (xy 60.669651 -139.187973) (xy 60.542899 -139.2627) (xy 60.412256 -139.330394)
			(xy 60.278111 -139.390853) (xy 60.140864 -139.443895) (xy 60.000926 -139.489364) (xy 59.858713 -139.527123)
			(xy 59.714651 -139.55706) (xy 59.569169 -139.579084) (xy 59.422701 -139.593132) (xy 59.275684 -139.599159)
			(xy 59.128558 -139.59715) (xy 58.981761 -139.587108) (xy 58.835732 -139.569066) (xy 58.690905 -139.543075)
			(xy 58.547715 -139.509215) (xy 58.406586 -139.467586) (xy 58.267942 -139.418311) (xy 58.132196 -139.36154)
			(xy 57.999752 -139.297439) (xy 57.871006 -139.226202) (xy 57.746343 -139.148041) (xy 57.626134 -139.063188)
			(xy 57.510738 -138.971897) (xy 57.4005 -138.874441) (xy 57.295748 -138.771111) (xy 57.196796 -138.662214)
			(xy 57.103938 -138.548076) (xy 57.017451 -138.429037) (xy 56.937594 -138.305453) (xy 56.864605 -138.177692)
			(xy 56.798702 -138.046137) (xy 56.740081 -137.911178) (xy 56.688918 -137.77322) (xy 56.645364 -137.632673)
			(xy 56.609551 -137.489958) (xy 56.581585 -137.345501) (xy 56.56155 -137.199731) (xy 56.549505 -137.053085)
			(xy 56.545486 -136.906) (xy 55.15356 -136.906) (xy 55.15356 -137.6934) (xy 55.153065 -137.710098)
			(xy 55.14443 -137.742358) (xy 55.127748 -137.771288) (xy 55.104153 -137.794922) (xy 55.075249 -137.811651)
			(xy 55.043003 -137.820338) (xy 55.026306 -137.820908) (xy 53.451506 -137.820908) (xy 53.434842 -137.820407)
			(xy 53.402647 -137.811791) (xy 53.373774 -137.795143) (xy 53.350187 -137.771597) (xy 53.333491 -137.742752)
			(xy 53.324821 -137.710571) (xy 53.324252 -137.693908) (xy 49.622227 -137.693908) (xy 49.619611 -137.703244)
			(xy 49.572235 -137.842548) (xy 49.517323 -137.979058) (xy 49.455037 -138.112365) (xy 49.385565 -138.242071)
			(xy 49.309114 -138.36779) (xy 49.225911 -138.489147) (xy 49.136205 -138.605779) (xy 49.040264 -138.717338)
			(xy 48.938373 -138.823491) (xy 48.830838 -138.923922) (xy 48.717979 -139.018331) (xy 48.600133 -139.106435)
			(xy 48.477651 -139.187973) (xy 48.350899 -139.2627) (xy 48.220256 -139.330394) (xy 48.086111 -139.390853)
			(xy 47.948864 -139.443895) (xy 47.808926 -139.489364) (xy 47.666713 -139.527123) (xy 47.522651 -139.55706)
			(xy 47.377169 -139.579084) (xy 47.230701 -139.593132) (xy 47.083684 -139.599159) (xy 46.936558 -139.59715)
			(xy 46.789761 -139.587108) (xy 46.643732 -139.569066) (xy 46.498905 -139.543075) (xy 46.355715 -139.509215)
			(xy 46.214586 -139.467586) (xy 46.075942 -139.418311) (xy 45.940196 -139.36154) (xy 45.807752 -139.297439)
			(xy 45.679006 -139.226202) (xy 45.554343 -139.148041) (xy 45.434134 -139.063188) (xy 45.318738 -138.971897)
			(xy 45.2085 -138.874441) (xy 45.103748 -138.771111) (xy 45.004796 -138.662214) (xy 44.911938 -138.548076)
			(xy 44.825451 -138.429037) (xy 44.745594 -138.305453) (xy 44.672605 -138.177692) (xy 44.606702 -138.046137)
			(xy 44.548081 -137.911178) (xy 44.496918 -137.77322) (xy 44.453364 -137.632673) (xy 44.417551 -137.489958)
			(xy 44.389585 -137.345501) (xy 44.36955 -137.199731) (xy 44.357505 -137.053085) (xy 44.353486 -136.906)
			(xy 42.96156 -136.906) (xy 42.96156 -137.6934) (xy 42.961065 -137.710098) (xy 42.95243 -137.742358)
			(xy 42.935748 -137.771288) (xy 42.912153 -137.794922) (xy 42.883249 -137.811651) (xy 42.851003 -137.820338)
			(xy 42.834306 -137.820908) (xy 41.259506 -137.820908) (xy 41.242842 -137.820407) (xy 41.210647 -137.811791)
			(xy 41.181774 -137.795143) (xy 41.158187 -137.771597) (xy 41.141491 -137.742752) (xy 41.132821 -137.710571)
			(xy 41.132252 -137.693908) (xy 37.531802 -137.693908) (xy 37.531802 -141.742414) (xy 37.531935 -141.747305)
			(xy 37.533847 -141.756901) (xy 37.535612 -141.761464) (xy 37.542978 -141.780006) (xy 37.54475 -141.784634)
			(xy 37.546668 -141.794356) (xy 37.546788 -141.79931) (xy 37.546788 -143.537432) (xy 37.547216 -143.5475)
			(xy 37.554938 -143.566097) (xy 37.561774 -143.5735) (xy 38.974014 -144.98574) (xy 38.981411 -144.992591)
			(xy 39.000009 -145.000329) (xy 39.010082 -145.000726)
		)
		(stroke
			(width 0)
			(type solid)
		)
		(fill yes)
		(layer "B.Cu")
		(net "P52V_HS_FILTER")
	)
	(gr_poly
		(pts
			(arc
				(start 298.302172 -132.452364)
				(mid 298.321695 -132.448463)
				(end 298.33824 -132.437378)
			)
			(arc
				(start 299.240448 -131.53517)
				(mid 299.251559 -131.518636)
				(end 299.255434 -131.499102)
			)
			(xy 299.255434 -122.167396) (xy 299.252894 -122.156474)
			(arc
				(start 299.250354 -122.15114)
				(mid 299.221372 -122.069537)
				(end 299.211492 -121.9835)
			)
			(arc
				(start 299.211492 -121.9835)
				(mid 299.221323 -121.897451)
				(end 299.250354 -121.81586)
			)
			(xy 299.252894 -121.810526) (xy 299.255434 -121.799604) (xy 299.255434 -121.278396) (xy 299.252894 -121.267474)
			(arc
				(start 299.250354 -121.26214)
				(mid 299.221372 -121.180537)
				(end 299.211492 -121.0945)
			)
			(arc
				(start 299.211492 -121.0945)
				(mid 299.221323 -121.008451)
				(end 299.250354 -120.92686)
			)
			(xy 299.252894 -120.921526) (xy 299.255434 -120.910604) (xy 299.255434 -120.389396) (xy 299.252894 -120.378474)
			(arc
				(start 299.250354 -120.37314)
				(mid 299.221372 -120.291537)
				(end 299.211492 -120.2055)
			)
			(arc
				(start 299.211492 -120.2055)
				(mid 299.221323 -120.119451)
				(end 299.250354 -120.03786)
			)
			(xy 299.252894 -120.032526) (xy 299.255434 -120.021604) (xy 299.255434 -119.500396) (xy 299.252894 -119.489474)
			(arc
				(start 299.250354 -119.48414)
				(mid 299.221372 -119.402537)
				(end 299.211492 -119.3165)
			)
			(arc
				(start 299.211492 -119.3165)
				(mid 299.221323 -119.230451)
				(end 299.250354 -119.14886)
			)
			(xy 299.252894 -119.143526) (xy 299.255434 -119.132604)
			(arc
				(start 299.255434 -98.091244)
				(mid 299.251533 -98.071721)
				(end 299.240448 -98.055176)
			)
			(arc
				(start 298.075858 -96.890586)
				(mid 298.059324 -96.879475)
				(end 298.03979 -96.8756)
			)
			(arc
				(start 279.923494 -96.8756)
				(mid 279.903971 -96.879501)
				(end 279.887426 -96.890586)
			)
			(arc
				(start 278.722836 -98.055176)
				(mid 278.711725 -98.07171)
				(end 278.70785 -98.091244)
			)
			(arc
				(start 278.70785 -131.362958)
				(mid 278.711751 -131.382481)
				(end 278.722836 -131.399026)
			)
			(arc
				(start 279.761188 -132.437378)
				(mid 279.777722 -132.448489)
				(end 279.797256 -132.452364)
			)
		)
		(stroke
			(width 0)
			(type solid)
		)
		(fill yes)
		(layer "In1.Cu")
		(net "P52V_HS1_DRAIN_1")
	)
	(gr_poly
		(pts
			(arc
				(start 298.03979 -95.8596)
				(mid 298.059313 -95.855699)
				(end 298.075858 -95.844614)
			)
			(arc
				(start 299.240448 -94.680024)
				(mid 299.251559 -94.66349)
				(end 299.255434 -94.643956)
			)
			(arc
				(start 299.255434 -86.018878)
				(mid 299.25339 -86.004863)
				(end 299.24756 -85.991954)
			)
			(arc
				(start 299.24756 -85.991954)
				(mid 299.203848 -85.894376)
				(end 299.188886 -85.7885)
			)
			(arc
				(start 299.188886 -85.7885)
				(mid 299.203802 -85.682611)
				(end 299.24756 -85.585046)
			)
			(arc
				(start 299.24756 -85.585046)
				(mid 299.253395 -85.572139)
				(end 299.255434 -85.558122)
			)
			(arc
				(start 299.255434 -85.129878)
				(mid 299.25339 -85.115863)
				(end 299.24756 -85.102954)
			)
			(arc
				(start 299.24756 -85.102954)
				(mid 299.203848 -85.005376)
				(end 299.188886 -84.8995)
			)
			(arc
				(start 299.188886 -84.8995)
				(mid 299.203802 -84.793611)
				(end 299.24756 -84.696046)
			)
			(arc
				(start 299.24756 -84.696046)
				(mid 299.253395 -84.683139)
				(end 299.255434 -84.669122)
			)
			(arc
				(start 299.255434 -84.240878)
				(mid 299.25339 -84.226863)
				(end 299.24756 -84.213954)
			)
			(arc
				(start 299.24756 -84.213954)
				(mid 299.203848 -84.116376)
				(end 299.188886 -84.0105)
			)
			(arc
				(start 299.188886 -84.0105)
				(mid 299.203802 -83.904611)
				(end 299.24756 -83.807046)
			)
			(arc
				(start 299.24756 -83.807046)
				(mid 299.253395 -83.794139)
				(end 299.255434 -83.780122)
			)
			(arc
				(start 299.255434 -83.351878)
				(mid 299.25339 -83.337863)
				(end 299.24756 -83.324954)
			)
			(arc
				(start 299.24756 -83.324954)
				(mid 299.203848 -83.227376)
				(end 299.188886 -83.1215)
			)
			(arc
				(start 299.188886 -83.1215)
				(mid 299.203802 -83.015611)
				(end 299.24756 -82.918046)
			)
			(arc
				(start 299.24756 -82.918046)
				(mid 299.253395 -82.905139)
				(end 299.255434 -82.891122)
			)
			(xy 299.255434 -78.790546)
			(arc
				(start 299.254672 -78.786482)
				(mid 299.251029 -78.755972)
				(end 299.249846 -78.725268)
			)
			(arc
				(start 299.249846 -78.725268)
				(mid 299.251022 -78.694563)
				(end 299.254672 -78.664054)
			)
			(xy 299.255434 -78.65999) (xy 299.255434 -77.774546)
			(arc
				(start 299.254672 -77.770482)
				(mid 299.251029 -77.739972)
				(end 299.249846 -77.709268)
			)
			(arc
				(start 299.249846 -77.709268)
				(mid 299.251022 -77.678563)
				(end 299.254672 -77.648054)
			)
			(xy 299.255434 -77.64399) (xy 299.255434 -74.49693)
			(arc
				(start 299.254164 -74.491088)
				(mid 299.24372 -74.43257)
				(end 299.240194 -74.373232)
			)
			(arc
				(start 299.240194 -74.373232)
				(mid 299.243731 -74.313896)
				(end 299.254164 -74.255376)
			)
			(xy 299.255434 -74.249534) (xy 299.255434 -72.839326)
			(arc
				(start 299.254164 -72.833484)
				(mid 299.24372 -72.774966)
				(end 299.240194 -72.715628)
			)
			(arc
				(start 299.240194 -72.715628)
				(mid 299.243731 -72.656292)
				(end 299.254164 -72.597772)
			)
			(xy 299.255434 -72.59193)
			(arc
				(start 299.255434 -61.186822)
				(mid 299.251533 -61.167299)
				(end 299.240448 -61.150754)
			)
			(arc
				(start 298.329858 -60.240164)
				(mid 298.313324 -60.229053)
				(end 298.29379 -60.225178)
			)
			(arc
				(start 279.88006 -60.225178)
				(mid 279.860537 -60.229079)
				(end 279.843992 -60.240164)
			)
			(arc
				(start 278.722836 -61.36132)
				(mid 278.711725 -61.377854)
				(end 278.70785 -61.397388)
			)
			(arc
				(start 278.70785 -94.643956)
				(mid 278.711751 -94.663479)
				(end 278.722836 -94.680024)
			)
			(arc
				(start 279.887426 -95.844614)
				(mid 279.90396 -95.855725)
				(end 279.923494 -95.8596)
			)
		)
		(stroke
			(width 0)
			(type solid)
		)
		(fill yes)
		(layer "In1.Cu")
		(net "P52V_HS1_DRAIN_2")
	)
	(gr_poly
		(pts
			(xy 319.402206 -121.6914) (xy 319.412276 -121.690976) (xy 319.430879 -121.68326) (xy 319.438274 -121.676414)
			(xy 320.406014 -120.708674) (xy 320.412866 -120.701278) (xy 320.420604 -120.682679) (xy 320.421 -120.672606)
			(xy 320.421 -77.091794) (xy 320.420576 -77.081724) (xy 320.41286 -77.063121) (xy 320.406014 -77.055726)
			(xy 319.692274 -76.341986) (xy 319.684878 -76.335134) (xy 319.666279 -76.327396) (xy 319.656206 -76.327)
			(xy 308.6608 -76.327) (xy 308.62754 -76.326479) (xy 308.56159 -76.317791) (xy 308.497339 -76.300566)
			(xy 308.435888 -76.275097) (xy 308.378289 -76.241821) (xy 308.325529 -76.201308) (xy 308.301644 -76.178156)
			(xy 306.185824 -74.062336) (xy 306.178423 -74.055498) (xy 306.159824 -74.047785) (xy 306.149756 -74.04735)
			(xy 301.336964 -74.04735) (xy 301.334932 -74.047858) (xy 301.305357 -74.054617) (xy 301.245124 -74.061872)
			(xy 301.21479 -74.062336) (xy 300.798484 -74.062336) (xy 300.788416 -74.062763) (xy 300.769819 -74.070485)
			(xy 300.762416 -74.077322) (xy 300.28642 -74.553318) (xy 300.279574 -74.560717) (xy 300.271843 -74.579315)
			(xy 300.271434 -74.589386) (xy 300.271434 -88.45423) (xy 300.271729 -88.462103) (xy 300.276515 -88.477104)
			(xy 300.280832 -88.483694) (xy 300.295759 -88.505354) (xy 300.32016 -88.551955) (xy 300.337926 -88.601467)
			(xy 300.348721 -88.652951) (xy 300.352339 -88.705429) (xy 300.348712 -88.757907) (xy 300.33791 -88.809389)
			(xy 300.320136 -88.858899) (xy 300.295729 -88.905496) (xy 300.280832 -88.927178) (xy 300.276501 -88.933762)
			(xy 300.271707 -88.948766) (xy 300.271434 -88.956642) (xy 300.271434 -101.454966) (xy 307.269651 -101.454966)
			(xy 307.273647 -101.2731) (xy 307.285627 -101.091585) (xy 307.305569 -100.910772) (xy 307.333434 -100.731009)
			(xy 307.369168 -100.552644) (xy 307.412701 -100.37602) (xy 307.463951 -100.201479) (xy 307.522818 -100.029357)
			(xy 307.589189 -99.859987) (xy 307.662935 -99.693696) (xy 307.743914 -99.530805) (xy 307.831969 -99.371628)
			(xy 307.926932 -99.216472) (xy 308.028617 -99.065637) (xy 308.13683 -98.919415) (xy 308.251362 -98.778086)
			(xy 308.37199 -98.641925) (xy 308.498483 -98.511193) (xy 308.630596 -98.386144) (xy 308.768074 -98.267018)
			(xy 308.910652 -98.154046) (xy 309.058055 -98.047446) (xy 309.209998 -97.947423) (xy 309.366187 -97.854171)
			(xy 309.526322 -97.767869) (xy 309.690093 -97.688684) (xy 309.857184 -97.616769) (xy 310.027272 -97.552263)
			(xy 310.20003 -97.495291) (xy 310.375124 -97.445961) (xy 310.552215 -97.40437) (xy 310.730962 -97.370597)
			(xy 310.91102 -97.344709) (xy 311.092042 -97.326754) (xy 311.273677 -97.316768) (xy 311.455576 -97.31477)
			(xy 311.637387 -97.320764) (xy 311.818759 -97.334737) (xy 311.999343 -97.356664) (xy 312.178789 -97.386502)
			(xy 312.356751 -97.424193) (xy 312.532886 -97.469664) (xy 312.706854 -97.522828) (xy 312.878318 -97.583582)
			(xy 313.046949 -97.651809) (xy 313.21242 -97.727377) (xy 313.374412 -97.81014) (xy 313.532612 -97.899939)
			(xy 313.686715 -97.9966) (xy 313.836424 -98.099937) (xy 313.981449 -98.209749) (xy 314.121511 -98.325826)
			(xy 314.256339 -98.447943) (xy 314.385673 -98.575864) (xy 314.509264 -98.709343) (xy 314.626872 -98.848121)
			(xy 314.738271 -98.991932) (xy 314.843246 -99.140496) (xy 314.941594 -99.293528) (xy 315.033125 -99.450733)
			(xy 315.117663 -99.611806) (xy 315.195044 -99.776437) (xy 315.265119 -99.944308) (xy 315.327753 -100.115095)
			(xy 315.382824 -100.288468) (xy 315.430228 -100.464093) (xy 315.469871 -100.64163) (xy 315.501678 -100.820737)
			(xy 315.525587 -101.001069) (xy 315.541552 -101.182277) (xy 315.549542 -101.364011) (xy 315.550042 -101.454966)
			(xy 315.549542 -101.545921) (xy 315.541552 -101.727655) (xy 315.525587 -101.908863) (xy 315.501678 -102.089195)
			(xy 315.469871 -102.268302) (xy 315.430228 -102.445839) (xy 315.382824 -102.621464) (xy 315.327753 -102.794837)
			(xy 315.265119 -102.965624) (xy 315.195044 -103.133495) (xy 315.117663 -103.298126) (xy 315.033125 -103.459199)
			(xy 314.941594 -103.616404) (xy 314.843246 -103.769436) (xy 314.738271 -103.918) (xy 314.626872 -104.061811)
			(xy 314.509264 -104.200589) (xy 314.385673 -104.334068) (xy 314.256339 -104.461989) (xy 314.121511 -104.584106)
			(xy 313.981449 -104.700183) (xy 313.836424 -104.809995) (xy 313.686715 -104.913332) (xy 313.532612 -105.009993)
			(xy 313.374412 -105.099792) (xy 313.21242 -105.182555) (xy 313.046949 -105.258123) (xy 312.878318 -105.32635)
			(xy 312.706854 -105.387104) (xy 312.532886 -105.440268) (xy 312.356751 -105.485739) (xy 312.178789 -105.52343)
			(xy 311.999343 -105.553268) (xy 311.818759 -105.575195) (xy 311.637387 -105.589168) (xy 311.455576 -105.595162)
			(xy 311.273677 -105.593164) (xy 311.092042 -105.583178) (xy 310.91102 -105.565223) (xy 310.730962 -105.539335)
			(xy 310.552215 -105.505562) (xy 310.375124 -105.463971) (xy 310.20003 -105.414641) (xy 310.027272 -105.357669)
			(xy 309.857184 -105.293163) (xy 309.690093 -105.221248) (xy 309.526322 -105.142063) (xy 309.366187 -105.055761)
			(xy 309.209998 -104.962509) (xy 309.058055 -104.862486) (xy 308.910652 -104.755886) (xy 308.768074 -104.642914)
			(xy 308.630596 -104.523788) (xy 308.498483 -104.398739) (xy 308.37199 -104.268007) (xy 308.251362 -104.131846)
			(xy 308.13683 -103.990517) (xy 308.028617 -103.844295) (xy 307.926932 -103.69346) (xy 307.831969 -103.538304)
			(xy 307.743914 -103.379127) (xy 307.662935 -103.216236) (xy 307.589189 -103.049945) (xy 307.522818 -102.880575)
			(xy 307.463951 -102.708453) (xy 307.412701 -102.533912) (xy 307.369168 -102.357288) (xy 307.333434 -102.178923)
			(xy 307.305569 -101.99916) (xy 307.285627 -101.818347) (xy 307.273647 -101.636832) (xy 307.269651 -101.454966)
			(xy 300.271434 -101.454966) (xy 300.271434 -120.646698) (xy 300.271857 -120.656768) (xy 300.279575 -120.67537)
			(xy 300.28642 -120.682766) (xy 301.280068 -121.676414) (xy 301.287466 -121.683259) (xy 301.306065 -121.690982)
			(xy 301.316136 -121.6914)
		)
		(stroke
			(width 0)
			(type solid)
		)
		(fill yes)
		(layer "In1.Cu")
		(net "P52V_1")
	)
	(gr_poly
		(pts
			(xy 326.00011 -166.271956) (xy 326.055917 -166.271446) (xy 326.167218 -166.263105) (xy 326.277585 -166.246469)
			(xy 326.386399 -166.221631) (xy 326.493054 -166.188731) (xy 326.596951 -166.147953) (xy 326.697511 -166.099525)
			(xy 326.79417 -166.043717) (xy 326.886389 -165.980841) (xy 326.973651 -165.91125) (xy 327.055468 -165.835332)
			(xy 327.131383 -165.753513) (xy 327.200971 -165.666249) (xy 327.263843 -165.574028) (xy 327.319648 -165.477367)
			(xy 327.368073 -165.376806) (xy 327.408848 -165.272907) (xy 327.441744 -165.166251) (xy 327.466578 -165.057436)
			(xy 327.48321 -164.947068) (xy 327.491548 -164.835767) (xy 327.492106 -164.77996) (xy 327.492106 -150.999952)
			(xy 327.491583 -150.944146) (xy 327.483238 -150.832846) (xy 327.4666 -150.722481) (xy 327.441761 -150.613668)
			(xy 327.408861 -150.507016) (xy 327.368082 -150.40312) (xy 327.319653 -150.302562) (xy 327.263845 -150.205904)
			(xy 327.20097 -150.113687) (xy 327.13138 -150.026426) (xy 327.055463 -149.94461) (xy 326.973645 -149.868695)
			(xy 326.886382 -149.799107) (xy 326.794164 -149.736235) (xy 326.697504 -149.680429) (xy 326.596945 -149.632003)
			(xy 326.493048 -149.591227) (xy 326.386395 -149.558329) (xy 326.277581 -149.533493) (xy 326.167216 -149.516857)
			(xy 326.055916 -149.508516) (xy 326.00011 -149.507956) (xy 154.399996 -149.507956) (xy 154.344188 -149.508478)
			(xy 154.232885 -149.516819) (xy 154.122517 -149.533454) (xy 154.0137 -149.558291) (xy 153.907043 -149.591189)
			(xy 153.803144 -149.631966) (xy 153.702581 -149.680394) (xy 153.605919 -149.7362) (xy 153.513698 -149.799075)
			(xy 153.426433 -149.868664) (xy 153.344612 -149.944581) (xy 153.268693 -150.026399) (xy 153.199101 -150.113662)
			(xy 153.136224 -150.205882) (xy 153.080414 -150.302543) (xy 153.031984 -150.403103) (xy 152.991204 -150.507002)
			(xy 152.958302 -150.613657) (xy 152.933462 -150.722474) (xy 152.916824 -150.832842) (xy 152.908479 -150.944144)
			(xy 152.908 -150.999952) (xy 152.908 -161.844536) (xy 155.304225 -161.844536) (xy 155.304225 -161.715396)
			(xy 155.312175 -161.586501) (xy 155.328045 -161.458341) (xy 155.351774 -161.3314) (xy 155.383273 -161.206161)
			(xy 155.422422 -161.083098) (xy 155.469073 -160.962679) (xy 155.523048 -160.84536) (xy 155.584143 -160.731586)
			(xy 155.652126 -160.621789) (xy 155.72674 -160.516386) (xy 155.807701 -160.415776) (xy 155.894701 -160.320341)
			(xy 155.987412 -160.230442) (xy 156.085482 -160.146421) (xy 156.188537 -160.068597) (xy 156.296188 -159.997265)
			(xy 156.408027 -159.932695) (xy 156.523628 -159.875133) (xy 156.642553 -159.824796) (xy 156.764352 -159.781876)
			(xy 156.888562 -159.746535) (xy 157.014711 -159.718908) (xy 157.142323 -159.699099) (xy 157.270912 -159.687183)
			(xy 157.39999 -159.683207) (xy 157.529068 -159.687183) (xy 157.657657 -159.699099) (xy 157.785269 -159.718908)
			(xy 157.911418 -159.746535) (xy 158.035628 -159.781876) (xy 158.157427 -159.824796) (xy 158.276352 -159.875133)
			(xy 158.391953 -159.932695) (xy 158.503792 -159.997265) (xy 158.611443 -160.068597) (xy 158.714498 -160.146421)
			(xy 158.812568 -160.230442) (xy 158.905279 -160.320341) (xy 158.992279 -160.415776) (xy 159.07324 -160.516386)
			(xy 159.147854 -160.621789) (xy 159.215837 -160.731586) (xy 159.276932 -160.84536) (xy 159.330907 -160.962679)
			(xy 159.377558 -161.083098) (xy 159.416707 -161.206161) (xy 159.448206 -161.3314) (xy 159.471935 -161.458341)
			(xy 159.487805 -161.586501) (xy 159.495755 -161.715396) (xy 159.496252 -161.779966) (xy 159.495755 -161.844536)
			(xy 320.904351 -161.844536) (xy 320.904351 -161.715396) (xy 320.912301 -161.586501) (xy 320.928171 -161.458341)
			(xy 320.9519 -161.3314) (xy 320.983399 -161.206161) (xy 321.022548 -161.083098) (xy 321.069199 -160.962679)
			(xy 321.123174 -160.84536) (xy 321.184269 -160.731586) (xy 321.252252 -160.621789) (xy 321.326866 -160.516386)
			(xy 321.407827 -160.415776) (xy 321.494827 -160.320341) (xy 321.587538 -160.230442) (xy 321.685608 -160.146421)
			(xy 321.788663 -160.068597) (xy 321.896314 -159.997265) (xy 322.008153 -159.932695) (xy 322.123754 -159.875133)
			(xy 322.242679 -159.824796) (xy 322.364478 -159.781876) (xy 322.488688 -159.746535) (xy 322.614837 -159.718908)
			(xy 322.742449 -159.699099) (xy 322.871038 -159.687183) (xy 323.000116 -159.683207) (xy 323.129194 -159.687183)
			(xy 323.257783 -159.699099) (xy 323.385395 -159.718908) (xy 323.511544 -159.746535) (xy 323.635754 -159.781876)
			(xy 323.757553 -159.824796) (xy 323.876478 -159.875133) (xy 323.992079 -159.932695) (xy 324.103918 -159.997265)
			(xy 324.211569 -160.068597) (xy 324.314624 -160.146421) (xy 324.412694 -160.230442) (xy 324.505405 -160.320341)
			(xy 324.592405 -160.415776) (xy 324.673366 -160.516386) (xy 324.74798 -160.621789) (xy 324.815963 -160.731586)
			(xy 324.877058 -160.84536) (xy 324.931033 -160.962679) (xy 324.977684 -161.083098) (xy 325.016833 -161.206161)
			(xy 325.048332 -161.3314) (xy 325.072061 -161.458341) (xy 325.087931 -161.586501) (xy 325.095881 -161.715396)
			(xy 325.096378 -161.779966) (xy 325.095881 -161.844536) (xy 325.087931 -161.973431) (xy 325.072061 -162.101591)
			(xy 325.048332 -162.228532) (xy 325.016833 -162.353771) (xy 324.977684 -162.476834) (xy 324.931033 -162.597253)
			(xy 324.877058 -162.714572) (xy 324.815963 -162.828346) (xy 324.74798 -162.938143) (xy 324.673366 -163.043546)
			(xy 324.592405 -163.144156) (xy 324.505405 -163.239591) (xy 324.412694 -163.32949) (xy 324.314624 -163.413511)
			(xy 324.211569 -163.491335) (xy 324.103918 -163.562667) (xy 323.992079 -163.627237) (xy 323.876478 -163.684799)
			(xy 323.757553 -163.735136) (xy 323.635754 -163.778056) (xy 323.511544 -163.813397) (xy 323.385395 -163.841024)
			(xy 323.257783 -163.860833) (xy 323.129194 -163.872749) (xy 323.000116 -163.876726) (xy 322.871038 -163.872749)
			(xy 322.742449 -163.860833) (xy 322.614837 -163.841024) (xy 322.488688 -163.813397) (xy 322.364478 -163.778056)
			(xy 322.242679 -163.735136) (xy 322.123754 -163.684799) (xy 322.008153 -163.627237) (xy 321.896314 -163.562667)
			(xy 321.788663 -163.491335) (xy 321.685608 -163.413511) (xy 321.587538 -163.32949) (xy 321.494827 -163.239591)
			(xy 321.407827 -163.144156) (xy 321.326866 -163.043546) (xy 321.252252 -162.938143) (xy 321.184269 -162.828346)
			(xy 321.123174 -162.714572) (xy 321.069199 -162.597253) (xy 321.022548 -162.476834) (xy 320.983399 -162.353771)
			(xy 320.9519 -162.228532) (xy 320.928171 -162.101591) (xy 320.912301 -161.973431) (xy 320.904351 -161.844536)
			(xy 159.495755 -161.844536) (xy 159.487805 -161.973431) (xy 159.471935 -162.101591) (xy 159.448206 -162.228532)
			(xy 159.416707 -162.353771) (xy 159.377558 -162.476834) (xy 159.330907 -162.597253) (xy 159.276932 -162.714572)
			(xy 159.215837 -162.828346) (xy 159.147854 -162.938143) (xy 159.07324 -163.043546) (xy 158.992279 -163.144156)
			(xy 158.905279 -163.239591) (xy 158.812568 -163.32949) (xy 158.714498 -163.413511) (xy 158.611443 -163.491335)
			(xy 158.503792 -163.562667) (xy 158.391953 -163.627237) (xy 158.276352 -163.684799) (xy 158.157427 -163.735136)
			(xy 158.035628 -163.778056) (xy 157.911418 -163.813397) (xy 157.785269 -163.841024) (xy 157.657657 -163.860833)
			(xy 157.529068 -163.872749) (xy 157.39999 -163.876726) (xy 157.270912 -163.872749) (xy 157.142323 -163.860833)
			(xy 157.014711 -163.841024) (xy 156.888562 -163.813397) (xy 156.764352 -163.778056) (xy 156.642553 -163.735136)
			(xy 156.523628 -163.684799) (xy 156.408027 -163.627237) (xy 156.296188 -163.562667) (xy 156.188537 -163.491335)
			(xy 156.085482 -163.413511) (xy 155.987412 -163.32949) (xy 155.894701 -163.239591) (xy 155.807701 -163.144156)
			(xy 155.72674 -163.043546) (xy 155.652126 -162.938143) (xy 155.584143 -162.828346) (xy 155.523048 -162.714572)
			(xy 155.469073 -162.597253) (xy 155.422422 -162.476834) (xy 155.383273 -162.353771) (xy 155.351774 -162.228532)
			(xy 155.328045 -162.101591) (xy 155.312175 -161.973431) (xy 155.304225 -161.844536) (xy 152.908 -161.844536)
			(xy 152.908 -164.77996) (xy 152.908508 -164.835769) (xy 152.916846 -164.947074) (xy 152.933479 -165.057444)
			(xy 152.958314 -165.166264) (xy 152.991211 -165.272922) (xy 153.031987 -165.376825) (xy 153.080414 -165.477389)
			(xy 153.13622 -165.574053) (xy 153.199095 -165.666277) (xy 153.268686 -165.753543) (xy 153.344603 -165.835366)
			(xy 153.426423 -165.911286) (xy 153.513688 -165.980879) (xy 153.605909 -166.043756) (xy 153.702572 -166.099566)
			(xy 153.803135 -166.147995) (xy 153.907036 -166.188775) (xy 154.013694 -166.221675) (xy 154.122512 -166.246513)
			(xy 154.232883 -166.263149) (xy 154.344187 -166.271491) (xy 154.399996 -166.271956)
		)
		(stroke
			(width 0)
			(type solid)
		)
		(fill yes)
		(layer "In1.Cu")
		(net "GND3")
	)
	(gr_poly
		(pts
			(xy 266.666472 -146.490944) (xy 323.000116 -146.490944) (xy 323.095449 -146.490445) (xy 323.285943 -146.482352)
			(xy 323.475923 -146.466182) (xy 323.665044 -146.441963) (xy 323.852968 -146.409739) (xy 324.039354 -146.369569)
			(xy 324.223868 -146.321525) (xy 324.406177 -146.265693) (xy 324.585951 -146.202173) (xy 324.762868 -146.131082)
			(xy 324.936608 -146.052545) (xy 325.106858 -145.966706) (xy 325.273312 -145.873718) (xy 325.43567 -145.77375)
			(xy 325.593638 -145.666981) (xy 325.746932 -145.553604) (xy 325.895277 -145.433823) (xy 326.038404 -145.307853)
			(xy 326.176056 -145.175923) (xy 326.307985 -145.03827) (xy 326.433952 -144.895142) (xy 326.553732 -144.746796)
			(xy 326.667107 -144.5935) (xy 326.773875 -144.435531) (xy 326.873841 -144.273173) (xy 326.966827 -144.106718)
			(xy 327.052665 -143.936467) (xy 327.1312 -143.762726) (xy 327.20229 -143.585808) (xy 327.265807 -143.406033)
			(xy 327.321637 -143.223724) (xy 327.36968 -143.03921) (xy 327.409848 -142.852823) (xy 327.44207 -142.664899)
			(xy 327.466287 -142.475777) (xy 327.482455 -142.285798) (xy 327.490546 -142.095303) (xy 327.49109 -141.99997)
			(xy 327.49109 -4.99999) (xy 327.490584 -4.904657) (xy 327.482491 -4.714162) (xy 327.466321 -4.524182)
			(xy 327.442103 -4.335059) (xy 327.40988 -4.147135) (xy 327.36971 -3.960748) (xy 327.321666 -3.776234)
			(xy 327.265834 -3.593925) (xy 327.202315 -3.414149) (xy 327.131224 -3.237232) (xy 327.052688 -3.063491)
			(xy 326.966849 -2.89324) (xy 326.873862 -2.726785) (xy 326.773894 -2.564427) (xy 326.667125 -2.406457)
			(xy 326.553748 -2.253162) (xy 326.433968 -2.104816) (xy 326.307999 -1.961688) (xy 326.176069 -1.824035)
			(xy 326.038416 -1.692105) (xy 325.895288 -1.566136) (xy 325.746943 -1.446355) (xy 325.593648 -1.332978)
			(xy 325.435678 -1.22621) (xy 325.27332 -1.126241) (xy 325.106866 -1.033254) (xy 324.936615 -0.947415)
			(xy 324.762874 -0.868878) (xy 324.585956 -0.797787) (xy 324.406181 -0.734268) (xy 324.223872 -0.678436)
			(xy 324.039358 -0.630391) (xy 323.852971 -0.590221) (xy 323.665046 -0.557998) (xy 323.475924 -0.533779)
			(xy 323.285944 -0.517609) (xy 323.095449 -0.509516) (xy 323.000116 -0.509016) (xy 4.99999 -0.509016)
			(xy 4.904657 -0.509522) (xy 4.714162 -0.517614) (xy 4.524182 -0.533784) (xy 4.335059 -0.558002) (xy 4.147135 -0.590225)
			(xy 3.960748 -0.630394) (xy 3.776233 -0.678438) (xy 3.593924 -0.73427) (xy 3.414149 -0.797788) (xy 3.237231 -0.86888)
			(xy 3.06349 -0.947415) (xy 2.893239 -1.033254) (xy 2.726784 -1.126242) (xy 2.564426 -1.22621) (xy 2.406456 -1.332978)
			(xy 2.253161 -1.446355) (xy 2.104815 -1.566136) (xy 1.961687 -1.692104) (xy 1.824034 -1.824034) (xy 1.692104 -1.961687)
			(xy 1.566136 -2.104815) (xy 1.446355 -2.253161) (xy 1.332978 -2.406456) (xy 1.22621 -2.564426) (xy 1.126242 -2.726784)
			(xy 1.033254 -2.893239) (xy 0.947415 -3.06349) (xy 0.86888 -3.237231) (xy 0.797788 -3.414149) (xy 0.73427 -3.593924)
			(xy 0.678438 -3.776233) (xy 0.630394 -3.960748) (xy 0.590225 -4.147135) (xy 0.558002 -4.335059) (xy 0.553544 -4.36987)
			(xy 242.877075 -4.36987) (xy 242.877075 -4.24073) (xy 242.885025 -4.111835) (xy 242.900895 -3.983675)
			(xy 242.924624 -3.856734) (xy 242.956123 -3.731495) (xy 242.995272 -3.608432) (xy 243.041923 -3.488013)
			(xy 243.095898 -3.370694) (xy 243.156993 -3.25692) (xy 243.224976 -3.147123) (xy 243.29959 -3.04172)
			(xy 243.380551 -2.94111) (xy 243.467551 -2.845675) (xy 243.560262 -2.755776) (xy 243.658332 -2.671755)
			(xy 243.761387 -2.593931) (xy 243.869038 -2.522599) (xy 243.980877 -2.458029) (xy 244.096478 -2.400467)
			(xy 244.215403 -2.35013) (xy 244.337202 -2.30721) (xy 244.461412 -2.271869) (xy 244.587561 -2.244242)
			(xy 244.715173 -2.224433) (xy 244.843762 -2.212517) (xy 244.97284 -2.208541) (xy 245.101918 -2.212517)
			(xy 245.230507 -2.224433) (xy 245.358119 -2.244242) (xy 245.484268 -2.271869) (xy 245.608478 -2.30721)
			(xy 245.730277 -2.35013) (xy 245.849202 -2.400467) (xy 245.964803 -2.458029) (xy 246.076642 -2.522599)
			(xy 246.184293 -2.593931) (xy 246.287348 -2.671755) (xy 246.385418 -2.755776) (xy 246.478129 -2.845675)
			(xy 246.565129 -2.94111) (xy 246.64609 -3.04172) (xy 246.720704 -3.147123) (xy 246.788687 -3.25692)
			(xy 246.849782 -3.370694) (xy 246.903757 -3.488013) (xy 246.950408 -3.608432) (xy 246.989557 -3.731495)
			(xy 247.021056 -3.856734) (xy 247.044785 -3.983675) (xy 247.060655 -4.111835) (xy 247.068605 -4.24073)
			(xy 247.069102 -4.3053) (xy 247.068605 -4.36987) (xy 247.060655 -4.498765) (xy 247.044785 -4.626925)
			(xy 247.021056 -4.753866) (xy 246.989557 -4.879105) (xy 246.950408 -5.002168) (xy 246.903757 -5.122587)
			(xy 246.849782 -5.239906) (xy 246.788687 -5.35368) (xy 246.720704 -5.463477) (xy 246.64609 -5.56888)
			(xy 246.565129 -5.66949) (xy 246.478129 -5.764925) (xy 246.385418 -5.854824) (xy 246.287348 -5.938845)
			(xy 246.184293 -6.016669) (xy 246.076642 -6.088001) (xy 245.964803 -6.152571) (xy 245.849202 -6.210133)
			(xy 245.730277 -6.26047) (xy 245.608478 -6.30339) (xy 245.484268 -6.338731) (xy 245.358119 -6.366358)
			(xy 245.230507 -6.386167) (xy 245.101918 -6.398083) (xy 244.97284 -6.40206) (xy 244.843762 -6.398083)
			(xy 244.715173 -6.386167) (xy 244.587561 -6.366358) (xy 244.461412 -6.338731) (xy 244.337202 -6.30339)
			(xy 244.215403 -6.26047) (xy 244.096478 -6.210133) (xy 243.980877 -6.152571) (xy 243.869038 -6.088001)
			(xy 243.761387 -6.016669) (xy 243.658332 -5.938845) (xy 243.560262 -5.854824) (xy 243.467551 -5.764925)
			(xy 243.380551 -5.66949) (xy 243.29959 -5.56888) (xy 243.224976 -5.463477) (xy 243.156993 -5.35368)
			(xy 243.095898 -5.239906) (xy 243.041923 -5.122587) (xy 242.995272 -5.002168) (xy 242.956123 -4.879105)
			(xy 242.924624 -4.753866) (xy 242.900895 -4.626925) (xy 242.885025 -4.498765) (xy 242.877075 -4.36987)
			(xy 0.553544 -4.36987) (xy 0.533784 -4.524182) (xy 0.517614 -4.714162) (xy 0.509522 -4.904657) (xy 0.509016 -4.99999)
			(xy 0.509016 -11.811) (xy 161.213292 -11.811) (xy 161.21368 -11.772716) (xy 161.220219 -11.696427)
			(xy 161.2333 -11.620985) (xy 161.252827 -11.546948) (xy 161.265362 -11.510772) (xy 161.268013 -11.502335)
			(xy 161.268013 -11.484665) (xy 161.265362 -11.476228) (xy 161.252837 -11.44005) (xy 161.233329 -11.36601)
			(xy 161.220249 -11.290569) (xy 161.213694 -11.214283) (xy 161.213292 -11.176) (xy 161.213787 -11.132867)
			(xy 161.222145 -11.047006) (xy 161.238773 -10.962358) (xy 161.263515 -10.879715) (xy 161.296139 -10.799856)
			(xy 161.336337 -10.723528) (xy 161.383734 -10.651448) (xy 161.437884 -10.584294) (xy 161.498278 -10.522696)
			(xy 161.564351 -10.467231) (xy 161.63548 -10.41842) (xy 161.711 -10.376723) (xy 161.7902 -10.342529)
			(xy 161.872338 -10.316161) (xy 161.956642 -10.297865) (xy 161.999422 -10.292334) (xy 162.010643 -10.290369)
			(xy 162.029893 -10.278242) (xy 162.036506 -10.268966) (xy 162.058636 -10.234762) (xy 162.108294 -10.170172)
			(xy 162.163649 -10.110392) (xy 162.224237 -10.055923) (xy 162.289549 -10.007219) (xy 162.35904 -9.964689)
			(xy 162.432128 -9.928689) (xy 162.508201 -9.899521) (xy 162.586621 -9.877428) (xy 162.666732 -9.862596)
			(xy 162.747864 -9.855149) (xy 162.7886 -9.854692) (xy 162.829702 -9.855167) (xy 162.911557 -9.862752)
			(xy 162.992362 -9.877857) (xy 163.071429 -9.900353) (xy 163.148083 -9.930049) (xy 163.22167 -9.966691)
			(xy 163.291562 -10.009966) (xy 163.357163 -10.059506) (xy 163.417913 -10.114887) (xy 163.473294 -10.175637)
			(xy 163.522834 -10.241238) (xy 163.566109 -10.31113) (xy 163.602751 -10.384717) (xy 163.632447 -10.461371)
			(xy 163.654943 -10.540438) (xy 163.670048 -10.621243) (xy 163.677633 -10.703098) (xy 163.678108 -10.7442)
			(xy 163.677552 -10.788906) (xy 163.668575 -10.877868) (xy 163.650722 -10.96548) (xy 163.624174 -11.050861)
			(xy 163.589197 -11.133148) (xy 163.546144 -11.211513) (xy 163.495449 -11.285166) (xy 163.437624 -11.353364)
			(xy 163.40582 -11.384788) (xy 163.397946 -11.392408) (xy 163.390072 -11.41222) (xy 163.393374 -11.509502)
			(xy 163.402772 -11.528806) (xy 163.411154 -11.535918) (xy 163.44386 -11.564051) (xy 163.50427 -11.625646)
			(xy 163.558433 -11.692801) (xy 163.605841 -11.764883) (xy 163.646049 -11.841217) (xy 163.678677 -11.921084)
			(xy 163.703421 -12.003735) (xy 163.720046 -12.088393) (xy 163.728399 -12.174262) (xy 163.728908 -12.2174)
			(xy 163.728433 -12.258502) (xy 163.720848 -12.340357) (xy 163.705743 -12.421162) (xy 163.683247 -12.500229)
			(xy 163.653551 -12.576883) (xy 163.616909 -12.65047) (xy 163.573634 -12.720362) (xy 163.524094 -12.785963)
			(xy 163.468713 -12.846713) (xy 163.407963 -12.902094) (xy 163.342362 -12.951634) (xy 163.27247 -12.994909)
			(xy 163.198883 -13.031551) (xy 163.122229 -13.061247) (xy 163.043162 -13.083743) (xy 162.962357 -13.098848)
			(xy 162.880502 -13.106433) (xy 162.8394 -13.106908) (xy 162.79634 -13.10644) (xy 162.710622 -13.098119)
			(xy 162.626109 -13.081554) (xy 162.543592 -13.056902) (xy 162.463843 -13.024392) (xy 162.387608 -12.984328)
			(xy 162.315601 -12.937087) (xy 162.248496 -12.883108) (xy 162.18692 -12.822899) (xy 162.131449 -12.757022)
			(xy 162.10661 -12.721844) (xy 162.099372 -12.712425) (xy 162.078566 -12.701028) (xy 162.066732 -12.7)
			(xy 162.02424 -12.697737) (xy 161.939934 -12.686166) (xy 161.857118 -12.666598) (xy 161.776548 -12.639212)
			(xy 161.698961 -12.604258) (xy 161.625066 -12.562056) (xy 161.555538 -12.512991) (xy 161.491013 -12.457512)
			(xy 161.432079 -12.396125) (xy 161.379276 -12.329392) (xy 161.333087 -12.257922) (xy 161.293932 -12.182368)
			(xy 161.26217 -12.103421) (xy 161.23809 -12.021802) (xy 161.221914 -11.938257) (xy 161.213789 -11.853548)
			(xy 161.213292 -11.811) (xy 0.509016 -11.811) (xy 0.509016 -16.070072) (xy 0.509506 -16.139948) (xy 0.517342 -16.279481)
			(xy 0.53299 -16.418355) (xy 0.556399 -16.556133) (xy 0.587497 -16.692382) (xy 0.626186 -16.826673)
			(xy 0.672343 -16.958583) (xy 0.725824 -17.087698) (xy 0.78646 -17.21361) (xy 0.854061 -17.335925)
			(xy 0.928414 -17.454257) (xy 1.009285 -17.568234) (xy 1.09642 -17.677497) (xy 1.189543 -17.781703)
			(xy 1.288363 -17.880523) (xy 1.392569 -17.973646) (xy 1.501832 -18.060781) (xy 1.615809 -18.141652)
			(xy 1.734141 -18.216005) (xy 1.856456 -18.283606) (xy 1.982368 -18.344242) (xy 2.111483 -18.397723)
			(xy 2.243393 -18.44388) (xy 2.377684 -18.482569) (xy 2.513933 -18.513667) (xy 2.651711 -18.537076)
			(xy 2.790585 -18.552724) (xy 2.930118 -18.56056) (xy 2.999994 -18.56105) (xy 9.600184 -18.56105)
			(xy 9.644215 -18.561509) (xy 9.731942 -18.569171) (xy 9.818668 -18.584451) (xy 9.903731 -18.607233)
			(xy 9.986485 -18.637344) (xy 10.066298 -18.674554) (xy 10.142564 -18.71858) (xy 10.214702 -18.769087)
			(xy 10.282162 -18.825691) (xy 10.344431 -18.88796) (xy 10.401034 -18.95542) (xy 10.451541 -19.027557)
			(xy 10.495567 -19.103823) (xy 10.532777 -19.183637) (xy 10.562888 -19.266391) (xy 10.58567 -19.351454)
			(xy 10.60095 -19.43818) (xy 10.608611 -19.525907) (xy 10.609072 -19.569938) (xy 10.609072 -20.997361)
			(xy 276.478742 -20.997361) (xy 276.478742 -20.912639) (xy 276.486795 -20.828302) (xy 276.502829 -20.745112)
			(xy 276.526697 -20.663822) (xy 276.558185 -20.58517) (xy 276.597007 -20.509867) (xy 276.64281 -20.438595)
			(xy 276.695181 -20.371999) (xy 276.753646 -20.310684) (xy 276.817674 -20.255203) (xy 276.886686 -20.20606)
			(xy 276.960056 -20.1637) (xy 277.037121 -20.128505) (xy 277.117183 -20.100796) (xy 277.199516 -20.080822)
			(xy 277.283375 -20.068765) (xy 277.368 -20.064734) (xy 277.452625 -20.068765) (xy 277.536484 -20.080822)
			(xy 277.618817 -20.100796) (xy 277.698879 -20.128505) (xy 277.775944 -20.1637) (xy 277.849314 -20.20606)
			(xy 277.918326 -20.255203) (xy 277.982354 -20.310684) (xy 278.040819 -20.371999) (xy 278.09319 -20.438595)
			(xy 278.138993 -20.509867) (xy 278.177815 -20.58517) (xy 278.209303 -20.663822) (xy 278.233171 -20.745112)
			(xy 278.249205 -20.828302) (xy 278.257258 -20.912639) (xy 278.257762 -20.955) (xy 278.257258 -20.997361)
			(xy 278.249205 -21.081698) (xy 278.233171 -21.164888) (xy 278.209303 -21.246178) (xy 278.177815 -21.32483)
			(xy 278.138993 -21.400133) (xy 278.09319 -21.471405) (xy 278.040819 -21.538001) (xy 277.982354 -21.599316)
			(xy 277.918326 -21.654797) (xy 277.849314 -21.70394) (xy 277.775944 -21.7463) (xy 277.698879 -21.781495)
			(xy 277.618817 -21.809204) (xy 277.536484 -21.829178) (xy 277.452625 -21.841235) (xy 277.368 -21.845267)
			(xy 277.283375 -21.841235) (xy 277.199516 -21.829178) (xy 277.117183 -21.809204) (xy 277.037121 -21.781495)
			(xy 276.960056 -21.7463) (xy 276.886686 -21.70394) (xy 276.817674 -21.654797) (xy 276.753646 -21.599316)
			(xy 276.695181 -21.538001) (xy 276.64281 -21.471405) (xy 276.597007 -21.400133) (xy 276.558185 -21.32483)
			(xy 276.526697 -21.246178) (xy 276.502829 -21.164888) (xy 276.486795 -21.081698) (xy 276.478742 -20.997361)
			(xy 10.609072 -20.997361) (xy 10.609072 -25.329903) (xy 12.90965 -25.329903) (xy 12.913613 -25.189472)
			(xy 12.925487 -25.049488) (xy 12.945237 -24.910397) (xy 12.972799 -24.77264) (xy 13.008084 -24.636657)
			(xy 13.050982 -24.50288) (xy 13.101355 -24.371734) (xy 13.159043 -24.243638) (xy 13.223863 -24.118999)
			(xy 13.295608 -23.998213) (xy 13.374049 -23.881665) (xy 13.458938 -23.769726) (xy 13.550004 -23.662752)
			(xy 13.646958 -23.561083) (xy 13.74949 -23.465043) (xy 13.857275 -23.374937) (xy 13.969969 -23.291053)
			(xy 14.087214 -23.213657) (xy 14.208637 -23.142996) (xy 14.333851 -23.079294) (xy 14.462458 -23.022755)
			(xy 14.594049 -22.973557) (xy 14.728204 -22.931858) (xy 14.864498 -22.89779) (xy 15.002496 -22.871462)
			(xy 15.141758 -22.852958) (xy 15.281843 -22.842336) (xy 15.422304 -22.83963) (xy 15.562693 -22.844849)
			(xy 15.702565 -22.857976) (xy 15.841475 -22.87897) (xy 15.978979 -22.907763) (xy 16.114641 -22.944264)
			(xy 16.248029 -22.988357) (xy 16.378718 -23.039902) (xy 16.506293 -23.098734) (xy 16.630347 -23.164666)
			(xy 16.750486 -23.237489) (xy 16.866328 -23.316971) (xy 16.977503 -23.402858) (xy 17.083658 -23.494878)
			(xy 17.184455 -23.592737) (xy 17.232376 -23.644098) (xy 17.241266 -23.65375) (xy 17.264888 -23.661878)
			(xy 17.3736 -23.645368) (xy 17.393666 -23.630382) (xy 17.399 -23.618698) (xy 17.438143 -23.536826)
			(xy 17.522872 -23.376323) (xy 17.614769 -23.219815) (xy 17.713645 -23.067619) (xy 17.819299 -22.920048)
			(xy 17.931515 -22.777404) (xy 18.050063 -22.639976) (xy 18.174701 -22.508047) (xy 18.305175 -22.381886)
			(xy 18.441218 -22.261751) (xy 18.582551 -22.147887) (xy 18.728885 -22.040528) (xy 18.879923 -21.939892)
			(xy 19.035355 -21.846185) (xy 19.194863 -21.759599) (xy 19.358121 -21.68031) (xy 19.524796 -21.608481)
			(xy 19.694548 -21.544259) (xy 19.867028 -21.487775) (xy 20.041885 -21.439144) (xy 20.218761 -21.398465)
			(xy 20.397295 -21.365823) (xy 20.577122 -21.341282) (xy 20.757875 -21.324895) (xy 20.939183 -21.316693)
			(xy 21.02993 -21.316188) (xy 21.120001 -21.316693) (xy 21.299962 -21.324775) (xy 21.479379 -21.340923)
			(xy 21.657891 -21.365104) (xy 21.835139 -21.39727) (xy 22.010765 -21.437355) (xy 22.184415 -21.48528)
			(xy 22.355741 -21.540947) (xy 22.524396 -21.604244) (xy 22.690042 -21.675045) (xy 22.852345 -21.753206)
			(xy 23.010977 -21.838569) (xy 23.16562 -21.930964) (xy 23.315962 -22.030204) (xy 23.461701 -22.136089)
			(xy 23.602542 -22.248406) (xy 23.738202 -22.366929) (xy 23.868408 -22.491418) (xy 23.992897 -22.621624)
			(xy 24.11142 -22.757284) (xy 24.223737 -22.898125) (xy 24.329622 -23.043864) (xy 24.428862 -23.194206)
			(xy 24.521257 -23.348849) (xy 24.60662 -23.507481) (xy 24.684781 -23.669784) (xy 24.755582 -23.83543)
			(xy 24.818879 -24.004085) (xy 24.874546 -24.175411) (xy 24.922471 -24.349061) (xy 24.962556 -24.524687)
			(xy 24.994722 -24.701935) (xy 25.018903 -24.880447) (xy 25.035051 -25.059864) (xy 25.043133 -25.239825)
			(xy 25.043133 -25.329896) (xy 25.159471 -25.329896) (xy 25.16346 -25.188998) (xy 25.175414 -25.048551)
			(xy 25.195294 -24.909006) (xy 25.223037 -24.770809) (xy 25.258555 -24.634403) (xy 25.301732 -24.500224)
			(xy 25.352432 -24.368704) (xy 25.410492 -24.240262) (xy 25.475724 -24.115311) (xy 25.547922 -23.99425)
			(xy 25.626853 -23.877468) (xy 25.712264 -23.765339) (xy 25.803883 -23.658221) (xy 25.901415 -23.556458)
			(xy 26.004547 -23.460376) (xy 26.112951 -23.370283) (xy 26.226278 -23.286466) (xy 26.344165 -23.209196)
			(xy 26.466235 -23.138719) (xy 26.592097 -23.07526) (xy 26.721347 -23.019025) (xy 26.853572 -22.970191)
			(xy 26.988348 -22.928916) (xy 27.125243 -22.895333) (xy 27.263819 -22.869548) (xy 27.403632 -22.851644)
			(xy 27.544234 -22.841679) (xy 27.685174 -22.839684) (xy 27.826002 -22.845667) (xy 27.966265 -22.859607)
			(xy 28.105515 -22.88146) (xy 28.243306 -22.911156) (xy 28.379196 -22.9486) (xy 28.51275 -22.993672)
			(xy 28.64354 -23.046228) (xy 28.73385 -23.0886) (xy 271.702788 -23.0886) (xy 271.706818 -23.003999)
			(xy 271.718871 -22.920164) (xy 271.738839 -22.837855) (xy 271.766541 -22.757816) (xy 271.801725 -22.680773)
			(xy 271.844074 -22.607423) (xy 271.893203 -22.538431) (xy 271.948668 -22.474421) (xy 272.009966 -22.415973)
			(xy 272.076542 -22.363617) (xy 272.147794 -22.317827) (xy 272.223075 -22.279016) (xy 272.301705 -22.247537)
			(xy 272.382972 -22.223676) (xy 272.466138 -22.207647) (xy 272.550452 -22.199596) (xy 272.5928 -22.199092)
			(xy 272.635108 -22.199589) (xy 272.719344 -22.207592) (xy 272.80244 -22.223553) (xy 272.883646 -22.24733)
			(xy 272.962229 -22.278706) (xy 273.037479 -22.317399) (xy 273.073368 -22.339808) (xy 273.081757 -22.344691)
			(xy 273.1008 -22.348362) (xy 273.119843 -22.344691) (xy 273.128232 -22.339808) (xy 273.164109 -22.317376)
			(xy 273.239354 -22.278665) (xy 273.317937 -22.247279) (xy 273.399147 -22.223503) (xy 273.482249 -22.20755)
			(xy 273.56649 -22.199566) (xy 273.6088 -22.199092) (xy 273.651148 -22.199596) (xy 273.735462 -22.207647)
			(xy 273.818628 -22.223676) (xy 273.899895 -22.247537) (xy 273.978525 -22.279016) (xy 274.053806 -22.317827)
			(xy 274.125058 -22.363617) (xy 274.191634 -22.415973) (xy 274.252932 -22.474421) (xy 274.308397 -22.538431)
			(xy 274.357526 -22.607423) (xy 274.399875 -22.680773) (xy 274.435059 -22.757816) (xy 274.462761 -22.837855)
			(xy 274.482729 -22.920164) (xy 274.494782 -23.003999) (xy 274.498813 -23.0886) (xy 274.494782 -23.173201)
			(xy 274.482729 -23.257036) (xy 274.462761 -23.339345) (xy 274.435059 -23.419384) (xy 274.399875 -23.496427)
			(xy 274.357526 -23.569777) (xy 274.308397 -23.638769) (xy 274.252932 -23.702779) (xy 274.191634 -23.761227)
			(xy 274.125058 -23.813583) (xy 274.053806 -23.859373) (xy 273.978525 -23.898184) (xy 273.899895 -23.929663)
			(xy 273.818628 -23.953524) (xy 273.735462 -23.969553) (xy 273.651148 -23.977604) (xy 273.6088 -23.978108)
			(xy 273.566492 -23.977611) (xy 273.482256 -23.969608) (xy 273.39916 -23.953647) (xy 273.317954 -23.92987)
			(xy 273.239371 -23.898494) (xy 273.164121 -23.859801) (xy 273.128232 -23.837392) (xy 273.119843 -23.832509)
			(xy 273.1008 -23.828838) (xy 273.081757 -23.832509) (xy 273.073368 -23.837392) (xy 273.037491 -23.859824)
			(xy 272.962246 -23.898535) (xy 272.883663 -23.929921) (xy 272.802453 -23.953697) (xy 272.719351 -23.96965)
			(xy 272.63511 -23.977634) (xy 272.5928 -23.978108) (xy 272.550452 -23.977604) (xy 272.466138 -23.969553)
			(xy 272.382972 -23.953524) (xy 272.301705 -23.929663) (xy 272.223075 -23.898184) (xy 272.147794 -23.859373)
			(xy 272.076542 -23.813583) (xy 272.009966 -23.761227) (xy 271.948668 -23.702779) (xy 271.893203 -23.638769)
			(xy 271.844074 -23.569777) (xy 271.801725 -23.496427) (xy 271.766541 -23.419384) (xy 271.738839 -23.339345)
			(xy 271.718871 -23.257036) (xy 271.706818 -23.173201) (xy 271.702788 -23.0886) (xy 28.73385 -23.0886)
			(xy 28.771147 -23.106099) (xy 28.895163 -23.173094) (xy 29.015189 -23.246997) (xy 29.130843 -23.327573)
			(xy 29.241752 -23.414562) (xy 29.347563 -23.507687) (xy 29.447935 -23.606649) (xy 29.542548 -23.711131)
			(xy 29.631099 -23.820799) (xy 29.713303 -23.935301) (xy 29.788897 -24.05427) (xy 29.85764 -24.177325)
			(xy 29.919311 -24.304072) (xy 29.973712 -24.434105) (xy 30.02067 -24.567008) (xy 30.060033 -24.702354)
			(xy 30.091676 -24.839711) (xy 30.115498 -24.978638) (xy 30.131421 -25.11869) (xy 30.139396 -25.259419)
			(xy 30.139894 -25.329896) (xy 30.139396 -25.400373) (xy 30.131421 -25.541102) (xy 30.125683 -25.59157)
			(xy 42.354235 -25.59157) (xy 42.354235 -25.46243) (xy 42.362185 -25.333535) (xy 42.378055 -25.205375)
			(xy 42.401784 -25.078434) (xy 42.433283 -24.953195) (xy 42.472432 -24.830132) (xy 42.519083 -24.709713)
			(xy 42.573058 -24.592394) (xy 42.634153 -24.47862) (xy 42.702136 -24.368823) (xy 42.77675 -24.26342)
			(xy 42.857711 -24.16281) (xy 42.944711 -24.067375) (xy 43.037422 -23.977476) (xy 43.135492 -23.893455)
			(xy 43.238547 -23.815631) (xy 43.346198 -23.744299) (xy 43.458037 -23.679729) (xy 43.573638 -23.622167)
			(xy 43.692563 -23.57183) (xy 43.814362 -23.52891) (xy 43.938572 -23.493569) (xy 44.064721 -23.465942)
			(xy 44.192333 -23.446133) (xy 44.320922 -23.434217) (xy 44.45 -23.430241) (xy 44.579078 -23.434217)
			(xy 44.707667 -23.446133) (xy 44.835279 -23.465942) (xy 44.961428 -23.493569) (xy 45.085638 -23.52891)
			(xy 45.207437 -23.57183) (xy 45.326362 -23.622167) (xy 45.441963 -23.679729) (xy 45.553802 -23.744299)
			(xy 45.661453 -23.815631) (xy 45.764508 -23.893455) (xy 45.862578 -23.977476) (xy 45.955289 -24.067375)
			(xy 46.042289 -24.16281) (xy 46.12325 -24.26342) (xy 46.197864 -24.368823) (xy 46.265847 -24.47862)
			(xy 46.326942 -24.592394) (xy 46.380917 -24.709713) (xy 46.427568 -24.830132) (xy 46.466717 -24.953195)
			(xy 46.498216 -25.078434) (xy 46.521945 -25.205375) (xy 46.537815 -25.333535) (xy 46.545765 -25.46243)
			(xy 46.546262 -25.527) (xy 46.545765 -25.59157) (xy 46.537815 -25.720465) (xy 46.521945 -25.848625)
			(xy 46.498216 -25.975566) (xy 46.466717 -26.100805) (xy 46.427568 -26.223868) (xy 46.380917 -26.344287)
			(xy 46.326942 -26.461606) (xy 46.265847 -26.57538) (xy 46.197864 -26.685177) (xy 46.12325 -26.79058)
			(xy 46.042289 -26.89119) (xy 45.955289 -26.986625) (xy 45.862578 -27.076524) (xy 45.764508 -27.160545)
			(xy 45.661453 -27.238369) (xy 45.553802 -27.309701) (xy 45.441963 -27.374271) (xy 45.326362 -27.431833)
			(xy 45.207437 -27.48217) (xy 45.085638 -27.52509) (xy 44.961428 -27.560431) (xy 44.835279 -27.588058)
			(xy 44.707667 -27.607867) (xy 44.579078 -27.619783) (xy 44.45 -27.62376) (xy 44.320922 -27.619783)
			(xy 44.192333 -27.607867) (xy 44.064721 -27.588058) (xy 43.938572 -27.560431) (xy 43.814362 -27.52509)
			(xy 43.692563 -27.48217) (xy 43.573638 -27.431833) (xy 43.458037 -27.374271) (xy 43.346198 -27.309701)
			(xy 43.238547 -27.238369) (xy 43.135492 -27.160545) (xy 43.037422 -27.076524) (xy 42.944711 -26.986625)
			(xy 42.857711 -26.89119) (xy 42.77675 -26.79058) (xy 42.702136 -26.685177) (xy 42.634153 -26.57538)
			(xy 42.573058 -26.461606) (xy 42.519083 -26.344287) (xy 42.472432 -26.223868) (xy 42.433283 -26.100805)
			(xy 42.401784 -25.975566) (xy 42.378055 -25.848625) (xy 42.362185 -25.720465) (xy 42.354235 -25.59157)
			(xy 30.125683 -25.59157) (xy 30.115498 -25.681154) (xy 30.091676 -25.820081) (xy 30.060033 -25.957438)
			(xy 30.02067 -26.092784) (xy 29.973712 -26.225687) (xy 29.919311 -26.35572) (xy 29.85764 -26.482467)
			(xy 29.788897 -26.605522) (xy 29.713303 -26.724491) (xy 29.631099 -26.838993) (xy 29.542548 -26.948661)
			(xy 29.447935 -27.053143) (xy 29.347563 -27.152105) (xy 29.241752 -27.24523) (xy 29.130843 -27.332219)
			(xy 29.015189 -27.412795) (xy 28.895163 -27.486698) (xy 28.771147 -27.553693) (xy 28.64354 -27.613564)
			(xy 28.51275 -27.66612) (xy 28.379196 -27.711192) (xy 28.243306 -27.748636) (xy 28.105515 -27.778332)
			(xy 27.966265 -27.800185) (xy 27.826002 -27.814125) (xy 27.685174 -27.820108) (xy 27.544234 -27.818113)
			(xy 27.403632 -27.808148) (xy 27.263819 -27.790244) (xy 27.125243 -27.764459) (xy 26.988348 -27.730876)
			(xy 26.853572 -27.689601) (xy 26.721347 -27.640767) (xy 26.592097 -27.584532) (xy 26.466235 -27.521073)
			(xy 26.344165 -27.450596) (xy 26.226278 -27.373326) (xy 26.112951 -27.289509) (xy 26.004547 -27.199416)
			(xy 25.901415 -27.103334) (xy 25.803883 -27.001571) (xy 25.712264 -26.894453) (xy 25.626853 -26.782324)
			(xy 25.547922 -26.665542) (xy 25.475724 -26.544481) (xy 25.410492 -26.41953) (xy 25.352432 -26.291088)
			(xy 25.301732 -26.159568) (xy 25.258555 -26.025389) (xy 25.223037 -25.888983) (xy 25.195294 -25.750786)
			(xy 25.175414 -25.611241) (xy 25.16346 -25.470794) (xy 25.159471 -25.329896) (xy 25.043133 -25.329896)
			(xy 25.043133 -25.419967) (xy 25.035051 -25.599928) (xy 25.018903 -25.779345) (xy 24.994722 -25.957857)
			(xy 24.962556 -26.135105) (xy 24.922471 -26.310731) (xy 24.874546 -26.484381) (xy 24.818879 -26.655707)
			(xy 24.755582 -26.824362) (xy 24.684781 -26.990008) (xy 24.60662 -27.152311) (xy 24.521257 -27.310943)
			(xy 24.428862 -27.465586) (xy 24.329622 -27.615928) (xy 24.223737 -27.761667) (xy 24.11142 -27.902508)
			(xy 23.992897 -28.038168) (xy 23.868408 -28.168374) (xy 23.738202 -28.292863) (xy 23.602542 -28.411386)
			(xy 23.461701 -28.523703) (xy 23.315962 -28.629588) (xy 23.16562 -28.728828) (xy 23.010977 -28.821223)
			(xy 22.852345 -28.906586) (xy 22.690042 -28.984747) (xy 22.524396 -29.055548) (xy 22.355741 -29.118845)
			(xy 22.184415 -29.174512) (xy 22.010765 -29.222437) (xy 21.835139 -29.262522) (xy 21.657891 -29.294688)
			(xy 21.479379 -29.318869) (xy 21.299962 -29.335017) (xy 21.120001 -29.343099) (xy 21.02993 -29.343604)
			(xy 20.939184 -29.343097) (xy 20.757877 -29.334889) (xy 20.577127 -29.318497) (xy 20.397302 -29.293952)
			(xy 20.21877 -29.261305) (xy 20.041895 -29.220623) (xy 19.867041 -29.171989) (xy 19.694562 -29.115502)
			(xy 19.524813 -29.051278) (xy 19.35814 -28.979448) (xy 19.194884 -28.900158) (xy 19.035377 -28.813572)
			(xy 18.879947 -28.719865) (xy 18.728911 -28.61923) (xy 18.582577 -28.511871) (xy 18.441244 -28.398009)
			(xy 18.305202 -28.277876) (xy 18.174728 -28.151717) (xy 18.050089 -28.01979) (xy 17.93154 -27.882366)
			(xy 17.819322 -27.739724) (xy 17.713666 -27.592156) (xy 17.614787 -27.439964) (xy 17.522887 -27.283459)
			(xy 17.438154 -27.12296) (xy 17.399 -27.041094) (xy 17.393666 -27.02941) (xy 17.3736 -27.014424)
			(xy 17.264888 -26.997914) (xy 17.241266 -27.006042) (xy 17.232376 -27.015694) (xy 17.184459 -27.067059)
			(xy 17.083662 -27.164918) (xy 16.977507 -27.256938) (xy 16.866332 -27.342826) (xy 16.750491 -27.422308)
			(xy 16.630352 -27.495131) (xy 16.506298 -27.561063) (xy 16.378724 -27.619896) (xy 16.248035 -27.671441)
			(xy 16.114647 -27.715534) (xy 15.978985 -27.752036) (xy 15.841481 -27.780829) (xy 15.702571 -27.801823)
			(xy 15.562699 -27.814951) (xy 15.42231 -27.82017) (xy 15.281849 -27.817465) (xy 15.141764 -27.806843)
			(xy 15.002501 -27.788339) (xy 14.864504 -27.762011) (xy 14.72821 -27.727944) (xy 14.594054 -27.686245)
			(xy 14.462464 -27.637048) (xy 14.333856 -27.580508) (xy 14.208642 -27.516807) (xy 14.087219 -27.446146)
			(xy 13.969974 -27.36875) (xy 13.857279 -27.284866) (xy 13.749494 -27.194761) (xy 13.646962 -27.098721)
			(xy 13.550008 -26.997053) (xy 13.458942 -26.890079) (xy 13.374053 -26.77814) (xy 13.295611 -26.661592)
			(xy 13.223866 -26.540806) (xy 13.159046 -26.416167) (xy 13.101357 -26.288071) (xy 13.050984 -26.156926)
			(xy 13.008086 -26.023149) (xy 12.9728 -25.887166) (xy 12.945238 -25.749409) (xy 12.925488 -25.610318)
			(xy 12.913613 -25.470334) (xy 12.90965 -25.329903) (xy 10.609072 -25.329903) (xy 10.609072 -31.070042)
			(xy 10.608582 -31.114068) (xy 10.600889 -31.201783) (xy 10.585583 -31.288494) (xy 10.562781 -31.373542)
			(xy 10.532655 -31.456279) (xy 10.495435 -31.536078) (xy 10.451404 -31.61233) (xy 10.400897 -31.684456)
			(xy 10.344298 -31.751907) (xy 10.282038 -31.81417) (xy 10.214589 -31.870772) (xy 10.142465 -31.921282)
			(xy 10.066215 -31.965316) (xy 9.986418 -32.002539) (xy 9.903682 -32.032668) (xy 9.818635 -32.055474)
			(xy 9.731924 -32.070783) (xy 9.64421 -32.07848) (xy 9.600184 -32.07893) (xy 2.999994 -32.07893) (xy 2.930118 -32.07942)
			(xy 2.790585 -32.087256) (xy 2.651711 -32.102904) (xy 2.513933 -32.126313) (xy 2.377684 -32.157411)
			(xy 2.243393 -32.1961) (xy 2.111483 -32.242257) (xy 1.982368 -32.295738) (xy 1.856456 -32.356374)
			(xy 1.734141 -32.423975) (xy 1.615809 -32.498328) (xy 1.501832 -32.579199) (xy 1.392569 -32.666334)
			(xy 1.288363 -32.759457) (xy 1.189543 -32.858277) (xy 1.09642 -32.962483) (xy 1.04643 -33.025168)
			(xy 59.677545 -33.025168) (xy 59.677545 -32.854812) (xy 59.68553 -32.684644) (xy 59.701482 -32.515037)
			(xy 59.725367 -32.346365) (xy 59.757131 -32.178997) (xy 59.796706 -32.013302) (xy 59.844003 -31.849644)
			(xy 59.89892 -31.688383) (xy 59.961335 -31.529873) (xy 60.031111 -31.374463) (xy 60.108094 -31.222495)
			(xy 60.192116 -31.074301) (xy 60.282992 -30.930209) (xy 60.380522 -30.790535) (xy 60.484492 -30.655586)
			(xy 60.594673 -30.525658) (xy 60.710822 -30.401038) (xy 60.832686 -30.281999) (xy 60.959994 -30.168803)
			(xy 61.092469 -30.061698) (xy 61.229819 -29.960921) (xy 61.371741 -29.866692) (xy 61.517923 -29.779219)
			(xy 61.668046 -29.698694) (xy 61.821777 -29.625294) (xy 61.97878 -29.55918) (xy 62.13871 -29.500498)
			(xy 62.301214 -29.449377) (xy 62.465935 -29.405929) (xy 62.632513 -29.37025) (xy 62.800579 -29.342418)
			(xy 62.969765 -29.322494) (xy 63.139699 -29.310522) (xy 63.310008 -29.306529) (xy 63.480317 -29.310522)
			(xy 63.650251 -29.322494) (xy 63.819437 -29.342418) (xy 63.987503 -29.37025) (xy 64.154081 -29.405929)
			(xy 64.318802 -29.449377) (xy 64.481306 -29.500498) (xy 64.641236 -29.55918) (xy 64.798239 -29.625294)
			(xy 64.95197 -29.698694) (xy 65.102093 -29.779219) (xy 65.248275 -29.866692) (xy 65.390197 -29.960921)
			(xy 65.527547 -30.061698) (xy 65.660022 -30.168803) (xy 65.78733 -30.281999) (xy 65.909194 -30.401038)
			(xy 66.025343 -30.525658) (xy 66.135524 -30.655586) (xy 66.239494 -30.790535) (xy 66.337024 -30.930209)
			(xy 66.4279 -31.074301) (xy 66.511922 -31.222495) (xy 66.588905 -31.374463) (xy 66.658681 -31.529873)
			(xy 66.721096 -31.688383) (xy 66.776013 -31.849644) (xy 66.82331 -32.013302) (xy 66.862885 -32.178997)
			(xy 66.894649 -32.346365) (xy 66.918534 -32.515037) (xy 66.934486 -32.684644) (xy 66.942471 -32.854812)
			(xy 66.94297 -32.93999) (xy 66.942471 -33.025168) (xy 66.934486 -33.195336) (xy 66.918534 -33.364943)
			(xy 66.894649 -33.533615) (xy 66.862885 -33.700983) (xy 66.82331 -33.866678) (xy 66.776013 -34.030336)
			(xy 66.721096 -34.191597) (xy 66.658681 -34.350107) (xy 66.588905 -34.505517) (xy 66.511922 -34.657485)
			(xy 66.4279 -34.805679) (xy 66.337024 -34.949771) (xy 66.239494 -35.089445) (xy 66.135524 -35.224394)
			(xy 66.025343 -35.354322) (xy 65.909194 -35.478942) (xy 65.78733 -35.597981) (xy 65.660022 -35.711177)
			(xy 65.527547 -35.818282) (xy 65.390197 -35.919059) (xy 65.248275 -36.013288) (xy 65.102093 -36.100761)
			(xy 64.95197 -36.181286) (xy 64.798239 -36.254686) (xy 64.641236 -36.3208) (xy 64.481306 -36.379482)
			(xy 64.318802 -36.430603) (xy 64.154081 -36.474051) (xy 63.987503 -36.50973) (xy 63.819437 -36.537562)
			(xy 63.650251 -36.557486) (xy 63.480317 -36.569458) (xy 63.310008 -36.573452) (xy 63.139699 -36.569458)
			(xy 62.969765 -36.557486) (xy 62.800579 -36.537562) (xy 62.632513 -36.50973) (xy 62.465935 -36.474051)
			(xy 62.301214 -36.430603) (xy 62.13871 -36.379482) (xy 61.97878 -36.3208) (xy 61.821777 -36.254686)
			(xy 61.668046 -36.181286) (xy 61.517923 -36.100761) (xy 61.371741 -36.013288) (xy 61.229819 -35.919059)
			(xy 61.092469 -35.818282) (xy 60.959994 -35.711177) (xy 60.832686 -35.597981) (xy 60.710822 -35.478942)
			(xy 60.594673 -35.354322) (xy 60.484492 -35.224394) (xy 60.380522 -35.089445) (xy 60.282992 -34.949771)
			(xy 60.192116 -34.805679) (xy 60.108094 -34.657485) (xy 60.031111 -34.505517) (xy 59.961335 -34.350107)
			(xy 59.89892 -34.191597) (xy 59.844003 -34.030336) (xy 59.796706 -33.866678) (xy 59.757131 -33.700983)
			(xy 59.725367 -33.533615) (xy 59.701482 -33.364943) (xy 59.68553 -33.195336) (xy 59.677545 -33.025168)
			(xy 1.04643 -33.025168) (xy 1.009285 -33.071746) (xy 0.928414 -33.185723) (xy 0.854061 -33.304055)
			(xy 0.78646 -33.42637) (xy 0.725824 -33.552282) (xy 0.672343 -33.681397) (xy 0.626186 -33.813307)
			(xy 0.587497 -33.947598) (xy 0.556399 -34.083847) (xy 0.53299 -34.221625) (xy 0.517342 -34.360499)
			(xy 0.509506 -34.500032) (xy 0.509016 -34.569908) (xy 0.509016 -38.019995) (xy 100.644828 -38.019995)
			(xy 100.648734 -37.915497) (xy 100.660427 -37.811582) (xy 100.679843 -37.70883) (xy 100.706873 -37.607813)
			(xy 100.741368 -37.509096) (xy 100.783133 -37.413228) (xy 100.831937 -37.320744) (xy 100.887507 -37.232161)
			(xy 100.949533 -37.147972) (xy 101.017669 -37.068647) (xy 101.091536 -36.994629) (xy 101.17072 -36.926329)
			(xy 101.254781 -36.86413) (xy 101.298756 -36.835842) (xy 101.309932 -36.82873) (xy 101.322378 -36.806378)
			(xy 101.322378 -36.693602) (xy 101.309932 -36.67125) (xy 101.298756 -36.664138) (xy 101.254773 -36.635864)
			(xy 101.170712 -36.573664) (xy 101.091528 -36.505364) (xy 101.017662 -36.431345) (xy 100.949526 -36.352019)
			(xy 100.887501 -36.26783) (xy 100.831931 -36.179246) (xy 100.783128 -36.086763) (xy 100.741364 -35.990894)
			(xy 100.70687 -35.892176) (xy 100.67984 -35.79116) (xy 100.660425 -35.688407) (xy 100.648733 -35.584492)
			(xy 100.644828 -35.479995) (xy 100.648734 -35.375497) (xy 100.660427 -35.271582) (xy 100.679843 -35.16883)
			(xy 100.706873 -35.067813) (xy 100.741368 -34.969096) (xy 100.783133 -34.873228) (xy 100.831937 -34.780744)
			(xy 100.887507 -34.692161) (xy 100.949533 -34.607972) (xy 101.017669 -34.528647) (xy 101.091536 -34.454629)
			(xy 101.17072 -34.386329) (xy 101.254781 -34.32413) (xy 101.298756 -34.295842) (xy 101.309932 -34.28873)
			(xy 101.322378 -34.266378) (xy 101.322378 -34.153602) (xy 101.309932 -34.13125) (xy 101.298756 -34.124138)
			(xy 101.253104 -34.094742) (xy 101.165995 -34.029905) (xy 101.084174 -33.95851) (xy 101.008134 -33.880988)
			(xy 100.938332 -33.797804) (xy 100.875189 -33.709459) (xy 100.819084 -33.616486) (xy 100.770355 -33.519443)
			(xy 100.729295 -33.418915) (xy 100.696152 -33.315506) (xy 100.671124 -33.209839) (xy 100.654363 -33.102551)
			(xy 100.645969 -32.994285) (xy 100.645468 -32.93999) (xy 100.645985 -32.887639) (xy 100.653809 -32.783228)
			(xy 100.669413 -32.679695) (xy 100.692709 -32.577616) (xy 100.723568 -32.477564) (xy 100.761816 -32.380097)
			(xy 100.807239 -32.28576) (xy 100.859585 -32.195082) (xy 100.91856 -32.108567) (xy 100.983834 -32.026702)
			(xy 101.055043 -31.949942) (xy 101.131788 -31.878718) (xy 101.213641 -31.813427) (xy 101.300143 -31.754435)
			(xy 101.390811 -31.702071) (xy 101.485138 -31.656629) (xy 101.582598 -31.618361) (xy 101.682644 -31.587482)
			(xy 101.784717 -31.564166) (xy 101.888248 -31.548541) (xy 101.992657 -31.540696) (xy 102.045008 -31.540196)
			(xy 102.099308 -31.540684) (xy 102.207582 -31.549102) (xy 102.314878 -31.565887) (xy 102.42055 -31.590938)
			(xy 102.523962 -31.624104) (xy 102.624493 -31.665187) (xy 102.721537 -31.713937) (xy 102.81451 -31.770063)
			(xy 102.902853 -31.833226) (xy 102.986035 -31.903047) (xy 103.063555 -31.979105) (xy 103.134946 -32.060943)
			(xy 103.199779 -32.148068) (xy 103.229156 -32.193738) (xy 103.236268 -32.204914) (xy 103.25862 -32.21736)
			(xy 103.371396 -32.21736) (xy 103.393748 -32.204914) (xy 103.40086 -32.193738) (xy 103.430248 -32.148075)
			(xy 103.49508 -32.060952) (xy 103.566471 -31.979116) (xy 103.643991 -31.903059) (xy 103.727172 -31.83324)
			(xy 103.815514 -31.770078) (xy 103.908487 -31.713954) (xy 104.00553 -31.665205) (xy 104.106059 -31.624125)
			(xy 104.20947 -31.59096) (xy 104.315141 -31.56591) (xy 104.422436 -31.549126) (xy 104.530708 -31.540709)
			(xy 104.585008 -31.540196) (xy 104.637364 -31.54063) (xy 104.741784 -31.548457) (xy 104.845326 -31.564066)
			(xy 104.947413 -31.58737) (xy 105.047472 -31.618239) (xy 105.144944 -31.6565) (xy 105.239283 -31.701939)
			(xy 105.329963 -31.754302) (xy 105.416476 -31.813296) (xy 105.498337 -31.878591) (xy 105.57509 -31.949821)
			(xy 105.646304 -32.026588) (xy 105.711581 -32.108464) (xy 105.770557 -32.194989) (xy 105.8229 -32.28568)
			(xy 105.868319 -32.38003) (xy 105.906559 -32.47751) (xy 105.937407 -32.577575) (xy 105.960689 -32.679667)
			(xy 105.976277 -32.783212) (xy 105.984081 -32.887634) (xy 105.984548 -32.93999) (xy 105.984054 -32.994284)
			(xy 105.975641 -33.102545) (xy 105.958864 -33.209828) (xy 105.933825 -33.315489) (xy 105.900673 -33.418892)
			(xy 105.859609 -33.519415) (xy 105.810879 -33.616455) (xy 105.754776 -33.709426) (xy 105.691638 -33.797771)
			(xy 105.621844 -33.880957) (xy 105.545813 -33.958486) (xy 105.464005 -34.029889) (xy 105.376909 -34.094739)
			(xy 105.33126 -34.124138) (xy 105.320084 -34.13125) (xy 105.307638 -34.153602) (xy 105.307638 -34.266378)
			(xy 105.320084 -34.28873) (xy 105.33126 -34.295842) (xy 105.375225 -34.324144) (xy 105.459284 -34.386343)
			(xy 105.538467 -34.454642) (xy 105.612332 -34.52866) (xy 105.680466 -34.607985) (xy 105.742491 -34.692172)
			(xy 105.798059 -34.780755) (xy 105.846862 -34.873237) (xy 105.888627 -34.969104) (xy 105.92312 -35.06782)
			(xy 105.95015 -35.168835) (xy 105.969565 -35.271585) (xy 105.981258 -35.375499) (xy 105.985163 -35.479995)
			(xy 105.981259 -35.584491) (xy 105.969567 -35.688404) (xy 105.950152 -35.791155) (xy 105.923123 -35.89217)
			(xy 105.88863 -35.990887) (xy 105.846867 -36.086753) (xy 105.798065 -36.179236) (xy 105.742497 -36.267819)
			(xy 105.680473 -36.352007) (xy 105.612339 -36.431332) (xy 105.538475 -36.50535) (xy 105.459292 -36.57365)
			(xy 105.375234 -36.63585) (xy 105.33126 -36.664138) (xy 105.320084 -36.67125) (xy 105.307638 -36.693602)
			(xy 105.307638 -36.806378) (xy 105.320084 -36.82873) (xy 105.33126 -36.835842) (xy 105.375225 -36.864144)
			(xy 105.459284 -36.926343) (xy 105.538467 -36.994642) (xy 105.612332 -37.06866) (xy 105.680466 -37.147985)
			(xy 105.742491 -37.232172) (xy 105.798059 -37.320755) (xy 105.846862 -37.413237) (xy 105.888627 -37.509104)
			(xy 105.92312 -37.60782) (xy 105.95015 -37.708835) (xy 105.969565 -37.811585) (xy 105.981258 -37.915499)
			(xy 105.985163 -38.019995) (xy 109.534828 -38.019995) (xy 109.538734 -37.915497) (xy 109.550427 -37.811582)
			(xy 109.569843 -37.70883) (xy 109.596873 -37.607813) (xy 109.631368 -37.509096) (xy 109.673133 -37.413228)
			(xy 109.721937 -37.320744) (xy 109.777507 -37.232161) (xy 109.839533 -37.147972) (xy 109.907669 -37.068647)
			(xy 109.981536 -36.994629) (xy 110.06072 -36.926329) (xy 110.144781 -36.86413) (xy 110.188756 -36.835842)
			(xy 110.199932 -36.82873) (xy 110.212378 -36.806378) (xy 110.212378 -36.693602) (xy 110.199932 -36.67125)
			(xy 110.188756 -36.664138) (xy 110.144773 -36.635864) (xy 110.060712 -36.573664) (xy 109.981528 -36.505364)
			(xy 109.907662 -36.431345) (xy 109.839526 -36.352019) (xy 109.777501 -36.26783) (xy 109.721931 -36.179246)
			(xy 109.673128 -36.086763) (xy 109.631364 -35.990894) (xy 109.59687 -35.892176) (xy 109.56984 -35.79116)
			(xy 109.550425 -35.688407) (xy 109.538733 -35.584492) (xy 109.534828 -35.479995) (xy 109.538734 -35.375497)
			(xy 109.550427 -35.271582) (xy 109.569843 -35.16883) (xy 109.596873 -35.067813) (xy 109.631368 -34.969096)
			(xy 109.673133 -34.873228) (xy 109.721937 -34.780744) (xy 109.777507 -34.692161) (xy 109.839533 -34.607972)
			(xy 109.907669 -34.528647) (xy 109.981536 -34.454629) (xy 110.06072 -34.386329) (xy 110.144781 -34.32413)
			(xy 110.188756 -34.295842) (xy 110.199932 -34.28873) (xy 110.212378 -34.266378) (xy 110.212378 -34.153602)
			(xy 110.199932 -34.13125) (xy 110.188756 -34.124138) (xy 110.143104 -34.094742) (xy 110.055995 -34.029905)
			(xy 109.974174 -33.95851) (xy 109.898134 -33.880988) (xy 109.828332 -33.797804) (xy 109.765189 -33.709459)
			(xy 109.709084 -33.616486) (xy 109.660355 -33.519443) (xy 109.619295 -33.418915) (xy 109.586152 -33.315506)
			(xy 109.561124 -33.209839) (xy 109.544363 -33.102551) (xy 109.535969 -32.994285) (xy 109.535468 -32.93999)
			(xy 109.535985 -32.887639) (xy 109.543809 -32.783228) (xy 109.559413 -32.679695) (xy 109.582709 -32.577616)
			(xy 109.613568 -32.477564) (xy 109.651816 -32.380097) (xy 109.697239 -32.28576) (xy 109.749585 -32.195082)
			(xy 109.80856 -32.108567) (xy 109.873834 -32.026702) (xy 109.945043 -31.949942) (xy 110.021788 -31.878718)
			(xy 110.103641 -31.813427) (xy 110.190143 -31.754435) (xy 110.280811 -31.702071) (xy 110.375138 -31.656629)
			(xy 110.472598 -31.618361) (xy 110.572644 -31.587482) (xy 110.674717 -31.564166) (xy 110.778248 -31.548541)
			(xy 110.882657 -31.540696) (xy 110.935008 -31.540196) (xy 110.989308 -31.540684) (xy 111.097582 -31.549102)
			(xy 111.204878 -31.565887) (xy 111.31055 -31.590938) (xy 111.413962 -31.624104) (xy 111.514493 -31.665187)
			(xy 111.611537 -31.713937) (xy 111.70451 -31.770063) (xy 111.792853 -31.833226) (xy 111.876035 -31.903047)
			(xy 111.953555 -31.979105) (xy 112.024946 -32.060943) (xy 112.089779 -32.148068) (xy 112.119156 -32.193738)
			(xy 112.126268 -32.204914) (xy 112.14862 -32.21736) (xy 112.261396 -32.21736) (xy 112.283748 -32.204914)
			(xy 112.29086 -32.193738) (xy 112.320248 -32.148075) (xy 112.38508 -32.060952) (xy 112.456471 -31.979116)
			(xy 112.533991 -31.903059) (xy 112.617172 -31.83324) (xy 112.705514 -31.770078) (xy 112.798487 -31.713954)
			(xy 112.89553 -31.665205) (xy 112.996059 -31.624125) (xy 113.09947 -31.59096) (xy 113.205141 -31.56591)
			(xy 113.312436 -31.549126) (xy 113.420708 -31.540709) (xy 113.475008 -31.540196) (xy 113.527364 -31.54063)
			(xy 113.631784 -31.548457) (xy 113.735326 -31.564066) (xy 113.837413 -31.58737) (xy 113.937472 -31.618239)
			(xy 114.034944 -31.6565) (xy 114.129283 -31.701939) (xy 114.219963 -31.754302) (xy 114.306476 -31.813296)
			(xy 114.388337 -31.878591) (xy 114.46509 -31.949821) (xy 114.536304 -32.026588) (xy 114.601581 -32.108464)
			(xy 114.660557 -32.194989) (xy 114.7129 -32.28568) (xy 114.758319 -32.38003) (xy 114.796559 -32.47751)
			(xy 114.827407 -32.577575) (xy 114.850689 -32.679667) (xy 114.866277 -32.783212) (xy 114.874081 -32.887634)
			(xy 114.874548 -32.93999) (xy 114.874054 -32.994284) (xy 114.865641 -33.102545) (xy 114.848864 -33.209828)
			(xy 114.823825 -33.315489) (xy 114.790673 -33.418892) (xy 114.749609 -33.519415) (xy 114.700879 -33.616455)
			(xy 114.644776 -33.709426) (xy 114.581638 -33.797771) (xy 114.511844 -33.880957) (xy 114.435813 -33.958486)
			(xy 114.354005 -34.029889) (xy 114.266909 -34.094739) (xy 114.22126 -34.124138) (xy 114.210084 -34.13125)
			(xy 114.197638 -34.153602) (xy 114.197638 -34.266378) (xy 114.210084 -34.28873) (xy 114.22126 -34.295842)
			(xy 114.265225 -34.324144) (xy 114.349284 -34.386343) (xy 114.428467 -34.454642) (xy 114.502332 -34.52866)
			(xy 114.570466 -34.607985) (xy 114.632491 -34.692172) (xy 114.688059 -34.780755) (xy 114.736862 -34.873237)
			(xy 114.778627 -34.969104) (xy 114.81312 -35.06782) (xy 114.84015 -35.168835) (xy 114.859565 -35.271585)
			(xy 114.871258 -35.375499) (xy 114.875163 -35.479995) (xy 114.871259 -35.584491) (xy 114.859567 -35.688404)
			(xy 114.840152 -35.791155) (xy 114.813123 -35.89217) (xy 114.77863 -35.990887) (xy 114.736867 -36.086753)
			(xy 114.688065 -36.179236) (xy 114.632497 -36.267819) (xy 114.570473 -36.352007) (xy 114.502339 -36.431332)
			(xy 114.428475 -36.50535) (xy 114.349292 -36.57365) (xy 114.265234 -36.63585) (xy 114.22126 -36.664138)
			(xy 114.210084 -36.67125) (xy 114.197638 -36.693602) (xy 114.197638 -36.806378) (xy 114.210084 -36.82873)
			(xy 114.22126 -36.835842) (xy 114.265225 -36.864144) (xy 114.349284 -36.926343) (xy 114.428467 -36.994642)
			(xy 114.502332 -37.06866) (xy 114.570466 -37.147985) (xy 114.632491 -37.232172) (xy 114.688059 -37.320755)
			(xy 114.736862 -37.413237) (xy 114.778627 -37.509104) (xy 114.81312 -37.60782) (xy 114.84015 -37.708835)
			(xy 114.859565 -37.811585) (xy 114.871258 -37.915499) (xy 114.875163 -38.019995) (xy 118.424828 -38.019995)
			(xy 118.428734 -37.915497) (xy 118.440427 -37.811582) (xy 118.459843 -37.70883) (xy 118.486873 -37.607813)
			(xy 118.521368 -37.509096) (xy 118.563133 -37.413228) (xy 118.611937 -37.320744) (xy 118.667507 -37.232161)
			(xy 118.729533 -37.147972) (xy 118.797669 -37.068647) (xy 118.871536 -36.994629) (xy 118.95072 -36.926329)
			(xy 119.034781 -36.86413) (xy 119.078756 -36.835842) (xy 119.089932 -36.82873) (xy 119.102378 -36.806378)
			(xy 119.102378 -36.693602) (xy 119.089932 -36.67125) (xy 119.078756 -36.664138) (xy 119.034773 -36.635864)
			(xy 118.950712 -36.573664) (xy 118.871528 -36.505364) (xy 118.797662 -36.431345) (xy 118.729526 -36.352019)
			(xy 118.667501 -36.26783) (xy 118.611931 -36.179246) (xy 118.563128 -36.086763) (xy 118.521364 -35.990894)
			(xy 118.48687 -35.892176) (xy 118.45984 -35.79116) (xy 118.440425 -35.688407) (xy 118.428733 -35.584492)
			(xy 118.424828 -35.479995) (xy 118.428734 -35.375497) (xy 118.440427 -35.271582) (xy 118.459843 -35.16883)
			(xy 118.486873 -35.067813) (xy 118.521368 -34.969096) (xy 118.563133 -34.873228) (xy 118.611937 -34.780744)
			(xy 118.667507 -34.692161) (xy 118.729533 -34.607972) (xy 118.797669 -34.528647) (xy 118.871536 -34.454629)
			(xy 118.95072 -34.386329) (xy 119.034781 -34.32413) (xy 119.078756 -34.295842) (xy 119.089932 -34.28873)
			(xy 119.102378 -34.266378) (xy 119.102378 -34.153602) (xy 119.089932 -34.13125) (xy 119.078756 -34.124138)
			(xy 119.033104 -34.094742) (xy 118.945995 -34.029905) (xy 118.864174 -33.95851) (xy 118.788134 -33.880988)
			(xy 118.718332 -33.797804) (xy 118.655189 -33.709459) (xy 118.599084 -33.616486) (xy 118.550355 -33.519443)
			(xy 118.509295 -33.418915) (xy 118.476152 -33.315506) (xy 118.451124 -33.209839) (xy 118.434363 -33.102551)
			(xy 118.425969 -32.994285) (xy 118.425468 -32.93999) (xy 118.425985 -32.887639) (xy 118.433809 -32.783228)
			(xy 118.449413 -32.679695) (xy 118.472709 -32.577616) (xy 118.503568 -32.477564) (xy 118.541816 -32.380097)
			(xy 118.587239 -32.28576) (xy 118.639585 -32.195082) (xy 118.69856 -32.108567) (xy 118.763834 -32.026702)
			(xy 118.835043 -31.949942) (xy 118.911788 -31.878718) (xy 118.993641 -31.813427) (xy 119.080143 -31.754435)
			(xy 119.170811 -31.702071) (xy 119.265138 -31.656629) (xy 119.362598 -31.618361) (xy 119.462644 -31.587482)
			(xy 119.564717 -31.564166) (xy 119.668248 -31.548541) (xy 119.772657 -31.540696) (xy 119.825008 -31.540196)
			(xy 119.879301 -31.540735) (xy 119.987561 -31.549143) (xy 120.094844 -31.565914) (xy 120.200505 -31.590948)
			(xy 120.303908 -31.624095) (xy 120.404431 -31.665155) (xy 120.501471 -31.713881) (xy 120.594443 -31.769981)
			(xy 120.682788 -31.833116) (xy 120.765975 -31.902907) (xy 120.843504 -31.978935) (xy 120.914908 -32.060742)
			(xy 120.979758 -32.147836) (xy 121.009156 -32.193484) (xy 121.016268 -32.20466) (xy 121.038874 -32.21736)
			(xy 121.151142 -32.21736) (xy 121.173748 -32.20466) (xy 121.18086 -32.193484) (xy 121.210229 -32.147817)
			(xy 121.275087 -32.060728) (xy 121.346497 -31.978925) (xy 121.42403 -31.902901) (xy 121.507221 -31.833112)
			(xy 121.595568 -31.76998) (xy 121.688542 -31.713882) (xy 121.785583 -31.665156) (xy 121.886107 -31.624095)
			(xy 121.98951 -31.590947) (xy 122.095171 -31.56591) (xy 122.202454 -31.549134) (xy 122.310715 -31.540722)
			(xy 122.365008 -31.540196) (xy 122.417364 -31.54063) (xy 122.521784 -31.548457) (xy 122.625326 -31.564066)
			(xy 122.727413 -31.58737) (xy 122.827472 -31.618239) (xy 122.924944 -31.6565) (xy 123.019283 -31.701939)
			(xy 123.109963 -31.754302) (xy 123.196476 -31.813296) (xy 123.278337 -31.878591) (xy 123.35509 -31.949821)
			(xy 123.426304 -32.026588) (xy 123.491581 -32.108464) (xy 123.550557 -32.194989) (xy 123.6029 -32.28568)
			(xy 123.648319 -32.38003) (xy 123.686559 -32.47751) (xy 123.717407 -32.577575) (xy 123.740689 -32.679667)
			(xy 123.756277 -32.783212) (xy 123.764081 -32.887634) (xy 123.764548 -32.93999) (xy 123.764017 -32.994277)
			(xy 123.761619 -33.025168) (xy 130.797545 -33.025168) (xy 130.797545 -32.854812) (xy 130.80553 -32.684644)
			(xy 130.821482 -32.515037) (xy 130.845367 -32.346365) (xy 130.877131 -32.178997) (xy 130.916706 -32.013302)
			(xy 130.964003 -31.849644) (xy 131.01892 -31.688383) (xy 131.081335 -31.529873) (xy 131.151111 -31.374463)
			(xy 131.228094 -31.222495) (xy 131.312116 -31.074301) (xy 131.402992 -30.930209) (xy 131.500522 -30.790535)
			(xy 131.604492 -30.655586) (xy 131.714673 -30.525658) (xy 131.830822 -30.401038) (xy 131.952686 -30.281999)
			(xy 132.079994 -30.168803) (xy 132.212469 -30.061698) (xy 132.349819 -29.960921) (xy 132.491741 -29.866692)
			(xy 132.637923 -29.779219) (xy 132.788046 -29.698694) (xy 132.941777 -29.625294) (xy 133.09878 -29.55918)
			(xy 133.25871 -29.500498) (xy 133.421214 -29.449377) (xy 133.585935 -29.405929) (xy 133.752513 -29.37025)
			(xy 133.920579 -29.342418) (xy 134.089765 -29.322494) (xy 134.259699 -29.310522) (xy 134.430008 -29.306529)
			(xy 134.600317 -29.310522) (xy 134.770251 -29.322494) (xy 134.939437 -29.342418) (xy 135.107503 -29.37025)
			(xy 135.274081 -29.405929) (xy 135.438802 -29.449377) (xy 135.601306 -29.500498) (xy 135.761236 -29.55918)
			(xy 135.918239 -29.625294) (xy 136.07197 -29.698694) (xy 136.222093 -29.779219) (xy 136.368275 -29.866692)
			(xy 136.510197 -29.960921) (xy 136.647547 -30.061698) (xy 136.780022 -30.168803) (xy 136.90733 -30.281999)
			(xy 137.029194 -30.401038) (xy 137.145343 -30.525658) (xy 137.255524 -30.655586) (xy 137.359494 -30.790535)
			(xy 137.457024 -30.930209) (xy 137.5479 -31.074301) (xy 137.631922 -31.222495) (xy 137.708905 -31.374463)
			(xy 137.778681 -31.529873) (xy 137.841096 -31.688383) (xy 137.896013 -31.849644) (xy 137.94331 -32.013302)
			(xy 137.982885 -32.178997) (xy 138.014649 -32.346365) (xy 138.038534 -32.515037) (xy 138.054486 -32.684644)
			(xy 138.062471 -32.854812) (xy 138.06297 -32.93999) (xy 138.062471 -33.025168) (xy 138.054486 -33.195336)
			(xy 138.038534 -33.364943) (xy 138.014649 -33.533615) (xy 137.982885 -33.700983) (xy 137.94331 -33.866678)
			(xy 137.896013 -34.030336) (xy 137.841096 -34.191597) (xy 137.778681 -34.350107) (xy 137.708905 -34.505517)
			(xy 137.631922 -34.657485) (xy 137.5479 -34.805679) (xy 137.457024 -34.949771) (xy 137.359494 -35.089445)
			(xy 137.255524 -35.224394) (xy 137.145343 -35.354322) (xy 137.029194 -35.478942) (xy 136.90733 -35.597981)
			(xy 136.780022 -35.711177) (xy 136.647547 -35.818282) (xy 136.510197 -35.919059) (xy 136.368275 -36.013288)
			(xy 136.222093 -36.100761) (xy 136.07197 -36.181286) (xy 135.918239 -36.254686) (xy 135.761236 -36.3208)
			(xy 135.601306 -36.379482) (xy 135.438802 -36.430603) (xy 135.274081 -36.474051) (xy 135.107503 -36.50973)
			(xy 134.939437 -36.537562) (xy 134.770251 -36.557486) (xy 134.600317 -36.569458) (xy 134.430008 -36.573452)
			(xy 134.259699 -36.569458) (xy 134.089765 -36.557486) (xy 133.920579 -36.537562) (xy 133.752513 -36.50973)
			(xy 133.585935 -36.474051) (xy 133.421214 -36.430603) (xy 133.25871 -36.379482) (xy 133.09878 -36.3208)
			(xy 132.941777 -36.254686) (xy 132.788046 -36.181286) (xy 132.637923 -36.100761) (xy 132.491741 -36.013288)
			(xy 132.349819 -35.919059) (xy 132.212469 -35.818282) (xy 132.079994 -35.711177) (xy 131.952686 -35.597981)
			(xy 131.830822 -35.478942) (xy 131.714673 -35.354322) (xy 131.604492 -35.224394) (xy 131.500522 -35.089445)
			(xy 131.402992 -34.949771) (xy 131.312116 -34.805679) (xy 131.228094 -34.657485) (xy 131.151111 -34.505517)
			(xy 131.081335 -34.350107) (xy 131.01892 -34.191597) (xy 130.964003 -34.030336) (xy 130.916706 -33.866678)
			(xy 130.877131 -33.700983) (xy 130.845367 -33.533615) (xy 130.821482 -33.364943) (xy 130.80553 -33.195336)
			(xy 130.797545 -33.025168) (xy 123.761619 -33.025168) (xy 123.755614 -33.102525) (xy 123.738851 -33.209797)
			(xy 123.713828 -33.315448) (xy 123.680696 -33.418842) (xy 123.639653 -33.51936) (xy 123.590947 -33.616396)
			(xy 123.53487 -33.709366) (xy 123.471759 -33.797714) (xy 123.401993 -33.880907) (xy 123.325993 -33.958445)
			(xy 123.244214 -34.029862) (xy 123.157148 -34.09473) (xy 123.111514 -34.124138) (xy 123.100338 -34.13125)
			(xy 123.087638 -34.153856) (xy 123.087638 -34.266124) (xy 123.100338 -34.28873) (xy 123.111514 -34.295842)
			(xy 123.157141 -34.325264) (xy 123.244218 -34.39012) (xy 123.326008 -34.461529) (xy 123.402018 -34.53906)
			(xy 123.471791 -34.622249) (xy 123.534909 -34.710595) (xy 123.59099 -34.803566) (xy 123.639698 -34.900603)
			(xy 123.68074 -35.001123) (xy 123.71387 -35.104521) (xy 123.738887 -35.210175) (xy 123.755642 -35.317451)
			(xy 123.764033 -35.425702) (xy 123.764548 -35.47999) (xy 123.764054 -35.534284) (xy 123.755641 -35.642545)
			(xy 123.738864 -35.749828) (xy 123.713825 -35.855489) (xy 123.680673 -35.958892) (xy 123.639609 -36.059415)
			(xy 123.590879 -36.156455) (xy 123.534776 -36.249426) (xy 123.471638 -36.337771) (xy 123.401844 -36.420957)
			(xy 123.325813 -36.498486) (xy 123.244005 -36.569889) (xy 123.156909 -36.634739) (xy 123.11126 -36.664138)
			(xy 123.100084 -36.67125) (xy 123.087638 -36.693602) (xy 123.087638 -36.806378) (xy 123.100084 -36.82873)
			(xy 123.11126 -36.835842) (xy 123.156907 -36.865246) (xy 123.244015 -36.930083) (xy 123.325836 -37.001477)
			(xy 123.401875 -37.078999) (xy 123.471677 -37.162182) (xy 123.534821 -37.250526) (xy 123.590926 -37.343499)
			(xy 123.639655 -37.440541) (xy 123.680716 -37.541068) (xy 123.71386 -37.644476) (xy 123.738888 -37.750142)
			(xy 123.755651 -37.85743) (xy 123.764046 -37.965695) (xy 123.764548 -38.01999) (xy 123.764403 -38.03481)
			(xy 165.292523 -38.03481) (xy 165.292523 -37.864454) (xy 165.300508 -37.694286) (xy 165.31646 -37.524679)
			(xy 165.340345 -37.356007) (xy 165.372109 -37.188639) (xy 165.411684 -37.022944) (xy 165.458981 -36.859286)
			(xy 165.513898 -36.698025) (xy 165.576313 -36.539515) (xy 165.646089 -36.384105) (xy 165.723072 -36.232137)
			(xy 165.807094 -36.083943) (xy 165.89797 -35.939851) (xy 165.9955 -35.800177) (xy 166.09947 -35.665228)
			(xy 166.209651 -35.5353) (xy 166.3258 -35.41068) (xy 166.447664 -35.291641) (xy 166.574972 -35.178445)
			(xy 166.707447 -35.07134) (xy 166.844797 -34.970563) (xy 166.986719 -34.876334) (xy 167.132901 -34.788861)
			(xy 167.283024 -34.708336) (xy 167.436755 -34.634936) (xy 167.593758 -34.568822) (xy 167.753688 -34.51014)
			(xy 167.916192 -34.459019) (xy 168.080913 -34.415571) (xy 168.247491 -34.379892) (xy 168.415557 -34.35206)
			(xy 168.584743 -34.332136) (xy 168.754677 -34.320164) (xy 168.924986 -34.316171) (xy 169.095295 -34.320164)
			(xy 169.265229 -34.332136) (xy 169.434415 -34.35206) (xy 169.602481 -34.379892) (xy 169.769059 -34.415571)
			(xy 169.93378 -34.459019) (xy 170.096284 -34.51014) (xy 170.256214 -34.568822) (xy 170.413217 -34.634936)
			(xy 170.566948 -34.708336) (xy 170.717071 -34.788861) (xy 170.863253 -34.876334) (xy 171.005175 -34.970563)
			(xy 171.142525 -35.07134) (xy 171.275 -35.178445) (xy 171.402308 -35.291641) (xy 171.523084 -35.409617)
			(xy 179.589852 -35.409617) (xy 179.593756 -35.305123) (xy 179.605447 -35.201211) (xy 179.62486 -35.098461)
			(xy 179.651888 -34.997447) (xy 179.686379 -34.898732) (xy 179.728141 -34.802866) (xy 179.776941 -34.710384)
			(xy 179.832508 -34.621802) (xy 179.89453 -34.537614) (xy 179.962662 -34.45829) (xy 180.036524 -34.384272)
			(xy 180.115705 -34.315972) (xy 180.199761 -34.253773) (xy 180.243734 -34.225484) (xy 180.25491 -34.218372)
			(xy 180.267356 -34.19602) (xy 180.267356 -34.083244) (xy 180.25491 -34.060892) (xy 180.243734 -34.05378)
			(xy 180.19979 -34.025447) (xy 180.115731 -33.963249) (xy 180.036549 -33.894952) (xy 179.962685 -33.820935)
			(xy 179.894551 -33.741612) (xy 179.832527 -33.657426) (xy 179.776958 -33.568846) (xy 179.728156 -33.476365)
			(xy 179.686391 -33.3805) (xy 179.651898 -33.281786) (xy 179.624868 -33.180772) (xy 179.605452 -33.078023)
			(xy 179.593758 -32.974112) (xy 179.589852 -32.869617) (xy 179.593756 -32.765123) (xy 179.605447 -32.661211)
			(xy 179.62486 -32.558461) (xy 179.651888 -32.457447) (xy 179.686379 -32.358732) (xy 179.728141 -32.262866)
			(xy 179.776941 -32.170384) (xy 179.832508 -32.081802) (xy 179.89453 -31.997614) (xy 179.962662 -31.91829)
			(xy 180.036524 -31.844272) (xy 180.115705 -31.775972) (xy 180.199761 -31.713773) (xy 180.243734 -31.685484)
			(xy 180.25491 -31.678372) (xy 180.267356 -31.65602) (xy 180.267356 -31.543244) (xy 180.25491 -31.520892)
			(xy 180.243734 -31.51378) (xy 180.198088 -31.484366) (xy 180.110965 -31.419535) (xy 180.029129 -31.348147)
			(xy 179.953072 -31.27063) (xy 179.883253 -31.187451) (xy 179.82009 -31.099111) (xy 179.763965 -31.006141)
			(xy 179.715214 -30.9091) (xy 179.674132 -30.808573) (xy 179.640965 -30.705163) (xy 179.615913 -30.599495)
			(xy 179.599126 -30.492202) (xy 179.590707 -30.383931) (xy 179.590192 -30.329632) (xy 179.590669 -30.277276)
			(xy 179.598492 -30.172858) (xy 179.614099 -30.069316) (xy 179.6374 -29.967231) (xy 179.668266 -29.867172)
			(xy 179.706525 -29.7697) (xy 179.751961 -29.675361) (xy 179.804321 -29.584681) (xy 179.863313 -29.498168)
			(xy 179.928605 -29.416307) (xy 179.999834 -29.339554) (xy 180.076599 -29.26834) (xy 180.158473 -29.203062)
			(xy 180.244996 -29.144086) (xy 180.335685 -29.091742) (xy 180.430033 -29.046323) (xy 180.527512 -29.008082)
			(xy 180.627576 -28.977234) (xy 180.729666 -28.953951) (xy 180.83321 -28.938364) (xy 180.93763 -28.930559)
			(xy 180.989986 -28.930092) (xy 181.044279 -28.930616) (xy 181.152538 -28.939029) (xy 181.259821 -28.955805)
			(xy 181.36548 -28.980843) (xy 181.468882 -29.013992) (xy 181.569405 -29.055055) (xy 181.666444 -29.103782)
			(xy 181.759415 -29.159882) (xy 181.84776 -29.223017) (xy 181.930947 -29.292808) (xy 182.008477 -29.368835)
			(xy 182.079882 -29.45064) (xy 182.144735 -29.537733) (xy 182.174134 -29.58338) (xy 182.181246 -29.594556)
			(xy 182.203598 -29.607002) (xy 182.316374 -29.607002) (xy 182.338726 -29.594556) (xy 182.345838 -29.58338)
			(xy 182.375259 -29.537744) (xy 182.440094 -29.450635) (xy 182.511486 -29.368813) (xy 182.589006 -29.292773)
			(xy 182.672187 -29.22297) (xy 182.760529 -29.159825) (xy 182.853501 -29.103719) (xy 182.950542 -29.054988)
			(xy 183.051068 -29.013927) (xy 183.154475 -28.980782) (xy 183.26014 -28.955753) (xy 183.367427 -28.93899)
			(xy 183.475691 -28.930594) (xy 183.529986 -28.930092) (xy 183.582338 -28.930608) (xy 183.686749 -28.938431)
			(xy 183.790283 -28.954033) (xy 183.892362 -28.977328) (xy 183.992415 -29.008186) (xy 184.089883 -29.046433)
			(xy 184.18422 -29.091856) (xy 184.2749 -29.144202) (xy 184.361415 -29.203176) (xy 184.443281 -29.268451)
			(xy 184.520041 -29.33966) (xy 184.591265 -29.416405) (xy 184.656556 -29.498258) (xy 184.715548 -29.584761)
			(xy 184.767912 -29.67543) (xy 184.813354 -29.769758) (xy 184.851621 -29.867218) (xy 184.882499 -29.967265)
			(xy 184.905814 -30.06934) (xy 184.921437 -30.172871) (xy 184.929281 -30.27728) (xy 184.92978 -30.329632)
			(xy 184.929276 -30.383932) (xy 184.920857 -30.492205) (xy 184.904071 -30.599499) (xy 184.87902 -30.70517)
			(xy 184.845853 -30.808581) (xy 184.804772 -30.909111) (xy 184.756023 -31.006154) (xy 184.699899 -31.099127)
			(xy 184.636737 -31.18747) (xy 184.566919 -31.270653) (xy 184.490864 -31.348173) (xy 184.409029 -31.419566)
			(xy 184.321907 -31.484402) (xy 184.276238 -31.51378) (xy 184.265062 -31.520892) (xy 184.252616 -31.543244)
			(xy 184.252616 -31.65602) (xy 184.265062 -31.678372) (xy 184.276238 -31.685484) (xy 184.320242 -31.713727)
			(xy 184.404303 -31.775928) (xy 184.483488 -31.84423) (xy 184.557355 -31.91825) (xy 184.625491 -31.997578)
			(xy 184.687517 -32.081768) (xy 184.743086 -32.170354) (xy 184.79189 -32.262839) (xy 184.833654 -32.358709)
			(xy 184.868148 -32.457429) (xy 184.895177 -32.558447) (xy 184.914592 -32.661201) (xy 184.926283 -32.765118)
			(xy 184.930187 -32.869617) (xy 184.926281 -32.974116) (xy 184.914587 -33.078032) (xy 184.895169 -33.180786)
			(xy 184.868138 -33.281804) (xy 184.833642 -33.380523) (xy 184.791875 -33.476391) (xy 184.743069 -33.568876)
			(xy 184.687498 -33.65746) (xy 184.62547 -33.741649) (xy 184.557332 -33.820975) (xy 184.483463 -33.894993)
			(xy 184.404277 -33.963293) (xy 184.320214 -34.025492) (xy 184.276238 -34.05378) (xy 184.265062 -34.060892)
			(xy 184.252616 -34.083244) (xy 184.252616 -34.19602) (xy 184.265062 -34.218372) (xy 184.276238 -34.225484)
			(xy 184.320242 -34.253727) (xy 184.404303 -34.315928) (xy 184.483488 -34.38423) (xy 184.557355 -34.45825)
			(xy 184.625491 -34.537578) (xy 184.687517 -34.621768) (xy 184.743086 -34.710354) (xy 184.79189 -34.802839)
			(xy 184.833654 -34.898709) (xy 184.868148 -34.997429) (xy 184.895177 -35.098447) (xy 184.914592 -35.201201)
			(xy 184.926283 -35.305118) (xy 184.930187 -35.409617) (xy 188.479852 -35.409617) (xy 188.483756 -35.305123)
			(xy 188.495447 -35.201211) (xy 188.51486 -35.098461) (xy 188.541888 -34.997447) (xy 188.576379 -34.898732)
			(xy 188.618141 -34.802866) (xy 188.666941 -34.710384) (xy 188.722508 -34.621802) (xy 188.78453 -34.537614)
			(xy 188.852662 -34.45829) (xy 188.926524 -34.384272) (xy 189.005705 -34.315972) (xy 189.089761 -34.253773)
			(xy 189.133734 -34.225484) (xy 189.14491 -34.218372) (xy 189.157356 -34.19602) (xy 189.157356 -34.083244)
			(xy 189.14491 -34.060892) (xy 189.133734 -34.05378) (xy 189.08979 -34.025447) (xy 189.005731 -33.963249)
			(xy 188.926549 -33.894952) (xy 188.852685 -33.820935) (xy 188.784551 -33.741612) (xy 188.722527 -33.657426)
			(xy 188.666958 -33.568846) (xy 188.618156 -33.476365) (xy 188.576391 -33.3805) (xy 188.541898 -33.281786)
			(xy 188.514868 -33.180772) (xy 188.495452 -33.078023) (xy 188.483758 -32.974112) (xy 188.479852 -32.869617)
			(xy 188.483756 -32.765123) (xy 188.495447 -32.661211) (xy 188.51486 -32.558461) (xy 188.541888 -32.457447)
			(xy 188.576379 -32.358732) (xy 188.618141 -32.262866) (xy 188.666941 -32.170384) (xy 188.722508 -32.081802)
			(xy 188.78453 -31.997614) (xy 188.852662 -31.91829) (xy 188.926524 -31.844272) (xy 189.005705 -31.775972)
			(xy 189.089761 -31.713773) (xy 189.133734 -31.685484) (xy 189.14491 -31.678372) (xy 189.157356 -31.65602)
			(xy 189.157356 -31.543244) (xy 189.14491 -31.520892) (xy 189.133734 -31.51378) (xy 189.088088 -31.484366)
			(xy 189.000965 -31.419535) (xy 188.919129 -31.348147) (xy 188.843072 -31.27063) (xy 188.773253 -31.187451)
			(xy 188.71009 -31.099111) (xy 188.653965 -31.006141) (xy 188.605214 -30.9091) (xy 188.564132 -30.808573)
			(xy 188.530965 -30.705163) (xy 188.505913 -30.599495) (xy 188.489126 -30.492202) (xy 188.480707 -30.383931)
			(xy 188.480192 -30.329632) (xy 188.480669 -30.277276) (xy 188.488492 -30.172858) (xy 188.504099 -30.069316)
			(xy 188.5274 -29.967231) (xy 188.558266 -29.867172) (xy 188.596525 -29.7697) (xy 188.641961 -29.675361)
			(xy 188.694321 -29.584681) (xy 188.753313 -29.498168) (xy 188.818605 -29.416307) (xy 188.889834 -29.339554)
			(xy 188.966599 -29.26834) (xy 189.048473 -29.203062) (xy 189.134996 -29.144086) (xy 189.225685 -29.091742)
			(xy 189.320033 -29.046323) (xy 189.417512 -29.008082) (xy 189.517576 -28.977234) (xy 189.619666 -28.953951)
			(xy 189.72321 -28.938364) (xy 189.82763 -28.930559) (xy 189.879986 -28.930092) (xy 189.934279 -28.930616)
			(xy 190.042538 -28.939029) (xy 190.149821 -28.955805) (xy 190.25548 -28.980843) (xy 190.358882 -29.013992)
			(xy 190.459405 -29.055055) (xy 190.556444 -29.103782) (xy 190.649415 -29.159882) (xy 190.73776 -29.223017)
			(xy 190.820947 -29.292808) (xy 190.898477 -29.368835) (xy 190.969882 -29.45064) (xy 191.034735 -29.537733)
			(xy 191.064134 -29.58338) (xy 191.071246 -29.594556) (xy 191.093598 -29.607002) (xy 191.206374 -29.607002)
			(xy 191.228726 -29.594556) (xy 191.235838 -29.58338) (xy 191.265259 -29.537744) (xy 191.330094 -29.450635)
			(xy 191.401486 -29.368813) (xy 191.479006 -29.292773) (xy 191.562187 -29.22297) (xy 191.650529 -29.159825)
			(xy 191.743501 -29.103719) (xy 191.840542 -29.054988) (xy 191.941068 -29.013927) (xy 192.044475 -28.980782)
			(xy 192.15014 -28.955753) (xy 192.257427 -28.93899) (xy 192.365691 -28.930594) (xy 192.419986 -28.930092)
			(xy 192.472338 -28.930608) (xy 192.576749 -28.938431) (xy 192.680283 -28.954033) (xy 192.782362 -28.977328)
			(xy 192.882415 -29.008186) (xy 192.979883 -29.046433) (xy 193.07422 -29.091856) (xy 193.1649 -29.144202)
			(xy 193.251415 -29.203176) (xy 193.333281 -29.268451) (xy 193.410041 -29.33966) (xy 193.481265 -29.416405)
			(xy 193.546556 -29.498258) (xy 193.605548 -29.584761) (xy 193.657912 -29.67543) (xy 193.703354 -29.769758)
			(xy 193.741621 -29.867218) (xy 193.772499 -29.967265) (xy 193.795814 -30.06934) (xy 193.811437 -30.172871)
			(xy 193.819281 -30.27728) (xy 193.81978 -30.329632) (xy 193.819276 -30.383932) (xy 193.810857 -30.492205)
			(xy 193.794071 -30.599499) (xy 193.76902 -30.70517) (xy 193.735853 -30.808581) (xy 193.694772 -30.909111)
			(xy 193.646023 -31.006154) (xy 193.589899 -31.099127) (xy 193.526737 -31.18747) (xy 193.456919 -31.270653)
			(xy 193.380864 -31.348173) (xy 193.299029 -31.419566) (xy 193.211907 -31.484402) (xy 193.166238 -31.51378)
			(xy 193.155062 -31.520892) (xy 193.142616 -31.543244) (xy 193.142616 -31.65602) (xy 193.155062 -31.678372)
			(xy 193.166238 -31.685484) (xy 193.21193 -31.714827) (xy 193.299051 -31.779666) (xy 193.380885 -31.851062)
			(xy 193.456939 -31.928586) (xy 193.526756 -32.011772) (xy 193.589915 -32.100118) (xy 193.646037 -32.193094)
			(xy 193.694783 -32.29014) (xy 193.735861 -32.390673) (xy 193.769024 -32.494087) (xy 193.794071 -32.59976)
			(xy 193.810853 -32.707057) (xy 193.819268 -32.815331) (xy 193.81978 -32.869617) (xy 197.369852 -32.869617)
			(xy 197.373756 -32.765123) (xy 197.385447 -32.661211) (xy 197.40486 -32.558461) (xy 197.431888 -32.457447)
			(xy 197.466379 -32.358732) (xy 197.508141 -32.262866) (xy 197.556941 -32.170384) (xy 197.612508 -32.081802)
			(xy 197.67453 -31.997614) (xy 197.742662 -31.91829) (xy 197.816524 -31.844272) (xy 197.895705 -31.775972)
			(xy 197.979761 -31.713773) (xy 198.023734 -31.685484) (xy 198.03491 -31.678372) (xy 198.047356 -31.65602)
			(xy 198.047356 -31.543244) (xy 198.03491 -31.520892) (xy 198.023734 -31.51378) (xy 197.978088 -31.484366)
			(xy 197.890965 -31.419535) (xy 197.809129 -31.348147) (xy 197.733072 -31.27063) (xy 197.663253 -31.187451)
			(xy 197.60009 -31.099111) (xy 197.543965 -31.006141) (xy 197.495214 -30.9091) (xy 197.454132 -30.808573)
			(xy 197.420965 -30.705163) (xy 197.395913 -30.599495) (xy 197.379126 -30.492202) (xy 197.370707 -30.383931)
			(xy 197.370192 -30.329632) (xy 197.370669 -30.277276) (xy 197.378492 -30.172858) (xy 197.394099 -30.069316)
			(xy 197.4174 -29.967231) (xy 197.448266 -29.867172) (xy 197.486525 -29.7697) (xy 197.531961 -29.675361)
			(xy 197.584321 -29.584681) (xy 197.643313 -29.498168) (xy 197.708605 -29.416307) (xy 197.779834 -29.339554)
			(xy 197.856599 -29.26834) (xy 197.938473 -29.203062) (xy 198.024996 -29.144086) (xy 198.115685 -29.091742)
			(xy 198.210033 -29.046323) (xy 198.307512 -29.008082) (xy 198.407576 -28.977234) (xy 198.509666 -28.953951)
			(xy 198.61321 -28.938364) (xy 198.71763 -28.930559) (xy 198.769986 -28.930092) (xy 198.824272 -28.930654)
			(xy 198.932519 -28.939056) (xy 199.039789 -28.955818) (xy 199.145439 -28.98084) (xy 199.248832 -29.01397)
			(xy 199.349349 -29.055011) (xy 199.446384 -29.103714) (xy 199.539355 -29.159789) (xy 199.627703 -29.222896)
			(xy 199.710896 -29.292659) (xy 199.788436 -29.368656) (xy 199.859855 -29.450431) (xy 199.924724 -29.537493)
			(xy 199.954134 -29.583126) (xy 199.961246 -29.594302) (xy 199.983852 -29.607002) (xy 200.09612 -29.607002)
			(xy 200.118726 -29.594302) (xy 200.125838 -29.583126) (xy 200.155267 -29.537503) (xy 200.22012 -29.450424)
			(xy 200.291527 -29.368632) (xy 200.369058 -29.29262) (xy 200.452246 -29.222845) (xy 200.540591 -29.159726)
			(xy 200.633561 -29.103643) (xy 200.730598 -29.054933) (xy 200.831118 -29.01389) (xy 200.934516 -28.980759)
			(xy 201.040171 -28.955741) (xy 201.147446 -28.938986) (xy 201.255698 -28.930594) (xy 201.309986 -28.930092)
			(xy 201.362338 -28.930608) (xy 201.466749 -28.938431) (xy 201.570283 -28.954033) (xy 201.672362 -28.977328)
			(xy 201.772415 -29.008186) (xy 201.869883 -29.046433) (xy 201.96422 -29.091856) (xy 202.0549 -29.144202)
			(xy 202.141415 -29.203176) (xy 202.223281 -29.268451) (xy 202.300041 -29.33966) (xy 202.371265 -29.416405)
			(xy 202.436556 -29.498258) (xy 202.495548 -29.584761) (xy 202.547912 -29.67543) (xy 202.593354 -29.769758)
			(xy 202.631621 -29.867218) (xy 202.662499 -29.967265) (xy 202.685814 -30.06934) (xy 202.701437 -30.172871)
			(xy 202.709281 -30.27728) (xy 202.70978 -30.329632) (xy 202.709225 -30.383924) (xy 202.700816 -30.492183)
			(xy 202.684044 -30.599465) (xy 202.663232 -30.6873) (xy 284.351952 -30.6873) (xy 284.355982 -30.602696)
			(xy 284.368036 -30.518857) (xy 284.388005 -30.436544) (xy 284.415708 -30.356502) (xy 284.450893 -30.279456)
			(xy 284.493244 -30.206103) (xy 284.542375 -30.137109) (xy 284.597842 -30.073096) (xy 284.659142 -30.014646)
			(xy 284.725721 -29.962288) (xy 284.796976 -29.916495) (xy 284.87226 -29.877683) (xy 284.950894 -29.846203)
			(xy 285.032163 -29.822341) (xy 285.115333 -29.806311) (xy 285.19965 -29.79826) (xy 285.242 -29.797756)
			(xy 285.288396 -29.798333) (xy 285.380684 -29.807979) (xy 285.471468 -29.827177) (xy 285.559762 -29.855717)
			(xy 285.602426 -29.873956) (xy 285.612368 -29.877762) (xy 285.633632 -29.877762) (xy 285.643574 -29.873956)
			(xy 285.686235 -29.855709) (xy 285.774528 -29.827166) (xy 285.865313 -29.807974) (xy 285.957604 -29.798341)
			(xy 286.004 -29.797756) (xy 286.047483 -29.798269) (xy 286.134036 -29.806754) (xy 286.219347 -29.823643)
			(xy 286.302603 -29.848776) (xy 286.38301 -29.881911) (xy 286.459801 -29.922733) (xy 286.532242 -29.970853)
			(xy 286.599643 -30.025811) (xy 286.630872 -30.056074) (xy 286.638238 -30.063186) (xy 286.656526 -30.070806)
			(xy 286.748474 -30.070806) (xy 286.766762 -30.063186) (xy 286.774128 -30.056074) (xy 286.805348 -30.025802)
			(xy 286.872752 -29.970849) (xy 286.945196 -29.922734) (xy 287.021989 -29.881915) (xy 287.102397 -29.848783)
			(xy 287.185654 -29.823654) (xy 287.270965 -29.806766) (xy 287.357517 -29.798282) (xy 287.401 -29.797756)
			(xy 287.447396 -29.798333) (xy 287.539684 -29.807979) (xy 287.630468 -29.827177) (xy 287.718762 -29.855717)
			(xy 287.761426 -29.873956) (xy 287.771368 -29.877762) (xy 287.792632 -29.877762) (xy 287.802574 -29.873956)
			(xy 287.845235 -29.855709) (xy 287.933528 -29.827166) (xy 288.024313 -29.807974) (xy 288.116604 -29.798341)
			(xy 288.163 -29.797756) (xy 288.205347 -29.798332) (xy 288.289657 -29.806382) (xy 288.37282 -29.822411)
			(xy 288.454083 -29.846271) (xy 288.53271 -29.877749) (xy 288.607988 -29.916558) (xy 288.679237 -29.962347)
			(xy 288.745811 -30.014701) (xy 288.807106 -30.073146) (xy 288.862569 -30.137153) (xy 288.911696 -30.206142)
			(xy 288.954043 -30.279489) (xy 288.989226 -30.356529) (xy 289.016926 -30.436565) (xy 289.036893 -30.518871)
			(xy 289.048947 -30.602702) (xy 289.052977 -30.6873) (xy 289.048947 -30.771898) (xy 289.036893 -30.855729)
			(xy 289.016926 -30.938035) (xy 288.989226 -31.018071) (xy 288.954043 -31.095111) (xy 288.911696 -31.168458)
			(xy 288.862569 -31.237447) (xy 288.807106 -31.301454) (xy 288.745811 -31.359899) (xy 288.679237 -31.412253)
			(xy 288.607988 -31.458042) (xy 288.53271 -31.496851) (xy 288.454083 -31.528329) (xy 288.37282 -31.552189)
			(xy 288.289657 -31.568218) (xy 288.205347 -31.576268) (xy 288.163 -31.576772) (xy 288.116604 -31.576192)
			(xy 288.024316 -31.566547) (xy 287.933532 -31.54735) (xy 287.845239 -31.518811) (xy 287.802574 -31.500572)
			(xy 287.792632 -31.496766) (xy 287.771368 -31.496766) (xy 287.761426 -31.500572) (xy 287.718763 -31.518815)
			(xy 287.630471 -31.54736) (xy 287.539686 -31.566553) (xy 287.447396 -31.576187) (xy 287.401 -31.576772)
			(xy 287.357516 -31.57628) (xy 287.270963 -31.567794) (xy 287.18565 -31.550903) (xy 287.102393 -31.525769)
			(xy 287.021986 -31.492631) (xy 286.945195 -31.451805) (xy 286.872755 -31.403681) (xy 286.805356 -31.348719)
			(xy 286.774128 -31.318454) (xy 286.766762 -31.311342) (xy 286.748474 -31.303722) (xy 286.656526 -31.303722)
			(xy 286.638238 -31.311342) (xy 286.630872 -31.318454) (xy 286.599639 -31.348712) (xy 286.532238 -31.403668)
			(xy 286.459797 -31.451787) (xy 286.383007 -31.492607) (xy 286.3026 -31.525741) (xy 286.219344 -31.550873)
			(xy 286.134034 -31.567761) (xy 286.047483 -31.576246) (xy 286.004 -31.576772) (xy 285.957604 -31.576192)
			(xy 285.865316 -31.566547) (xy 285.774532 -31.54735) (xy 285.686239 -31.518811) (xy 285.643574 -31.500572)
			(xy 285.633632 -31.496766) (xy 285.612368 -31.496766) (xy 285.602426 -31.500572) (xy 285.559763 -31.518815)
			(xy 285.471471 -31.54736) (xy 285.380686 -31.566553) (xy 285.288396 -31.576187) (xy 285.242 -31.576772)
			(xy 285.19965 -31.57634) (xy 285.115333 -31.568289) (xy 285.032163 -31.552259) (xy 284.950894 -31.528397)
			(xy 284.87226 -31.496917) (xy 284.796976 -31.458105) (xy 284.725721 -31.412312) (xy 284.659142 -31.359954)
			(xy 284.597842 -31.301504) (xy 284.542375 -31.237491) (xy 284.493244 -31.168497) (xy 284.450893 -31.095144)
			(xy 284.415708 -31.018098) (xy 284.388005 -30.938056) (xy 284.368036 -30.855743) (xy 284.355982 -30.771904)
			(xy 284.351952 -30.6873) (xy 202.663232 -30.6873) (xy 202.659009 -30.705125) (xy 202.625863 -30.808527)
			(xy 202.584804 -30.909049) (xy 202.536079 -31.006088) (xy 202.479981 -31.09906) (xy 202.416848 -31.187405)
			(xy 202.347059 -31.270593) (xy 202.271034 -31.348122) (xy 202.18923 -31.419528) (xy 202.102138 -31.48438)
			(xy 202.056492 -31.51378) (xy 202.045316 -31.520892) (xy 202.032616 -31.543498) (xy 202.032616 -31.655766)
			(xy 202.045316 -31.678372) (xy 202.056492 -31.685484) (xy 202.102118 -31.714914) (xy 202.189209 -31.779766)
			(xy 202.271012 -31.85117) (xy 202.347038 -31.928698) (xy 202.416828 -32.011883) (xy 202.479963 -32.100225)
			(xy 202.536064 -32.193194) (xy 202.584793 -32.290229) (xy 202.625858 -32.390749) (xy 202.659011 -32.494147)
			(xy 202.684053 -32.599804) (xy 202.700833 -32.707083) (xy 202.709252 -32.81534) (xy 202.70978 -32.869632)
			(xy 202.709276 -32.923932) (xy 202.700857 -33.032205) (xy 202.688311 -33.112399) (xy 274.529292 -33.112399)
			(xy 274.529292 -33.027677) (xy 274.537345 -32.94334) (xy 274.553379 -32.86015) (xy 274.577247 -32.77886)
			(xy 274.608735 -32.700208) (xy 274.647557 -32.624905) (xy 274.69336 -32.553633) (xy 274.745731 -32.487037)
			(xy 274.804196 -32.425722) (xy 274.868224 -32.370241) (xy 274.937236 -32.321098) (xy 275.010606 -32.278738)
			(xy 275.087671 -32.243543) (xy 275.167733 -32.215834) (xy 275.250066 -32.19586) (xy 275.333925 -32.183803)
			(xy 275.41855 -32.179772) (xy 275.503175 -32.183803) (xy 275.587034 -32.19586) (xy 275.598955 -32.198752)
			(xy 282.524141 -32.198752) (xy 282.524141 -32.114048) (xy 282.532193 -32.029727) (xy 282.548223 -31.946554)
			(xy 282.572088 -31.865281) (xy 282.60357 -31.786644) (xy 282.642385 -31.711356) (xy 282.68818 -31.640099)
			(xy 282.740542 -31.573518) (xy 282.798996 -31.512216) (xy 282.863012 -31.456748) (xy 282.932012 -31.407616)
			(xy 282.968446 -31.386018) (xy 283.002302 -31.366983) (xy 283.072707 -31.334173) (xy 283.145705 -31.307624)
			(xy 283.220737 -31.287536) (xy 283.297235 -31.274064) (xy 283.374616 -31.267309) (xy 283.413454 -31.266892)
			(xy 283.455805 -31.267378) (xy 283.540123 -31.275425) (xy 283.623294 -31.291451) (xy 283.704565 -31.315311)
			(xy 283.783201 -31.346788) (xy 283.858487 -31.385598) (xy 283.929744 -31.431388) (xy 283.996325 -31.483745)
			(xy 284.057628 -31.542194) (xy 284.113097 -31.606206) (xy 284.16223 -31.6752) (xy 284.204582 -31.748553)
			(xy 284.239769 -31.8256) (xy 284.267473 -31.905642) (xy 284.287443 -31.987956) (xy 284.299498 -32.071795)
			(xy 284.303528 -32.1564) (xy 284.299498 -32.241005) (xy 284.287443 -32.324844) (xy 284.267473 -32.407158)
			(xy 284.239769 -32.4872) (xy 284.204582 -32.564247) (xy 284.16223 -32.6376) (xy 284.113097 -32.706594)
			(xy 284.057628 -32.770606) (xy 283.996325 -32.829055) (xy 283.929744 -32.881412) (xy 283.858487 -32.927202)
			(xy 283.783201 -32.966012) (xy 283.704565 -32.997489) (xy 283.623294 -33.021349) (xy 283.540123 -33.037375)
			(xy 283.455805 -33.045422) (xy 283.413454 -33.045908) (xy 283.374614 -33.045521) (xy 283.297228 -33.038783)
			(xy 283.220725 -33.025319) (xy 283.145688 -33.005231) (xy 283.07269 -32.978672) (xy 283.002287 -32.945846)
			(xy 282.968446 -32.926782) (xy 282.932012 -32.905184) (xy 282.863012 -32.856052) (xy 282.798996 -32.800584)
			(xy 282.740542 -32.739282) (xy 282.68818 -32.672701) (xy 282.642385 -32.601444) (xy 282.60357 -32.526156)
			(xy 282.572088 -32.447519) (xy 282.548223 -32.366246) (xy 282.532193 -32.283073) (xy 282.524141 -32.198752)
			(xy 275.598955 -32.198752) (xy 275.669367 -32.215834) (xy 275.749429 -32.243543) (xy 275.826494 -32.278738)
			(xy 275.899864 -32.321098) (xy 275.968876 -32.370241) (xy 276.032904 -32.425722) (xy 276.091369 -32.487037)
			(xy 276.14374 -32.553633) (xy 276.189543 -32.624905) (xy 276.228365 -32.700208) (xy 276.259853 -32.77886)
			(xy 276.283721 -32.86015) (xy 276.299755 -32.94334) (xy 276.307808 -33.027677) (xy 276.308312 -33.070038)
			(xy 276.307808 -33.112399) (xy 276.299755 -33.196736) (xy 276.283721 -33.279926) (xy 276.259853 -33.361216)
			(xy 276.228365 -33.439868) (xy 276.189543 -33.515171) (xy 276.14374 -33.586443) (xy 276.091369 -33.653039)
			(xy 276.032904 -33.714354) (xy 275.968876 -33.769835) (xy 275.899864 -33.818978) (xy 275.826494 -33.861338)
			(xy 275.749429 -33.896533) (xy 275.669367 -33.924242) (xy 275.587034 -33.944216) (xy 275.503175 -33.956273)
			(xy 275.41855 -33.960305) (xy 275.333925 -33.956273) (xy 275.250066 -33.944216) (xy 275.167733 -33.924242)
			(xy 275.087671 -33.896533) (xy 275.010606 -33.861338) (xy 274.937236 -33.818978) (xy 274.868224 -33.769835)
			(xy 274.804196 -33.714354) (xy 274.745731 -33.653039) (xy 274.69336 -33.586443) (xy 274.647557 -33.515171)
			(xy 274.608735 -33.439868) (xy 274.577247 -33.361216) (xy 274.553379 -33.279926) (xy 274.537345 -33.196736)
			(xy 274.529292 -33.112399) (xy 202.688311 -33.112399) (xy 202.684071 -33.139499) (xy 202.65902 -33.24517)
			(xy 202.625853 -33.348581) (xy 202.584772 -33.449111) (xy 202.536023 -33.546154) (xy 202.479899 -33.639127)
			(xy 202.416737 -33.72747) (xy 202.346919 -33.810653) (xy 202.270864 -33.888173) (xy 202.189029 -33.959566)
			(xy 202.101907 -34.024402) (xy 202.056238 -34.05378) (xy 202.045062 -34.060892) (xy 202.032616 -34.083244)
			(xy 202.032616 -34.19602) (xy 202.045062 -34.218372) (xy 202.056238 -34.225484) (xy 202.10193 -34.254827)
			(xy 202.189051 -34.319666) (xy 202.270885 -34.391062) (xy 202.346939 -34.468586) (xy 202.416756 -34.551772)
			(xy 202.479915 -34.640118) (xy 202.536037 -34.733094) (xy 202.584783 -34.83014) (xy 202.625861 -34.930673)
			(xy 202.659024 -35.034087) (xy 202.684071 -35.13976) (xy 202.700853 -35.247057) (xy 202.709268 -35.355331)
			(xy 202.70978 -35.409632) (xy 202.709225 -35.463924) (xy 202.700816 -35.572183) (xy 202.684044 -35.679465)
			(xy 202.659009 -35.785125) (xy 202.625863 -35.888527) (xy 202.584804 -35.989049) (xy 202.536079 -36.086088)
			(xy 202.479981 -36.17906) (xy 202.416848 -36.267405) (xy 202.347059 -36.350593) (xy 202.271034 -36.428122)
			(xy 202.18923 -36.499528) (xy 202.102138 -36.56438) (xy 202.056492 -36.59378) (xy 202.045316 -36.600892)
			(xy 202.032616 -36.623498) (xy 202.032616 -36.735766) (xy 202.045316 -36.758372) (xy 202.056492 -36.765484)
			(xy 202.102118 -36.794914) (xy 202.189209 -36.859766) (xy 202.271012 -36.93117) (xy 202.347038 -37.008698)
			(xy 202.416828 -37.091883) (xy 202.479963 -37.180225) (xy 202.536064 -37.273194) (xy 202.584793 -37.370229)
			(xy 202.625858 -37.470749) (xy 202.659011 -37.574147) (xy 202.684053 -37.679804) (xy 202.700833 -37.787083)
			(xy 202.709252 -37.89534) (xy 202.70978 -37.949632) (xy 202.709293 -38.001987) (xy 202.706832 -38.03481)
			(xy 245.302523 -38.03481) (xy 245.302523 -37.864454) (xy 245.310508 -37.694286) (xy 245.32646 -37.524679)
			(xy 245.350345 -37.356007) (xy 245.382109 -37.188639) (xy 245.421684 -37.022944) (xy 245.468981 -36.859286)
			(xy 245.523898 -36.698025) (xy 245.586313 -36.539515) (xy 245.656089 -36.384105) (xy 245.733072 -36.232137)
			(xy 245.817094 -36.083943) (xy 245.90797 -35.939851) (xy 246.0055 -35.800177) (xy 246.10947 -35.665228)
			(xy 246.219651 -35.5353) (xy 246.3358 -35.41068) (xy 246.457664 -35.291641) (xy 246.584972 -35.178445)
			(xy 246.717447 -35.07134) (xy 246.854797 -34.970563) (xy 246.996719 -34.876334) (xy 247.142901 -34.788861)
			(xy 247.293024 -34.708336) (xy 247.446755 -34.634936) (xy 247.603758 -34.568822) (xy 247.763688 -34.51014)
			(xy 247.926192 -34.459019) (xy 248.090913 -34.415571) (xy 248.257491 -34.379892) (xy 248.425557 -34.35206)
			(xy 248.594743 -34.332136) (xy 248.764677 -34.320164) (xy 248.934986 -34.316171) (xy 249.105295 -34.320164)
			(xy 249.275229 -34.332136) (xy 249.444415 -34.35206) (xy 249.612481 -34.379892) (xy 249.779059 -34.415571)
			(xy 249.94378 -34.459019) (xy 250.106284 -34.51014) (xy 250.266214 -34.568822) (xy 250.423217 -34.634936)
			(xy 250.576948 -34.708336) (xy 250.727071 -34.788861) (xy 250.873253 -34.876334) (xy 251.015175 -34.970563)
			(xy 251.080047 -35.018161) (xy 293.293542 -35.018161) (xy 293.293542 -34.933439) (xy 293.301595 -34.849102)
			(xy 293.317629 -34.765912) (xy 293.341497 -34.684622) (xy 293.372985 -34.60597) (xy 293.411807 -34.530667)
			(xy 293.45761 -34.459395) (xy 293.509981 -34.392799) (xy 293.568446 -34.331484) (xy 293.632474 -34.276003)
			(xy 293.701486 -34.22686) (xy 293.774856 -34.1845) (xy 293.851921 -34.149305) (xy 293.931983 -34.121596)
			(xy 294.014316 -34.101622) (xy 294.098175 -34.089565) (xy 294.1828 -34.085534) (xy 294.267425 -34.089565)
			(xy 294.351284 -34.101622) (xy 294.433617 -34.121596) (xy 294.513679 -34.149305) (xy 294.590744 -34.1845)
			(xy 294.664114 -34.22686) (xy 294.733126 -34.276003) (xy 294.797154 -34.331484) (xy 294.855619 -34.392799)
			(xy 294.90799 -34.459395) (xy 294.953793 -34.530667) (xy 294.992615 -34.60597) (xy 295.024103 -34.684622)
			(xy 295.047971 -34.765912) (xy 295.064005 -34.849102) (xy 295.072058 -34.933439) (xy 295.072562 -34.9758)
			(xy 295.072058 -35.018161) (xy 295.064005 -35.102498) (xy 295.047971 -35.185688) (xy 295.024103 -35.266978)
			(xy 294.992615 -35.34563) (xy 294.953793 -35.420933) (xy 294.90799 -35.492205) (xy 294.855619 -35.558801)
			(xy 294.797154 -35.620116) (xy 294.733126 -35.675597) (xy 294.664114 -35.72474) (xy 294.590744 -35.7671)
			(xy 294.513679 -35.802295) (xy 294.433617 -35.830004) (xy 294.351284 -35.849978) (xy 294.267425 -35.862035)
			(xy 294.1828 -35.866067) (xy 294.098175 -35.862035) (xy 294.014316 -35.849978) (xy 293.931983 -35.830004)
			(xy 293.851921 -35.802295) (xy 293.774856 -35.7671) (xy 293.701486 -35.72474) (xy 293.632474 -35.675597)
			(xy 293.568446 -35.620116) (xy 293.509981 -35.558801) (xy 293.45761 -35.492205) (xy 293.411807 -35.420933)
			(xy 293.372985 -35.34563) (xy 293.341497 -35.266978) (xy 293.317629 -35.185688) (xy 293.301595 -35.102498)
			(xy 293.293542 -35.018161) (xy 251.080047 -35.018161) (xy 251.152525 -35.07134) (xy 251.285 -35.178445)
			(xy 251.412308 -35.291641) (xy 251.534172 -35.41068) (xy 251.650321 -35.5353) (xy 251.760502 -35.665228)
			(xy 251.864472 -35.800177) (xy 251.962002 -35.939851) (xy 252.052878 -36.083943) (xy 252.1369 -36.232137)
			(xy 252.213883 -36.384105) (xy 252.283659 -36.539515) (xy 252.346074 -36.698025) (xy 252.400991 -36.859286)
			(xy 252.448288 -37.022944) (xy 252.487863 -37.188639) (xy 252.504967 -37.278761) (xy 259.293102 -37.278761)
			(xy 259.293102 -37.194039) (xy 259.301155 -37.109702) (xy 259.317189 -37.026512) (xy 259.341057 -36.945222)
			(xy 259.372545 -36.86657) (xy 259.411367 -36.791267) (xy 259.45717 -36.719995) (xy 259.509541 -36.653399)
			(xy 259.568006 -36.592084) (xy 259.632034 -36.536603) (xy 259.701046 -36.48746) (xy 259.774416 -36.4451)
			(xy 259.851481 -36.409905) (xy 259.931543 -36.382196) (xy 260.013876 -36.362222) (xy 260.097735 -36.350165)
			(xy 260.18236 -36.346134) (xy 260.266985 -36.350165) (xy 260.350844 -36.362222) (xy 260.433177 -36.382196)
			(xy 260.513239 -36.409905) (xy 260.590304 -36.4451) (xy 260.663674 -36.48746) (xy 260.732686 -36.536603)
			(xy 260.796714 -36.592084) (xy 260.855179 -36.653399) (xy 260.90755 -36.719995) (xy 260.953353 -36.791267)
			(xy 260.992175 -36.86657) (xy 261.023663 -36.945222) (xy 261.047531 -37.026512) (xy 261.063565 -37.109702)
			(xy 261.071618 -37.194039) (xy 261.072122 -37.2364) (xy 261.071618 -37.278761) (xy 261.063565 -37.363098)
			(xy 261.047531 -37.446288) (xy 261.023663 -37.527578) (xy 260.992175 -37.60623) (xy 260.953353 -37.681533)
			(xy 260.90755 -37.752805) (xy 260.855179 -37.819401) (xy 260.796714 -37.880716) (xy 260.732686 -37.936197)
			(xy 260.663674 -37.98534) (xy 260.590304 -38.0277) (xy 260.513239 -38.062895) (xy 260.433177 -38.090604)
			(xy 260.350844 -38.110578) (xy 260.266985 -38.122635) (xy 260.18236 -38.126667) (xy 260.097735 -38.122635)
			(xy 260.013876 -38.110578) (xy 259.931543 -38.090604) (xy 259.851481 -38.062895) (xy 259.774416 -38.0277)
			(xy 259.701046 -37.98534) (xy 259.632034 -37.936197) (xy 259.568006 -37.880716) (xy 259.509541 -37.819401)
			(xy 259.45717 -37.752805) (xy 259.411367 -37.681533) (xy 259.372545 -37.60623) (xy 259.341057 -37.527578)
			(xy 259.317189 -37.446288) (xy 259.301155 -37.363098) (xy 259.293102 -37.278761) (xy 252.504967 -37.278761)
			(xy 252.519627 -37.356007) (xy 252.543512 -37.524679) (xy 252.559464 -37.694286) (xy 252.567449 -37.864454)
			(xy 252.567948 -37.949632) (xy 252.567449 -38.03481) (xy 252.559464 -38.204978) (xy 252.543512 -38.374585)
			(xy 252.519627 -38.543257) (xy 252.487863 -38.710625) (xy 252.448288 -38.87632) (xy 252.400991 -39.039978)
			(xy 252.350882 -39.18712) (xy 257.640836 -39.18712) (xy 257.641465 -39.140264) (xy 257.651373 -39.047077)
			(xy 257.671018 -38.955447) (xy 257.700183 -38.866389) (xy 257.718814 -38.823392) (xy 257.722591 -38.813952)
			(xy 257.723116 -38.793644) (xy 257.71983 -38.784022) (xy 257.705286 -38.745426) (xy 257.682591 -38.666124)
			(xy 257.667328 -38.585063) (xy 257.659626 -38.502938) (xy 257.659124 -38.461696) (xy 257.659628 -38.419335)
			(xy 257.667681 -38.334998) (xy 257.683715 -38.251808) (xy 257.707583 -38.170518) (xy 257.739071 -38.091866)
			(xy 257.777893 -38.016563) (xy 257.823696 -37.945291) (xy 257.876067 -37.878695) (xy 257.934532 -37.81738)
			(xy 257.99856 -37.761899) (xy 258.067572 -37.712756) (xy 258.140942 -37.670396) (xy 258.218007 -37.635201)
			(xy 258.298069 -37.607492) (xy 258.380402 -37.587518) (xy 258.464261 -37.575461) (xy 258.548886 -37.57143)
			(xy 258.633511 -37.575461) (xy 258.71737 -37.587518) (xy 258.799703 -37.607492) (xy 258.879765 -37.635201)
			(xy 258.95683 -37.670396) (xy 259.0302 -37.712756) (xy 259.099212 -37.761899) (xy 259.16324 -37.81738)
			(xy 259.221705 -37.878695) (xy 259.274076 -37.945291) (xy 259.319879 -38.016563) (xy 259.358701 -38.091866)
			(xy 259.390189 -38.170518) (xy 259.414057 -38.251808) (xy 259.430091 -38.334998) (xy 259.438144 -38.419335)
			(xy 259.438648 -38.461696) (xy 259.438331 -38.49433) (xy 259.433502 -38.559421) (xy 259.428996 -38.591744)
			(xy 259.427218 -38.603682) (xy 259.43433 -38.62578) (xy 259.506212 -38.700964) (xy 259.528056 -38.709092)
			(xy 259.53974 -38.707822) (xy 259.562407 -38.705593) (xy 259.607896 -38.703178) (xy 259.630672 -38.702996)
			(xy 259.671782 -38.703479) (xy 259.753652 -38.711065) (xy 259.834473 -38.726173) (xy 259.913554 -38.748676)
			(xy 259.990221 -38.778381) (xy 260.06382 -38.815034) (xy 260.133721 -38.858323) (xy 260.19933 -38.907879)
			(xy 260.260085 -38.963278) (xy 260.315468 -39.024047) (xy 260.365007 -39.089669) (xy 260.408278 -39.159581)
			(xy 260.444912 -39.233189) (xy 260.474597 -39.309864) (xy 260.49708 -39.388951) (xy 260.512167 -39.469776)
			(xy 260.519731 -39.551648) (xy 260.52018 -39.592758) (xy 260.519659 -39.635175) (xy 260.511589 -39.719623)
			(xy 260.495517 -39.80292) (xy 260.47159 -39.884309) (xy 260.440025 -39.963051) (xy 260.401108 -40.038431)
			(xy 260.355193 -40.109764) (xy 260.302698 -40.176404) (xy 260.244097 -40.237744) (xy 260.212332 -40.265858)
			(xy 260.203696 -40.273224) (xy 260.194806 -40.293036) (xy 260.194806 -40.392604) (xy 260.203696 -40.412416)
			(xy 260.212332 -40.419782) (xy 260.24409 -40.447905) (xy 260.302694 -40.509243) (xy 260.355193 -40.575881)
			(xy 260.401112 -40.647213) (xy 260.440033 -40.722591) (xy 260.471603 -40.801332) (xy 260.495535 -40.88272)
			(xy 260.502615 -40.9194) (xy 287.730188 -40.9194) (xy 287.734218 -40.834799) (xy 287.746271 -40.750964)
			(xy 287.766239 -40.668655) (xy 287.793941 -40.588616) (xy 287.829125 -40.511573) (xy 287.871474 -40.438223)
			(xy 287.920603 -40.369231) (xy 287.976068 -40.305221) (xy 288.037366 -40.246773) (xy 288.103942 -40.194417)
			(xy 288.175194 -40.148627) (xy 288.250475 -40.109816) (xy 288.329105 -40.078337) (xy 288.410372 -40.054476)
			(xy 288.493538 -40.038447) (xy 288.577852 -40.030396) (xy 288.6202 -40.029892) (xy 288.658991 -40.030305)
			(xy 288.736279 -40.037037) (xy 288.812687 -40.050475) (xy 288.887634 -40.070517) (xy 288.960551 -40.097012)
			(xy 289.030883 -40.129757) (xy 289.0647 -40.148764) (xy 289.072574 -40.152923) (xy 289.0901 -40.156017)
			(xy 289.107626 -40.152923) (xy 289.1155 -40.148764) (xy 289.149326 -40.129773) (xy 289.219657 -40.097028)
			(xy 289.292572 -40.070532) (xy 289.367517 -40.050487) (xy 289.443923 -40.037043) (xy 289.52121 -40.030305)
			(xy 289.56 -40.029892) (xy 289.602348 -40.030396) (xy 289.686662 -40.038447) (xy 289.769828 -40.054476)
			(xy 289.851095 -40.078337) (xy 289.929725 -40.109816) (xy 290.005006 -40.148627) (xy 290.076258 -40.194417)
			(xy 290.142834 -40.246773) (xy 290.204132 -40.305221) (xy 290.259597 -40.369231) (xy 290.308726 -40.438223)
			(xy 290.351075 -40.511573) (xy 290.386259 -40.588616) (xy 290.413961 -40.668655) (xy 290.433929 -40.750964)
			(xy 290.445982 -40.834799) (xy 290.450013 -40.9194) (xy 290.445982 -41.004001) (xy 290.433929 -41.087836)
			(xy 290.413961 -41.170145) (xy 290.386259 -41.250184) (xy 290.351075 -41.327227) (xy 290.308726 -41.400577)
			(xy 290.259597 -41.469569) (xy 290.204132 -41.533579) (xy 290.142834 -41.592027) (xy 290.076258 -41.644383)
			(xy 290.005006 -41.690173) (xy 289.929725 -41.728984) (xy 289.851095 -41.760463) (xy 289.769828 -41.784324)
			(xy 289.686662 -41.800353) (xy 289.602348 -41.808404) (xy 289.56 -41.808908) (xy 289.521209 -41.808495)
			(xy 289.443921 -41.801763) (xy 289.367513 -41.788325) (xy 289.292566 -41.768283) (xy 289.219649 -41.741788)
			(xy 289.149317 -41.709043) (xy 289.1155 -41.690036) (xy 289.107626 -41.685877) (xy 289.0901 -41.682783)
			(xy 289.072574 -41.685877) (xy 289.0647 -41.690036) (xy 289.030874 -41.709027) (xy 288.960543 -41.741772)
			(xy 288.887628 -41.768268) (xy 288.812683 -41.788313) (xy 288.736277 -41.801757) (xy 288.65899 -41.808495)
			(xy 288.6202 -41.808908) (xy 288.577852 -41.808404) (xy 288.493538 -41.800353) (xy 288.410372 -41.784324)
			(xy 288.329105 -41.760463) (xy 288.250475 -41.728984) (xy 288.175194 -41.690173) (xy 288.103942 -41.644383)
			(xy 288.037366 -41.592027) (xy 287.976068 -41.533579) (xy 287.920603 -41.469569) (xy 287.871474 -41.400577)
			(xy 287.829125 -41.327227) (xy 287.793941 -41.250184) (xy 287.766239 -41.170145) (xy 287.746271 -41.087836)
			(xy 287.734218 -41.004001) (xy 287.730188 -40.9194) (xy 260.502615 -40.9194) (xy 260.511612 -40.966017)
			(xy 260.519688 -41.050465) (xy 260.52018 -41.092882) (xy 260.519705 -41.135309) (xy 260.511626 -41.219777)
			(xy 260.49554 -41.303091) (xy 260.471593 -41.384495) (xy 260.440002 -41.463249) (xy 260.401055 -41.538636)
			(xy 260.355107 -41.609972) (xy 260.302573 -41.676608) (xy 260.243933 -41.737938) (xy 260.179718 -41.793405)
			(xy 260.110513 -41.842505) (xy 260.036947 -41.884791) (xy 259.959689 -41.919879) (xy 259.919724 -41.93413)
			(xy 259.910326 -41.937432) (xy 259.895594 -41.950132) (xy 259.854446 -42.03065) (xy 259.852668 -42.049954)
			(xy 259.855462 -42.059606) (xy 259.867486 -42.101336) (xy 259.874135 -42.134987) (xy 291.917116 -42.134987)
			(xy 291.917116 -42.050265) (xy 291.925169 -41.965928) (xy 291.941203 -41.882738) (xy 291.965071 -41.801448)
			(xy 291.996559 -41.722796) (xy 292.035381 -41.647493) (xy 292.081184 -41.576221) (xy 292.133555 -41.509625)
			(xy 292.19202 -41.44831) (xy 292.256048 -41.392829) (xy 292.32506 -41.343686) (xy 292.39843 -41.301326)
			(xy 292.475495 -41.266131) (xy 292.555557 -41.238422) (xy 292.63789 -41.218448) (xy 292.721749 -41.206391)
			(xy 292.806374 -41.20236) (xy 292.890999 -41.206391) (xy 292.974858 -41.218448) (xy 293.057191 -41.238422)
			(xy 293.137253 -41.266131) (xy 293.214318 -41.301326) (xy 293.287688 -41.343686) (xy 293.3567 -41.392829)
			(xy 293.420728 -41.44831) (xy 293.479193 -41.509625) (xy 293.531564 -41.576221) (xy 293.577367 -41.647493)
			(xy 293.616189 -41.722796) (xy 293.647677 -41.801448) (xy 293.671545 -41.882738) (xy 293.687579 -41.965928)
			(xy 293.695632 -42.050265) (xy 293.696136 -42.092626) (xy 293.695632 -42.134987) (xy 293.687579 -42.219324)
			(xy 293.671545 -42.302514) (xy 293.647677 -42.383804) (xy 293.616189 -42.462456) (xy 293.577367 -42.537759)
			(xy 293.531564 -42.609031) (xy 293.479193 -42.675627) (xy 293.420728 -42.736942) (xy 293.3567 -42.792423)
			(xy 293.287688 -42.841566) (xy 293.214318 -42.883926) (xy 293.137253 -42.919121) (xy 293.057191 -42.94683)
			(xy 292.974858 -42.966804) (xy 292.890999 -42.978861) (xy 292.806374 -42.982893) (xy 292.721749 -42.978861)
			(xy 292.63789 -42.966804) (xy 292.555557 -42.94683) (xy 292.475495 -42.919121) (xy 292.39843 -42.883926)
			(xy 292.32506 -42.841566) (xy 292.256048 -42.792423) (xy 292.19202 -42.736942) (xy 292.133555 -42.675627)
			(xy 292.081184 -42.609031) (xy 292.035381 -42.537759) (xy 291.996559 -42.462456) (xy 291.965071 -42.383804)
			(xy 291.941203 -42.302514) (xy 291.925169 -42.219324) (xy 291.917116 -42.134987) (xy 259.874135 -42.134987)
			(xy 259.88432 -42.186539) (xy 259.892782 -42.272975) (xy 259.893308 -42.3164) (xy 259.892842 -42.358233)
			(xy 259.885017 -42.441532) (xy 259.869417 -42.523731) (xy 259.858256 -42.56405) (xy 259.85597 -42.573278)
			(xy 259.857676 -42.592201) (xy 259.861558 -42.60088) (xy 259.87502 -42.627804) (xy 259.879656 -42.63618)
			(xy 259.893889 -42.648965) (xy 259.902706 -42.652696) (xy 259.941221 -42.667831) (xy 260.015569 -42.704177)
			(xy 260.086221 -42.747271) (xy 260.152565 -42.79674) (xy 260.214028 -42.852157) (xy 260.270078 -42.913043)
			(xy 260.320231 -42.978871) (xy 260.364054 -43.049073) (xy 260.401167 -43.123041) (xy 260.431251 -43.200137)
			(xy 260.454044 -43.279693) (xy 260.469349 -43.361022) (xy 260.477035 -43.443421) (xy 260.477508 -43.4848)
			(xy 260.477004 -43.527148) (xy 260.468953 -43.611462) (xy 260.452924 -43.694628) (xy 260.432497 -43.7642)
			(xy 287.730188 -43.7642) (xy 287.734218 -43.679599) (xy 287.746271 -43.595764) (xy 287.766239 -43.513455)
			(xy 287.793941 -43.433416) (xy 287.829125 -43.356373) (xy 287.871474 -43.283023) (xy 287.920603 -43.214031)
			(xy 287.976068 -43.150021) (xy 288.037366 -43.091573) (xy 288.103942 -43.039217) (xy 288.175194 -42.993427)
			(xy 288.250475 -42.954616) (xy 288.329105 -42.923137) (xy 288.410372 -42.899276) (xy 288.493538 -42.883247)
			(xy 288.577852 -42.875196) (xy 288.6202 -42.874692) (xy 288.658991 -42.875105) (xy 288.736279 -42.881837)
			(xy 288.812687 -42.895275) (xy 288.887634 -42.915317) (xy 288.960551 -42.941812) (xy 289.030883 -42.974557)
			(xy 289.0647 -42.993564) (xy 289.072574 -42.997723) (xy 289.0901 -43.000817) (xy 289.107626 -42.997723)
			(xy 289.1155 -42.993564) (xy 289.149326 -42.974573) (xy 289.219657 -42.941828) (xy 289.292572 -42.915332)
			(xy 289.367517 -42.895287) (xy 289.443923 -42.881843) (xy 289.52121 -42.875105) (xy 289.56 -42.874692)
			(xy 289.602348 -42.875196) (xy 289.686662 -42.883247) (xy 289.769828 -42.899276) (xy 289.851095 -42.923137)
			(xy 289.929725 -42.954616) (xy 290.005006 -42.993427) (xy 290.076258 -43.039217) (xy 290.142834 -43.091573)
			(xy 290.204132 -43.150021) (xy 290.259597 -43.214031) (xy 290.308726 -43.283023) (xy 290.351075 -43.356373)
			(xy 290.386259 -43.433416) (xy 290.413961 -43.513455) (xy 290.433929 -43.595764) (xy 290.445982 -43.679599)
			(xy 290.450013 -43.7642) (xy 290.445982 -43.848801) (xy 290.433929 -43.932636) (xy 290.413961 -44.014945)
			(xy 290.386259 -44.094984) (xy 290.351075 -44.172027) (xy 290.308726 -44.245377) (xy 290.259597 -44.314369)
			(xy 290.204132 -44.378379) (xy 290.142834 -44.436827) (xy 290.076258 -44.489183) (xy 290.005006 -44.534973)
			(xy 289.929725 -44.573784) (xy 289.851095 -44.605263) (xy 289.769828 -44.629124) (xy 289.686662 -44.645153)
			(xy 289.602348 -44.653204) (xy 289.56 -44.653708) (xy 289.521209 -44.653295) (xy 289.443921 -44.646563)
			(xy 289.367513 -44.633125) (xy 289.292566 -44.613083) (xy 289.219649 -44.586588) (xy 289.149317 -44.553843)
			(xy 289.1155 -44.534836) (xy 289.107626 -44.530677) (xy 289.0901 -44.527583) (xy 289.072574 -44.530677)
			(xy 289.0647 -44.534836) (xy 289.030874 -44.553827) (xy 288.960543 -44.586572) (xy 288.887628 -44.613068)
			(xy 288.812683 -44.633113) (xy 288.736277 -44.646557) (xy 288.65899 -44.653295) (xy 288.6202 -44.653708)
			(xy 288.577852 -44.653204) (xy 288.493538 -44.645153) (xy 288.410372 -44.629124) (xy 288.329105 -44.605263)
			(xy 288.250475 -44.573784) (xy 288.175194 -44.534973) (xy 288.103942 -44.489183) (xy 288.037366 -44.436827)
			(xy 287.976068 -44.378379) (xy 287.920603 -44.314369) (xy 287.871474 -44.245377) (xy 287.829125 -44.172027)
			(xy 287.793941 -44.094984) (xy 287.766239 -44.014945) (xy 287.746271 -43.932636) (xy 287.734218 -43.848801)
			(xy 287.730188 -43.7642) (xy 260.432497 -43.7642) (xy 260.429063 -43.775895) (xy 260.397584 -43.854525)
			(xy 260.358773 -43.929806) (xy 260.312983 -44.001058) (xy 260.260627 -44.067634) (xy 260.202179 -44.128932)
			(xy 260.138169 -44.184397) (xy 260.069177 -44.233526) (xy 259.995827 -44.275875) (xy 259.918784 -44.311059)
			(xy 259.838745 -44.338761) (xy 259.756436 -44.358729) (xy 259.672601 -44.370782) (xy 259.588 -44.374813)
			(xy 259.503399 -44.370782) (xy 259.419564 -44.358729) (xy 259.337255 -44.338761) (xy 259.257216 -44.311059)
			(xy 259.180173 -44.275875) (xy 259.106823 -44.233526) (xy 259.037831 -44.184397) (xy 258.973821 -44.128932)
			(xy 258.915373 -44.067634) (xy 258.863017 -44.001058) (xy 258.817227 -43.929806) (xy 258.778416 -43.854525)
			(xy 258.746937 -43.775895) (xy 258.723076 -43.694628) (xy 258.707047 -43.611462) (xy 258.698996 -43.527148)
			(xy 258.698492 -43.4848) (xy 258.698958 -43.442967) (xy 258.706783 -43.359668) (xy 258.722383 -43.277469)
			(xy 258.733544 -43.23715) (xy 258.73583 -43.227922) (xy 258.734124 -43.208999) (xy 258.730242 -43.20032)
			(xy 258.71678 -43.173396) (xy 258.712144 -43.16502) (xy 258.697911 -43.152235) (xy 258.689094 -43.148504)
			(xy 258.650579 -43.133369) (xy 258.576231 -43.097023) (xy 258.505579 -43.053929) (xy 258.439235 -43.00446)
			(xy 258.377772 -42.949043) (xy 258.321722 -42.888157) (xy 258.271569 -42.822329) (xy 258.227746 -42.752127)
			(xy 258.190633 -42.678159) (xy 258.160549 -42.601063) (xy 258.137756 -42.521507) (xy 258.122451 -42.440178)
			(xy 258.114765 -42.357779) (xy 258.114292 -42.3164) (xy 258.114767 -42.275174) (xy 258.122403 -42.193078)
			(xy 258.1376 -42.112039) (xy 258.160229 -42.032754) (xy 258.190094 -41.955902) (xy 258.226941 -41.882142)
			(xy 258.270452 -41.812106) (xy 258.320255 -41.746396) (xy 258.375923 -41.685574) (xy 258.406138 -41.657524)
			(xy 258.415282 -41.649142) (xy 258.423918 -41.62679) (xy 258.412488 -41.520618) (xy 258.39928 -41.500298)
			(xy 258.388612 -41.494202) (xy 258.352203 -41.47258) (xy 258.283247 -41.423422) (xy 258.219273 -41.367935)
			(xy 258.16086 -41.306622) (xy 258.108535 -41.240036) (xy 258.062773 -41.168781) (xy 258.023988 -41.093501)
			(xy 257.992529 -41.014876) (xy 257.968682 -40.933619) (xy 257.952663 -40.850463) (xy 257.944616 -40.766162)
			(xy 257.944112 -40.72382) (xy 257.944722 -40.676728) (xy 257.954664 -40.583071) (xy 257.974438 -40.490987)
			(xy 258.003824 -40.401506) (xy 258.022598 -40.358314) (xy 258.02655 -40.348334) (xy 258.026555 -40.32689)
			(xy 258.022598 -40.316912) (xy 258.004411 -40.274268) (xy 257.97595 -40.186031) (xy 257.956819 -40.095313)
			(xy 257.947225 -40.003097) (xy 257.946652 -39.95674) (xy 257.946693 -39.939388) (xy 257.947962 -39.904707)
			(xy 257.949192 -39.887398) (xy 257.949484 -39.87578) (xy 257.9409 -39.854212) (xy 257.932682 -39.845996)
			(xy 257.902445 -39.817967) (xy 257.846768 -39.757149) (xy 257.796958 -39.69144) (xy 257.753442 -39.621403)
			(xy 257.716595 -39.54764) (xy 257.686732 -39.470783) (xy 257.664109 -39.391493) (xy 257.648921 -39.310449)
			(xy 257.641298 -39.228347) (xy 257.640836 -39.18712) (xy 252.350882 -39.18712) (xy 252.346074 -39.201239)
			(xy 252.283659 -39.359749) (xy 252.213883 -39.515159) (xy 252.1369 -39.667127) (xy 252.052878 -39.815321)
			(xy 251.962002 -39.959413) (xy 251.864472 -40.099087) (xy 251.760502 -40.234036) (xy 251.650321 -40.363964)
			(xy 251.534172 -40.488584) (xy 251.412308 -40.607623) (xy 251.285 -40.720819) (xy 251.152525 -40.827924)
			(xy 251.015175 -40.928701) (xy 250.873253 -41.02293) (xy 250.727071 -41.110403) (xy 250.576948 -41.190928)
			(xy 250.423217 -41.264328) (xy 250.266214 -41.330442) (xy 250.106284 -41.389124) (xy 249.94378 -41.440245)
			(xy 249.779059 -41.483693) (xy 249.612481 -41.519372) (xy 249.444415 -41.547204) (xy 249.275229 -41.567128)
			(xy 249.105295 -41.5791) (xy 248.934986 -41.583094) (xy 248.764677 -41.5791) (xy 248.594743 -41.567128)
			(xy 248.425557 -41.547204) (xy 248.257491 -41.519372) (xy 248.090913 -41.483693) (xy 247.926192 -41.440245)
			(xy 247.763688 -41.389124) (xy 247.603758 -41.330442) (xy 247.446755 -41.264328) (xy 247.293024 -41.190928)
			(xy 247.142901 -41.110403) (xy 246.996719 -41.02293) (xy 246.854797 -40.928701) (xy 246.717447 -40.827924)
			(xy 246.584972 -40.720819) (xy 246.457664 -40.607623) (xy 246.3358 -40.488584) (xy 246.219651 -40.363964)
			(xy 246.10947 -40.234036) (xy 246.0055 -40.099087) (xy 245.90797 -39.959413) (xy 245.817094 -39.815321)
			(xy 245.733072 -39.667127) (xy 245.656089 -39.515159) (xy 245.586313 -39.359749) (xy 245.523898 -39.201239)
			(xy 245.468981 -39.039978) (xy 245.421684 -38.87632) (xy 245.382109 -38.710625) (xy 245.350345 -38.543257)
			(xy 245.32646 -38.374585) (xy 245.310508 -38.204978) (xy 245.302523 -38.03481) (xy 202.706832 -38.03481)
			(xy 202.701465 -38.106403) (xy 202.685855 -38.209943) (xy 202.662551 -38.312026) (xy 202.631683 -38.412082)
			(xy 202.593423 -38.509551) (xy 202.547985 -38.603889) (xy 202.495624 -38.694566) (xy 202.436633 -38.781077)
			(xy 202.371342 -38.862937) (xy 202.300114 -38.939688) (xy 202.22335 -39.010902) (xy 202.141479 -39.076179)
			(xy 202.054958 -39.135155) (xy 201.964271 -39.1875) (xy 201.869926 -39.232921) (xy 201.77245 -39.271164)
			(xy 201.672388 -39.302015) (xy 201.570301 -39.325301) (xy 201.466759 -39.340893) (xy 201.362341 -39.348702)
			(xy 201.309986 -39.349172) (xy 201.255699 -39.348649) (xy 201.147451 -39.340245) (xy 201.040179 -39.32348)
			(xy 200.934529 -39.298456) (xy 200.831134 -39.265322) (xy 200.730617 -39.224279) (xy 200.633581 -39.175572)
			(xy 200.54061 -39.119494) (xy 200.452263 -39.056383) (xy 200.36907 -38.986617) (xy 200.291532 -38.910617)
			(xy 200.220115 -38.828838) (xy 200.155247 -38.741772) (xy 200.125838 -38.696138) (xy 200.118726 -38.684962)
			(xy 200.09612 -38.672262) (xy 199.983852 -38.672262) (xy 199.961246 -38.684962) (xy 199.954134 -38.696138)
			(xy 199.924737 -38.741781) (xy 199.859878 -38.828858) (xy 199.788467 -38.910647) (xy 199.710933 -38.986656)
			(xy 199.627742 -39.056429) (xy 199.539394 -39.119545) (xy 199.446421 -39.175625) (xy 199.349382 -39.224332)
			(xy 199.24886 -39.265372) (xy 199.14546 -39.2985) (xy 199.039804 -39.323515) (xy 198.932527 -39.340268)
			(xy 198.824275 -39.348658) (xy 198.769986 -39.349172) (xy 198.717633 -39.348718) (xy 198.61322 -39.340894)
			(xy 198.509683 -39.325289) (xy 198.407602 -39.301991) (xy 198.307547 -39.271131) (xy 198.210078 -39.23288)
			(xy 198.11574 -39.187454) (xy 198.025059 -39.135106) (xy 197.938544 -39.076128) (xy 197.856677 -39.01085)
			(xy 197.779917 -38.939637) (xy 197.708692 -38.862888) (xy 197.643402 -38.781032) (xy 197.584411 -38.694526)
			(xy 197.532048 -38.603853) (xy 197.486607 -38.509522) (xy 197.448341 -38.412058) (xy 197.417465 -38.312008)
			(xy 197.394152 -38.209931) (xy 197.378531 -38.106397) (xy 197.37069 -38.001985) (xy 197.370192 -37.949632)
			(xy 197.370685 -37.895338) (xy 197.379097 -37.787077) (xy 197.395872 -37.679793) (xy 197.420911 -37.574131)
			(xy 197.454062 -37.470728) (xy 197.495126 -37.370204) (xy 197.543856 -37.273165) (xy 197.599959 -37.180193)
			(xy 197.663098 -37.091849) (xy 197.732893 -37.008662) (xy 197.808924 -36.931134) (xy 197.890734 -36.859731)
			(xy 197.977831 -36.794882) (xy 198.02348 -36.765484) (xy 198.034656 -36.758372) (xy 198.047356 -36.735766)
			(xy 198.047356 -36.623498) (xy 198.034656 -36.600892) (xy 198.02348 -36.59378) (xy 197.977831 -36.564385)
			(xy 197.890741 -36.499529) (xy 197.808938 -36.428122) (xy 197.732914 -36.35059) (xy 197.663125 -36.267402)
			(xy 197.599991 -36.179057) (xy 197.543892 -36.086085) (xy 197.495165 -35.989047) (xy 197.454103 -35.888525)
			(xy 197.420952 -35.785124) (xy 197.395913 -35.679465) (xy 197.379135 -35.572183) (xy 197.370719 -35.463925)
			(xy 197.370192 -35.409632) (xy 197.370714 -35.355332) (xy 197.379129 -35.247059) (xy 197.395911 -35.139764)
			(xy 197.420959 -35.034093) (xy 197.454122 -34.930681) (xy 197.495202 -34.830151) (xy 197.543949 -34.733107)
			(xy 197.600072 -34.640134) (xy 197.663233 -34.55179) (xy 197.733051 -34.468608) (xy 197.809106 -34.391087)
			(xy 197.890942 -34.319696) (xy 197.978065 -34.254861) (xy 198.023734 -34.225484) (xy 198.03491 -34.218372)
			(xy 198.047356 -34.19602) (xy 198.047356 -34.083244) (xy 198.03491 -34.060892) (xy 198.023734 -34.05378)
			(xy 197.97979 -34.025447) (xy 197.895731 -33.963249) (xy 197.816549 -33.894952) (xy 197.742685 -33.820935)
			(xy 197.674551 -33.741612) (xy 197.612527 -33.657426) (xy 197.556958 -33.568846) (xy 197.508156 -33.476365)
			(xy 197.466391 -33.3805) (xy 197.431898 -33.281786) (xy 197.404868 -33.180772) (xy 197.385452 -33.078023)
			(xy 197.373758 -32.974112) (xy 197.369852 -32.869617) (xy 193.81978 -32.869617) (xy 193.81978 -32.869632)
			(xy 193.819225 -32.923924) (xy 193.810816 -33.032183) (xy 193.794044 -33.139465) (xy 193.769009 -33.245125)
			(xy 193.735863 -33.348527) (xy 193.694804 -33.449049) (xy 193.646079 -33.546088) (xy 193.589981 -33.63906)
			(xy 193.526848 -33.727405) (xy 193.457059 -33.810593) (xy 193.381034 -33.888122) (xy 193.29923 -33.959528)
			(xy 193.212138 -34.02438) (xy 193.166492 -34.05378) (xy 193.155316 -34.060892) (xy 193.142616 -34.083498)
			(xy 193.142616 -34.195766) (xy 193.155316 -34.218372) (xy 193.166492 -34.225484) (xy 193.212118 -34.254914)
			(xy 193.299209 -34.319766) (xy 193.381012 -34.39117) (xy 193.457038 -34.468698) (xy 193.526828 -34.551883)
			(xy 193.589963 -34.640225) (xy 193.646064 -34.733194) (xy 193.694793 -34.830229) (xy 193.735858 -34.930749)
			(xy 193.769011 -35.034147) (xy 193.794053 -35.139804) (xy 193.810833 -35.247083) (xy 193.819252 -35.35534)
			(xy 193.81978 -35.409632) (xy 193.819276 -35.463932) (xy 193.810857 -35.572205) (xy 193.794071 -35.679499)
			(xy 193.76902 -35.78517) (xy 193.735853 -35.888581) (xy 193.694772 -35.989111) (xy 193.646023 -36.086154)
			(xy 193.589899 -36.179127) (xy 193.526737 -36.26747) (xy 193.456919 -36.350653) (xy 193.380864 -36.428173)
			(xy 193.299029 -36.499566) (xy 193.211907 -36.564402) (xy 193.166238 -36.59378) (xy 193.155062 -36.600892)
			(xy 193.142616 -36.623244) (xy 193.142616 -36.73602) (xy 193.155062 -36.758372) (xy 193.166238 -36.765484)
			(xy 193.21193 -36.794827) (xy 193.299051 -36.859666) (xy 193.380885 -36.931062) (xy 193.456939 -37.008586)
			(xy 193.526756 -37.091772) (xy 193.589915 -37.180118) (xy 193.646037 -37.273094) (xy 193.694783 -37.37014)
			(xy 193.735861 -37.470673) (xy 193.769024 -37.574087) (xy 193.794071 -37.67976) (xy 193.810853 -37.787057)
			(xy 193.819268 -37.895331) (xy 193.81978 -37.949632) (xy 193.819293 -38.001987) (xy 193.811465 -38.106403)
			(xy 193.795855 -38.209943) (xy 193.772551 -38.312026) (xy 193.741683 -38.412082) (xy 193.703423 -38.509551)
			(xy 193.657985 -38.603889) (xy 193.605624 -38.694566) (xy 193.546633 -38.781077) (xy 193.481342 -38.862937)
			(xy 193.410114 -38.939688) (xy 193.33335 -39.010902) (xy 193.251479 -39.076179) (xy 193.164958 -39.135155)
			(xy 193.074271 -39.1875) (xy 192.979926 -39.232921) (xy 192.88245 -39.271164) (xy 192.782388 -39.302015)
			(xy 192.680301 -39.325301) (xy 192.576759 -39.340893) (xy 192.472341 -39.348702) (xy 192.419986 -39.349172)
			(xy 192.365699 -39.348649) (xy 192.257451 -39.340245) (xy 192.150179 -39.32348) (xy 192.044529 -39.298456)
			(xy 191.941134 -39.265322) (xy 191.840617 -39.224279) (xy 191.743581 -39.175572) (xy 191.65061 -39.119494)
			(xy 191.562263 -39.056383) (xy 191.47907 -38.986617) (xy 191.401532 -38.910617) (xy 191.330115 -38.828838)
			(xy 191.265247 -38.741772) (xy 191.235838 -38.696138) (xy 191.228726 -38.684962) (xy 191.20612 -38.672262)
			(xy 191.093852 -38.672262) (xy 191.071246 -38.684962) (xy 191.064134 -38.696138) (xy 191.034737 -38.741781)
			(xy 190.969878 -38.828858) (xy 190.898467 -38.910647) (xy 190.820933 -38.986656) (xy 190.737742 -39.056429)
			(xy 190.649394 -39.119545) (xy 190.556421 -39.175625) (xy 190.459382 -39.224332) (xy 190.35886 -39.265372)
			(xy 190.25546 -39.2985) (xy 190.149804 -39.323515) (xy 190.042527 -39.340268) (xy 189.934275 -39.348658)
			(xy 189.879986 -39.349172) (xy 189.827633 -39.348718) (xy 189.72322 -39.340894) (xy 189.619683 -39.325289)
			(xy 189.517602 -39.301991) (xy 189.417547 -39.271131) (xy 189.320078 -39.23288) (xy 189.22574 -39.187454)
			(xy 189.135059 -39.135106) (xy 189.048544 -39.076128) (xy 188.966677 -39.01085) (xy 188.889917 -38.939637)
			(xy 188.818692 -38.862888) (xy 188.753402 -38.781032) (xy 188.694411 -38.694526) (xy 188.642048 -38.603853)
			(xy 188.596607 -38.509522) (xy 188.558341 -38.412058) (xy 188.527465 -38.312008) (xy 188.504152 -38.209931)
			(xy 188.488531 -38.106397) (xy 188.48069 -38.001985) (xy 188.480192 -37.949632) (xy 188.480714 -37.895332)
			(xy 188.489129 -37.787059) (xy 188.505911 -37.679764) (xy 188.530959 -37.574093) (xy 188.564122 -37.470681)
			(xy 188.605202 -37.370151) (xy 188.653949 -37.273107) (xy 188.710072 -37.180134) (xy 188.773233 -37.09179)
			(xy 188.843051 -37.008608) (xy 188.919106 -36.931087) (xy 189.000942 -36.859696) (xy 189.088065 -36.794861)
			(xy 189.133734 -36.765484) (xy 189.14491 -36.758372) (xy 189.157356 -36.73602) (xy 189.157356 -36.623244)
			(xy 189.14491 -36.600892) (xy 189.133734 -36.59378) (xy 189.08979 -36.565447) (xy 189.005731 -36.503249)
			(xy 188.926549 -36.434952) (xy 188.852685 -36.360935) (xy 188.784551 -36.281612) (xy 188.722527 -36.197426)
			(xy 188.666958 -36.108846) (xy 188.618156 -36.016365) (xy 188.576391 -35.9205) (xy 188.541898 -35.821786)
			(xy 188.514868 -35.720772) (xy 188.495452 -35.618023) (xy 188.483758 -35.514112) (xy 188.479852 -35.409617)
			(xy 184.930187 -35.409617) (xy 184.926281 -35.514116) (xy 184.914587 -35.618032) (xy 184.895169 -35.720786)
			(xy 184.868138 -35.821804) (xy 184.833642 -35.920523) (xy 184.791875 -36.016391) (xy 184.743069 -36.108876)
			(xy 184.687498 -36.19746) (xy 184.62547 -36.281649) (xy 184.557332 -36.360975) (xy 184.483463 -36.434993)
			(xy 184.404277 -36.503293) (xy 184.320214 -36.565492) (xy 184.276238 -36.59378) (xy 184.265062 -36.600892)
			(xy 184.252616 -36.623244) (xy 184.252616 -36.73602) (xy 184.265062 -36.758372) (xy 184.276238 -36.765484)
			(xy 184.32193 -36.794827) (xy 184.409051 -36.859666) (xy 184.490885 -36.931062) (xy 184.566939 -37.008586)
			(xy 184.636756 -37.091772) (xy 184.699915 -37.180118) (xy 184.756037 -37.273094) (xy 184.804783 -37.37014)
			(xy 184.845861 -37.470673) (xy 184.879024 -37.574087) (xy 184.904071 -37.67976) (xy 184.920853 -37.787057)
			(xy 184.929268 -37.895331) (xy 184.92978 -37.949632) (xy 184.929293 -38.001987) (xy 184.921465 -38.106403)
			(xy 184.905855 -38.209943) (xy 184.882551 -38.312026) (xy 184.851683 -38.412082) (xy 184.813423 -38.509551)
			(xy 184.767985 -38.603889) (xy 184.715624 -38.694566) (xy 184.656633 -38.781077) (xy 184.591342 -38.862937)
			(xy 184.520114 -38.939688) (xy 184.44335 -39.010902) (xy 184.361479 -39.076179) (xy 184.274958 -39.135155)
			(xy 184.184271 -39.1875) (xy 184.089926 -39.232921) (xy 183.99245 -39.271164) (xy 183.892388 -39.302015)
			(xy 183.790301 -39.325301) (xy 183.686759 -39.340893) (xy 183.582341 -39.348702) (xy 183.529986 -39.349172)
			(xy 183.475692 -39.348687) (xy 183.367431 -39.340272) (xy 183.260148 -39.323494) (xy 183.154487 -39.298453)
			(xy 183.051084 -39.2653) (xy 182.950561 -39.224235) (xy 182.853522 -39.175504) (xy 182.760551 -39.119401)
			(xy 182.672206 -39.056262) (xy 182.58902 -38.986468) (xy 182.511491 -38.910438) (xy 182.440087 -38.828629)
			(xy 182.375236 -38.741533) (xy 182.345838 -38.695884) (xy 182.338726 -38.684708) (xy 182.316374 -38.672262)
			(xy 182.203598 -38.672262) (xy 182.181246 -38.684708) (xy 182.174134 -38.695884) (xy 182.144756 -38.741548)
			(xy 182.079916 -38.828655) (xy 182.008519 -38.910475) (xy 181.930994 -38.986514) (xy 181.847809 -39.056314)
			(xy 181.759462 -39.119457) (xy 181.666488 -39.175561) (xy 181.569444 -39.224289) (xy 181.468914 -39.265348)
			(xy 181.365505 -39.29849) (xy 181.259837 -39.323517) (xy 181.152548 -39.340277) (xy 181.044282 -39.348671)
			(xy 180.989986 -39.349172) (xy 180.937633 -39.348718) (xy 180.83322 -39.340894) (xy 180.729683 -39.325289)
			(xy 180.627602 -39.301991) (xy 180.527547 -39.271131) (xy 180.430078 -39.23288) (xy 180.33574 -39.187454)
			(xy 180.245059 -39.135106) (xy 180.158544 -39.076128) (xy 180.076677 -39.01085) (xy 179.999917 -38.939637)
			(xy 179.928692 -38.862888) (xy 179.863402 -38.781032) (xy 179.804411 -38.694526) (xy 179.752048 -38.603853)
			(xy 179.706607 -38.509522) (xy 179.668341 -38.412058) (xy 179.637465 -38.312008) (xy 179.614152 -38.209931)
			(xy 179.598531 -38.106397) (xy 179.59069 -38.001985) (xy 179.590192 -37.949632) (xy 179.590714 -37.895332)
			(xy 179.599129 -37.787059) (xy 179.615911 -37.679764) (xy 179.640959 -37.574093) (xy 179.674122 -37.470681)
			(xy 179.715202 -37.370151) (xy 179.763949 -37.273107) (xy 179.820072 -37.180134) (xy 179.883233 -37.09179)
			(xy 179.953051 -37.008608) (xy 180.029106 -36.931087) (xy 180.110942 -36.859696) (xy 180.198065 -36.794861)
			(xy 180.243734 -36.765484) (xy 180.25491 -36.758372) (xy 180.267356 -36.73602) (xy 180.267356 -36.623244)
			(xy 180.25491 -36.600892) (xy 180.243734 -36.59378) (xy 180.19979 -36.565447) (xy 180.115731 -36.503249)
			(xy 180.036549 -36.434952) (xy 179.962685 -36.360935) (xy 179.894551 -36.281612) (xy 179.832527 -36.197426)
			(xy 179.776958 -36.108846) (xy 179.728156 -36.016365) (xy 179.686391 -35.9205) (xy 179.651898 -35.821786)
			(xy 179.624868 -35.720772) (xy 179.605452 -35.618023) (xy 179.593758 -35.514112) (xy 179.589852 -35.409617)
			(xy 171.523084 -35.409617) (xy 171.524172 -35.41068) (xy 171.640321 -35.5353) (xy 171.750502 -35.665228)
			(xy 171.854472 -35.800177) (xy 171.952002 -35.939851) (xy 172.042878 -36.083943) (xy 172.1269 -36.232137)
			(xy 172.203883 -36.384105) (xy 172.273659 -36.539515) (xy 172.336074 -36.698025) (xy 172.390991 -36.859286)
			(xy 172.438288 -37.022944) (xy 172.477863 -37.188639) (xy 172.509627 -37.356007) (xy 172.533512 -37.524679)
			(xy 172.549464 -37.694286) (xy 172.557449 -37.864454) (xy 172.557948 -37.949632) (xy 172.557449 -38.03481)
			(xy 172.549464 -38.204978) (xy 172.533512 -38.374585) (xy 172.509627 -38.543257) (xy 172.477863 -38.710625)
			(xy 172.438288 -38.87632) (xy 172.390991 -39.039978) (xy 172.336074 -39.201239) (xy 172.273659 -39.359749)
			(xy 172.203883 -39.515159) (xy 172.1269 -39.667127) (xy 172.042878 -39.815321) (xy 171.952002 -39.959413)
			(xy 171.854472 -40.099087) (xy 171.750502 -40.234036) (xy 171.640321 -40.363964) (xy 171.524172 -40.488584)
			(xy 171.402308 -40.607623) (xy 171.275 -40.720819) (xy 171.142525 -40.827924) (xy 171.005175 -40.928701)
			(xy 170.863253 -41.02293) (xy 170.717071 -41.110403) (xy 170.566948 -41.190928) (xy 170.413217 -41.264328)
			(xy 170.256214 -41.330442) (xy 170.096284 -41.389124) (xy 169.93378 -41.440245) (xy 169.769059 -41.483693)
			(xy 169.602481 -41.519372) (xy 169.434415 -41.547204) (xy 169.265229 -41.567128) (xy 169.095295 -41.5791)
			(xy 168.924986 -41.583094) (xy 168.754677 -41.5791) (xy 168.584743 -41.567128) (xy 168.415557 -41.547204)
			(xy 168.247491 -41.519372) (xy 168.080913 -41.483693) (xy 167.916192 -41.440245) (xy 167.753688 -41.389124)
			(xy 167.593758 -41.330442) (xy 167.436755 -41.264328) (xy 167.283024 -41.190928) (xy 167.132901 -41.110403)
			(xy 166.986719 -41.02293) (xy 166.844797 -40.928701) (xy 166.707447 -40.827924) (xy 166.574972 -40.720819)
			(xy 166.447664 -40.607623) (xy 166.3258 -40.488584) (xy 166.209651 -40.363964) (xy 166.09947 -40.234036)
			(xy 165.9955 -40.099087) (xy 165.89797 -39.959413) (xy 165.807094 -39.815321) (xy 165.723072 -39.667127)
			(xy 165.646089 -39.515159) (xy 165.576313 -39.359749) (xy 165.513898 -39.201239) (xy 165.458981 -39.039978)
			(xy 165.411684 -38.87632) (xy 165.372109 -38.710625) (xy 165.340345 -38.543257) (xy 165.31646 -38.374585)
			(xy 165.300508 -38.204978) (xy 165.292523 -38.03481) (xy 123.764403 -38.03481) (xy 123.764017 -38.074277)
			(xy 123.755614 -38.182525) (xy 123.738851 -38.289797) (xy 123.713828 -38.395448) (xy 123.680696 -38.498842)
			(xy 123.639653 -38.59936) (xy 123.590947 -38.696396) (xy 123.53487 -38.789366) (xy 123.471759 -38.877714)
			(xy 123.401993 -38.960907) (xy 123.325993 -39.038445) (xy 123.244214 -39.109862) (xy 123.157148 -39.17473)
			(xy 123.111514 -39.204138) (xy 123.100338 -39.21125) (xy 123.087638 -39.233856) (xy 123.087638 -39.346124)
			(xy 123.100338 -39.36873) (xy 123.111514 -39.375842) (xy 123.157141 -39.405264) (xy 123.244218 -39.47012)
			(xy 123.326008 -39.541529) (xy 123.402018 -39.61906) (xy 123.471791 -39.702249) (xy 123.534909 -39.790595)
			(xy 123.59099 -39.883566) (xy 123.639698 -39.980603) (xy 123.68074 -40.081123) (xy 123.71387 -40.184521)
			(xy 123.738887 -40.290175) (xy 123.755642 -40.397451) (xy 123.764033 -40.505702) (xy 123.764548 -40.55999)
			(xy 123.764095 -40.612343) (xy 123.756272 -40.716757) (xy 123.740669 -40.820294) (xy 123.717372 -40.922376)
			(xy 123.686513 -41.022432) (xy 123.648263 -41.119902) (xy 123.602837 -41.214241) (xy 123.550489 -41.304922)
			(xy 123.491511 -41.391438) (xy 123.426233 -41.473306) (xy 123.35502 -41.550066) (xy 123.278271 -41.621291)
			(xy 123.196414 -41.686581) (xy 123.109907 -41.745573) (xy 123.019234 -41.797935) (xy 122.924902 -41.843376)
			(xy 122.827438 -41.881641) (xy 122.727387 -41.912516) (xy 122.625308 -41.935828) (xy 122.521774 -41.951448)
			(xy 122.417361 -41.959287) (xy 122.365008 -41.959784) (xy 122.310709 -41.959246) (xy 122.202437 -41.95083)
			(xy 122.095143 -41.934047) (xy 121.989473 -41.908999) (xy 121.886062 -41.875835) (xy 121.785533 -41.834757)
			(xy 121.68849 -41.786011) (xy 121.595516 -41.729889) (xy 121.507173 -41.666731) (xy 121.42399 -41.596915)
			(xy 121.346469 -41.520862) (xy 121.275075 -41.43903) (xy 121.210239 -41.35191) (xy 121.18086 -41.306242)
			(xy 121.173748 -41.295066) (xy 121.151396 -41.28262) (xy 121.03862 -41.28262) (xy 121.016268 -41.295066)
			(xy 121.009156 -41.306242) (xy 120.979787 -41.351917) (xy 120.91495 -41.439038) (xy 120.843556 -41.520872)
			(xy 120.766034 -41.596926) (xy 120.682851 -41.666744) (xy 120.594507 -41.729904) (xy 120.501533 -41.786026)
			(xy 120.404489 -41.834774) (xy 120.303959 -41.875854) (xy 120.200547 -41.909019) (xy 120.094876 -41.934068)
			(xy 119.987581 -41.950853) (xy 119.879308 -41.95927) (xy 119.825008 -41.959784) (xy 119.772654 -41.959255)
			(xy 119.668238 -41.95143) (xy 119.5647 -41.935823) (xy 119.462617 -41.912521) (xy 119.362562 -41.881656)
			(xy 119.265093 -41.843398) (xy 119.170756 -41.797963) (xy 119.080078 -41.745605) (xy 118.993567 -41.686616)
			(xy 118.911707 -41.621327) (xy 118.834955 -41.550102) (xy 118.763742 -41.47334) (xy 118.698464 -41.39147)
			(xy 118.639487 -41.304951) (xy 118.587142 -41.214266) (xy 118.541721 -41.119922) (xy 118.503478 -41.022448)
			(xy 118.472627 -40.922388) (xy 118.44934 -40.820302) (xy 118.433748 -40.716761) (xy 118.425938 -40.612344)
			(xy 118.425468 -40.55999) (xy 118.425938 -40.505696) (xy 118.434353 -40.397434) (xy 118.451132 -40.29015)
			(xy 118.476173 -40.184488) (xy 118.509326 -40.081085) (xy 118.550393 -39.980561) (xy 118.599125 -39.883522)
			(xy 118.65523 -39.790551) (xy 118.71837 -39.702206) (xy 118.788166 -39.61902) (xy 118.864198 -39.541492)
			(xy 118.946009 -39.470089) (xy 119.033106 -39.40524) (xy 119.078756 -39.375842) (xy 119.089932 -39.36873)
			(xy 119.102378 -39.346378) (xy 119.102378 -39.233602) (xy 119.089932 -39.21125) (xy 119.078756 -39.204138)
			(xy 119.034773 -39.175864) (xy 118.950712 -39.113664) (xy 118.871528 -39.045364) (xy 118.797662 -38.971345)
			(xy 118.729526 -38.892019) (xy 118.667501 -38.80783) (xy 118.611931 -38.719246) (xy 118.563128 -38.626763)
			(xy 118.521364 -38.530894) (xy 118.48687 -38.432176) (xy 118.45984 -38.33116) (xy 118.440425 -38.228407)
			(xy 118.428733 -38.124492) (xy 118.424828 -38.019995) (xy 114.875163 -38.019995) (xy 114.871259 -38.124491)
			(xy 114.859567 -38.228404) (xy 114.840152 -38.331155) (xy 114.813123 -38.43217) (xy 114.77863 -38.530887)
			(xy 114.736867 -38.626753) (xy 114.688065 -38.719236) (xy 114.632497 -38.807819) (xy 114.570473 -38.892007)
			(xy 114.502339 -38.971332) (xy 114.428475 -39.04535) (xy 114.349292 -39.11365) (xy 114.265234 -39.17585)
			(xy 114.22126 -39.204138) (xy 114.210084 -39.21125) (xy 114.197638 -39.233602) (xy 114.197638 -39.346378)
			(xy 114.210084 -39.36873) (xy 114.22126 -39.375842) (xy 114.266907 -39.405246) (xy 114.354015 -39.470083)
			(xy 114.435836 -39.541477) (xy 114.511875 -39.618999) (xy 114.581677 -39.702182) (xy 114.644821 -39.790526)
			(xy 114.700926 -39.883499) (xy 114.749655 -39.980541) (xy 114.790716 -40.081068) (xy 114.82386 -40.184476)
			(xy 114.848888 -40.290142) (xy 114.865651 -40.39743) (xy 114.874046 -40.505695) (xy 114.874548 -40.55999)
			(xy 114.874095 -40.612343) (xy 114.866272 -40.716757) (xy 114.850669 -40.820294) (xy 114.827372 -40.922376)
			(xy 114.796513 -41.022432) (xy 114.758263 -41.119902) (xy 114.712837 -41.214241) (xy 114.660489 -41.304922)
			(xy 114.601511 -41.391438) (xy 114.536233 -41.473306) (xy 114.46502 -41.550066) (xy 114.388271 -41.621291)
			(xy 114.306414 -41.686581) (xy 114.219907 -41.745573) (xy 114.129234 -41.797935) (xy 114.034902 -41.843376)
			(xy 113.937438 -41.881641) (xy 113.837387 -41.912516) (xy 113.735308 -41.935828) (xy 113.631774 -41.951448)
			(xy 113.527361 -41.959287) (xy 113.475008 -41.959784) (xy 113.420709 -41.959246) (xy 113.312437 -41.95083)
			(xy 113.205143 -41.934047) (xy 113.099473 -41.908999) (xy 112.996062 -41.875835) (xy 112.895533 -41.834757)
			(xy 112.79849 -41.786011) (xy 112.705516 -41.729889) (xy 112.617173 -41.666731) (xy 112.53399 -41.596915)
			(xy 112.456469 -41.520862) (xy 112.385075 -41.43903) (xy 112.320239 -41.35191) (xy 112.29086 -41.306242)
			(xy 112.283748 -41.295066) (xy 112.261396 -41.28262) (xy 112.14862 -41.28262) (xy 112.126268 -41.295066)
			(xy 112.119156 -41.306242) (xy 112.089787 -41.351917) (xy 112.02495 -41.439038) (xy 111.953556 -41.520872)
			(xy 111.876034 -41.596926) (xy 111.792851 -41.666744) (xy 111.704507 -41.729904) (xy 111.611533 -41.786026)
			(xy 111.514489 -41.834774) (xy 111.413959 -41.875854) (xy 111.310547 -41.909019) (xy 111.204876 -41.934068)
			(xy 111.097581 -41.950853) (xy 110.989308 -41.95927) (xy 110.935008 -41.959784) (xy 110.882654 -41.959255)
			(xy 110.778238 -41.95143) (xy 110.6747 -41.935823) (xy 110.572617 -41.912521) (xy 110.472562 -41.881656)
			(xy 110.375093 -41.843398) (xy 110.280756 -41.797963) (xy 110.190078 -41.745605) (xy 110.103567 -41.686616)
			(xy 110.021707 -41.621327) (xy 109.944955 -41.550102) (xy 109.873742 -41.47334) (xy 109.808464 -41.39147)
			(xy 109.749487 -41.304951) (xy 109.697142 -41.214266) (xy 109.651721 -41.119922) (xy 109.613478 -41.022448)
			(xy 109.582627 -40.922388) (xy 109.55934 -40.820302) (xy 109.543748 -40.716761) (xy 109.535938 -40.612344)
			(xy 109.535468 -40.55999) (xy 109.535938 -40.505696) (xy 109.544353 -40.397434) (xy 109.561132 -40.29015)
			(xy 109.586173 -40.184488) (xy 109.619326 -40.081085) (xy 109.660393 -39.980561) (xy 109.709125 -39.883522)
			(xy 109.76523 -39.790551) (xy 109.82837 -39.702206) (xy 109.898166 -39.61902) (xy 109.974198 -39.541492)
			(xy 110.056009 -39.470089) (xy 110.143106 -39.40524) (xy 110.188756 -39.375842) (xy 110.199932 -39.36873)
			(xy 110.212378 -39.346378) (xy 110.212378 -39.233602) (xy 110.199932 -39.21125) (xy 110.188756 -39.204138)
			(xy 110.144773 -39.175864) (xy 110.060712 -39.113664) (xy 109.981528 -39.045364) (xy 109.907662 -38.971345)
			(xy 109.839526 -38.892019) (xy 109.777501 -38.80783) (xy 109.721931 -38.719246) (xy 109.673128 -38.626763)
			(xy 109.631364 -38.530894) (xy 109.59687 -38.432176) (xy 109.56984 -38.33116) (xy 109.550425 -38.228407)
			(xy 109.538733 -38.124492) (xy 109.534828 -38.019995) (xy 105.985163 -38.019995) (xy 105.981259 -38.124491)
			(xy 105.969567 -38.228404) (xy 105.950152 -38.331155) (xy 105.923123 -38.43217) (xy 105.88863 -38.530887)
			(xy 105.846867 -38.626753) (xy 105.798065 -38.719236) (xy 105.742497 -38.807819) (xy 105.680473 -38.892007)
			(xy 105.612339 -38.971332) (xy 105.538475 -39.04535) (xy 105.459292 -39.11365) (xy 105.375234 -39.17585)
			(xy 105.33126 -39.204138) (xy 105.320084 -39.21125) (xy 105.307638 -39.233602) (xy 105.307638 -39.346378)
			(xy 105.320084 -39.36873) (xy 105.33126 -39.375842) (xy 105.376907 -39.405246) (xy 105.464015 -39.470083)
			(xy 105.545836 -39.541477) (xy 105.621875 -39.618999) (xy 105.691677 -39.702182) (xy 105.754821 -39.790526)
			(xy 105.810926 -39.883499) (xy 105.859655 -39.980541) (xy 105.900716 -40.081068) (xy 105.93386 -40.184476)
			(xy 105.958888 -40.290142) (xy 105.975651 -40.39743) (xy 105.984046 -40.505695) (xy 105.984548 -40.55999)
			(xy 105.984095 -40.612343) (xy 105.976272 -40.716757) (xy 105.960669 -40.820294) (xy 105.937372 -40.922376)
			(xy 105.906513 -41.022432) (xy 105.868263 -41.119902) (xy 105.822837 -41.214241) (xy 105.770489 -41.304922)
			(xy 105.711511 -41.391438) (xy 105.646233 -41.473306) (xy 105.57502 -41.550066) (xy 105.498271 -41.621291)
			(xy 105.416414 -41.686581) (xy 105.329907 -41.745573) (xy 105.239234 -41.797935) (xy 105.144902 -41.843376)
			(xy 105.047438 -41.881641) (xy 104.947387 -41.912516) (xy 104.845308 -41.935828) (xy 104.741774 -41.951448)
			(xy 104.637361 -41.959287) (xy 104.585008 -41.959784) (xy 104.530709 -41.959246) (xy 104.422437 -41.95083)
			(xy 104.315143 -41.934047) (xy 104.209473 -41.908999) (xy 104.106062 -41.875835) (xy 104.005533 -41.834757)
			(xy 103.90849 -41.786011) (xy 103.815516 -41.729889) (xy 103.727173 -41.666731) (xy 103.64399 -41.596915)
			(xy 103.566469 -41.520862) (xy 103.495075 -41.43903) (xy 103.430239 -41.35191) (xy 103.40086 -41.306242)
			(xy 103.393748 -41.295066) (xy 103.371396 -41.28262) (xy 103.25862 -41.28262) (xy 103.236268 -41.295066)
			(xy 103.229156 -41.306242) (xy 103.199787 -41.351917) (xy 103.13495 -41.439038) (xy 103.063556 -41.520872)
			(xy 102.986034 -41.596926) (xy 102.902851 -41.666744) (xy 102.814507 -41.729904) (xy 102.721533 -41.786026)
			(xy 102.624489 -41.834774) (xy 102.523959 -41.875854) (xy 102.420547 -41.909019) (xy 102.314876 -41.934068)
			(xy 102.207581 -41.950853) (xy 102.099308 -41.95927) (xy 102.045008 -41.959784) (xy 101.992654 -41.959255)
			(xy 101.888238 -41.95143) (xy 101.7847 -41.935823) (xy 101.682617 -41.912521) (xy 101.582562 -41.881656)
			(xy 101.485093 -41.843398) (xy 101.390756 -41.797963) (xy 101.300078 -41.745605) (xy 101.213567 -41.686616)
			(xy 101.131707 -41.621327) (xy 101.054955 -41.550102) (xy 100.983742 -41.47334) (xy 100.918464 -41.39147)
			(xy 100.859487 -41.304951) (xy 100.807142 -41.214266) (xy 100.761721 -41.119922) (xy 100.723478 -41.022448)
			(xy 100.692627 -40.922388) (xy 100.66934 -40.820302) (xy 100.653748 -40.716761) (xy 100.645938 -40.612344)
			(xy 100.645468 -40.55999) (xy 100.645938 -40.505696) (xy 100.654353 -40.397434) (xy 100.671132 -40.29015)
			(xy 100.696173 -40.184488) (xy 100.729326 -40.081085) (xy 100.770393 -39.980561) (xy 100.819125 -39.883522)
			(xy 100.87523 -39.790551) (xy 100.93837 -39.702206) (xy 101.008166 -39.61902) (xy 101.084198 -39.541492)
			(xy 101.166009 -39.470089) (xy 101.253106 -39.40524) (xy 101.298756 -39.375842) (xy 101.309932 -39.36873)
			(xy 101.322378 -39.346378) (xy 101.322378 -39.233602) (xy 101.309932 -39.21125) (xy 101.298756 -39.204138)
			(xy 101.254773 -39.175864) (xy 101.170712 -39.113664) (xy 101.091528 -39.045364) (xy 101.017662 -38.971345)
			(xy 100.949526 -38.892019) (xy 100.887501 -38.80783) (xy 100.831931 -38.719246) (xy 100.783128 -38.626763)
			(xy 100.741364 -38.530894) (xy 100.70687 -38.432176) (xy 100.67984 -38.33116) (xy 100.660425 -38.228407)
			(xy 100.648733 -38.124492) (xy 100.644828 -38.019995) (xy 0.509016 -38.019995) (xy 0.509016 -46.6242)
			(xy 288.755312 -46.6242) (xy 288.759342 -46.539599) (xy 288.771396 -46.455763) (xy 288.791365 -46.373454)
			(xy 288.819068 -46.293415) (xy 288.854253 -46.216372) (xy 288.896603 -46.143023) (xy 288.945734 -46.074031)
			(xy 289.0012 -46.010023) (xy 289.0625 -45.951576) (xy 289.129078 -45.899222) (xy 289.200331 -45.853433)
			(xy 289.275615 -45.814625) (xy 289.354246 -45.783149) (xy 289.435514 -45.759291) (xy 289.518681 -45.743265)
			(xy 289.602995 -45.735218) (xy 289.645344 -45.734732) (xy 289.684496 -45.735134) (xy 289.7625 -45.741969)
			(xy 289.8396 -45.755642) (xy 289.915198 -45.776048) (xy 289.988706 -45.803028) (xy 290.024312 -45.819314)
			(xy 290.034699 -45.823549) (xy 290.057105 -45.823549) (xy 290.067492 -45.819314) (xy 290.103097 -45.80303)
			(xy 290.176614 -45.77608) (xy 290.252213 -45.755686) (xy 290.32931 -45.742008) (xy 290.407309 -45.735149)
			(xy 290.44646 -45.734732) (xy 290.488812 -45.735138) (xy 290.573134 -45.743186) (xy 290.656308 -45.759214)
			(xy 290.737583 -45.783075) (xy 290.816221 -45.814554) (xy 290.891511 -45.853365) (xy 290.96277 -45.899158)
			(xy 291.029354 -45.951517) (xy 291.090659 -46.009969) (xy 291.14613 -46.073983) (xy 291.195265 -46.142981)
			(xy 291.237618 -46.216336) (xy 291.272807 -46.293386) (xy 291.300512 -46.373432) (xy 291.320482 -46.455749)
			(xy 291.332537 -46.539591) (xy 291.336568 -46.6242) (xy 291.332537 -46.708809) (xy 291.320482 -46.792651)
			(xy 291.300512 -46.874968) (xy 291.272807 -46.955014) (xy 291.237618 -47.032064) (xy 291.195265 -47.105419)
			(xy 291.14613 -47.174417) (xy 291.090659 -47.238431) (xy 291.029354 -47.296883) (xy 290.96277 -47.349242)
			(xy 290.891511 -47.395035) (xy 290.85596 -47.413361) (xy 291.845742 -47.413361) (xy 291.845742 -47.328639)
			(xy 291.853795 -47.244302) (xy 291.869829 -47.161112) (xy 291.893697 -47.079822) (xy 291.925185 -47.00117)
			(xy 291.964007 -46.925867) (xy 292.00981 -46.854595) (xy 292.062181 -46.787999) (xy 292.120646 -46.726684)
			(xy 292.184674 -46.671203) (xy 292.253686 -46.62206) (xy 292.327056 -46.5797) (xy 292.404121 -46.544505)
			(xy 292.484183 -46.516796) (xy 292.566516 -46.496822) (xy 292.650375 -46.484765) (xy 292.735 -46.480734)
			(xy 292.819625 -46.484765) (xy 292.903484 -46.496822) (xy 292.985817 -46.516796) (xy 293.065879 -46.544505)
			(xy 293.142944 -46.5797) (xy 293.216314 -46.62206) (xy 293.285326 -46.671203) (xy 293.349354 -46.726684)
			(xy 293.407819 -46.787999) (xy 293.46019 -46.854595) (xy 293.505993 -46.925867) (xy 293.544815 -47.00117)
			(xy 293.576303 -47.079822) (xy 293.600171 -47.161112) (xy 293.616205 -47.244302) (xy 293.624258 -47.328639)
			(xy 293.624762 -47.371) (xy 293.624258 -47.413361) (xy 293.616205 -47.497698) (xy 293.600171 -47.580888)
			(xy 293.576303 -47.662178) (xy 293.544815 -47.74083) (xy 293.505993 -47.816133) (xy 293.46019 -47.887405)
			(xy 293.407819 -47.954001) (xy 293.349354 -48.015316) (xy 293.285326 -48.070797) (xy 293.216314 -48.11994)
			(xy 293.142944 -48.1623) (xy 293.065879 -48.197495) (xy 292.985817 -48.225204) (xy 292.903484 -48.245178)
			(xy 292.819625 -48.257235) (xy 292.735 -48.261267) (xy 292.650375 -48.257235) (xy 292.566516 -48.245178)
			(xy 292.484183 -48.225204) (xy 292.404121 -48.197495) (xy 292.327056 -48.1623) (xy 292.253686 -48.11994)
			(xy 292.184674 -48.070797) (xy 292.120646 -48.015316) (xy 292.062181 -47.954001) (xy 292.00981 -47.887405)
			(xy 291.964007 -47.816133) (xy 291.925185 -47.74083) (xy 291.893697 -47.662178) (xy 291.869829 -47.580888)
			(xy 291.853795 -47.497698) (xy 291.845742 -47.413361) (xy 290.85596 -47.413361) (xy 290.816221 -47.433846)
			(xy 290.737583 -47.465325) (xy 290.656308 -47.489186) (xy 290.573134 -47.505214) (xy 290.488812 -47.513262)
			(xy 290.44646 -47.513748) (xy 290.407308 -47.513346) (xy 290.329304 -47.506512) (xy 290.252204 -47.492839)
			(xy 290.176606 -47.472433) (xy 290.103098 -47.445452) (xy 290.067492 -47.429166) (xy 290.057105 -47.424931)
			(xy 290.034699 -47.424931) (xy 290.024312 -47.429166) (xy 289.988705 -47.445448) (xy 289.915189 -47.472398)
			(xy 289.839591 -47.492792) (xy 289.762494 -47.506472) (xy 289.684494 -47.513331) (xy 289.645344 -47.513748)
			(xy 289.602995 -47.513182) (xy 289.518681 -47.505135) (xy 289.435514 -47.489109) (xy 289.354246 -47.465251)
			(xy 289.275615 -47.433775) (xy 289.200331 -47.394967) (xy 289.129078 -47.349178) (xy 289.0625 -47.296824)
			(xy 289.0012 -47.238377) (xy 288.945734 -47.174369) (xy 288.896603 -47.105377) (xy 288.854253 -47.032028)
			(xy 288.819068 -46.954985) (xy 288.791365 -46.874946) (xy 288.771396 -46.792637) (xy 288.759342 -46.708801)
			(xy 288.755312 -46.6242) (xy 0.509016 -46.6242) (xy 0.509016 -48.327818) (xy 257.330448 -48.327818)
			(xy 257.331032 -48.281422) (xy 257.340676 -48.189134) (xy 257.359872 -48.09835) (xy 257.38841 -48.010057)
			(xy 257.406648 -47.967392) (xy 257.410445 -47.957447) (xy 257.410452 -47.936186) (xy 257.406648 -47.926244)
			(xy 257.388413 -47.883578) (xy 257.359865 -47.795287) (xy 257.340669 -47.704503) (xy 257.331034 -47.612214)
			(xy 257.330448 -47.565818) (xy 257.330952 -47.52347) (xy 257.339003 -47.439156) (xy 257.355032 -47.35599)
			(xy 257.378893 -47.274723) (xy 257.410372 -47.196093) (xy 257.449183 -47.120812) (xy 257.494973 -47.04956)
			(xy 257.547329 -46.982984) (xy 257.605777 -46.921686) (xy 257.669787 -46.866221) (xy 257.738779 -46.817092)
			(xy 257.812129 -46.774743) (xy 257.889172 -46.739559) (xy 257.969211 -46.711857) (xy 258.05152 -46.691889)
			(xy 258.135355 -46.679836) (xy 258.219956 -46.675806) (xy 258.304557 -46.679836) (xy 258.388392 -46.691889)
			(xy 258.470701 -46.711857) (xy 258.55074 -46.739559) (xy 258.627783 -46.774743) (xy 258.701133 -46.817092)
			(xy 258.770125 -46.866221) (xy 258.834135 -46.921686) (xy 258.892583 -46.982984) (xy 258.944939 -47.04956)
			(xy 258.990729 -47.120812) (xy 259.02954 -47.196093) (xy 259.061019 -47.274723) (xy 259.08488 -47.35599)
			(xy 259.100909 -47.439156) (xy 259.10896 -47.52347) (xy 259.109464 -47.565818) (xy 259.108891 -47.612214)
			(xy 259.099244 -47.704503) (xy 259.080045 -47.795286) (xy 259.051504 -47.88358) (xy 259.033264 -47.926244)
			(xy 259.029445 -47.936182) (xy 259.029452 -47.95745) (xy 259.033264 -47.967392) (xy 259.051512 -48.010053)
			(xy 259.080056 -48.098346) (xy 259.099248 -48.189131) (xy 259.10888 -48.281422) (xy 259.109464 -48.327818)
			(xy 259.10896 -48.370166) (xy 259.100909 -48.45448) (xy 259.08488 -48.537646) (xy 259.061019 -48.618913)
			(xy 259.02954 -48.697543) (xy 258.990729 -48.772824) (xy 258.944939 -48.844076) (xy 258.892583 -48.910652)
			(xy 258.834135 -48.97195) (xy 258.770125 -49.027415) (xy 258.701133 -49.076544) (xy 258.627783 -49.118893)
			(xy 258.55074 -49.154077) (xy 258.470701 -49.181779) (xy 258.388392 -49.201747) (xy 258.304557 -49.2138)
			(xy 258.219956 -49.217831) (xy 258.135355 -49.2138) (xy 258.05152 -49.201747) (xy 257.969211 -49.181779)
			(xy 257.889172 -49.154077) (xy 257.812129 -49.118893) (xy 257.738779 -49.076544) (xy 257.669787 -49.027415)
			(xy 257.605777 -48.97195) (xy 257.547329 -48.910652) (xy 257.494973 -48.844076) (xy 257.449183 -48.772824)
			(xy 257.410372 -48.697543) (xy 257.378893 -48.618913) (xy 257.355032 -48.537646) (xy 257.339003 -48.45448)
			(xy 257.330952 -48.370166) (xy 257.330448 -48.327818) (xy 0.509016 -48.327818) (xy 0.509016 -52.2859)
			(xy 43.474132 -52.2859) (xy 43.47455 -52.246133) (xy 43.48159 -52.166911) (xy 43.495677 -52.088634)
			(xy 43.516699 -52.011928) (xy 43.544486 -51.937406) (xy 43.561254 -51.901344) (xy 43.565585 -51.890843)
			(xy 43.565585 -51.868157) (xy 43.561254 -51.857656) (xy 43.544513 -51.821583) (xy 43.516732 -51.74706)
			(xy 43.495709 -51.670357) (xy 43.481612 -51.592084) (xy 43.474554 -51.512866) (xy 43.474132 -51.4731)
			(xy 43.474546 -51.432489) (xy 43.481951 -51.351605) (xy 43.496699 -51.271733) (xy 43.518668 -51.193537)
			(xy 43.547674 -51.117671) (xy 43.583475 -51.044765) (xy 43.625775 -50.975426) (xy 43.674219 -50.910233)
			(xy 43.728406 -50.849727) (xy 43.787882 -50.794414) (xy 43.852155 -50.744753) (xy 43.920686 -50.701159)
			(xy 43.992907 -50.663994) (xy 44.030392 -50.648362) (xy 44.040552 -50.644044) (xy 44.055792 -50.628042)
			(xy 44.087796 -50.534062) (xy 44.08551 -50.511964) (xy 44.079922 -50.502566) (xy 44.060228 -50.46832)
			(xy 44.026305 -50.396969) (xy 43.998845 -50.322889) (xy 43.978066 -50.246665) (xy 43.96413 -50.168899)
			(xy 43.957148 -50.090203) (xy 43.956732 -50.0507) (xy 43.957152 -50.009596) (xy 43.964738 -49.927738)
			(xy 43.979844 -49.846929) (xy 44.002342 -49.767859) (xy 44.03204 -49.691202) (xy 44.068685 -49.617612)
			(xy 44.111963 -49.547717) (xy 44.161506 -49.482114) (xy 44.216891 -49.421363) (xy 44.277645 -49.36598)
			(xy 44.34325 -49.31644) (xy 44.413147 -49.273165) (xy 44.486738 -49.236524) (xy 44.563397 -49.206829)
			(xy 44.642468 -49.184335) (xy 44.723277 -49.169232) (xy 44.805136 -49.16165) (xy 44.84624 -49.161192)
			(xy 44.891005 -49.161711) (xy 44.980087 -49.170644) (xy 45.06782 -49.188486) (xy 45.153315 -49.215055)
			(xy 45.194728 -49.232058) (xy 45.204319 -49.235623) (xy 45.224761 -49.235623) (xy 45.234352 -49.232058)
			(xy 45.275769 -49.215065) (xy 45.361266 -49.188508) (xy 45.448997 -49.170667) (xy 45.538076 -49.161723)
			(xy 45.58284 -49.161192) (xy 45.625958 -49.161716) (xy 45.71179 -49.170059) (xy 45.796411 -49.186672)
			(xy 45.879027 -49.211399) (xy 45.919136 -49.227232) (xy 45.928507 -49.230558) (xy 45.948373 -49.230558)
			(xy 45.957744 -49.227232) (xy 45.997848 -49.211383) (xy 46.080465 -49.186656) (xy 46.165087 -49.170043)
			(xy 46.250921 -49.161699) (xy 46.29404 -49.161192) (xy 46.336388 -49.161696) (xy 46.420702 -49.169747)
			(xy 46.503868 -49.185776) (xy 46.585135 -49.209637) (xy 46.663765 -49.241116) (xy 46.739046 -49.279927)
			(xy 46.810298 -49.325717) (xy 46.876874 -49.378073) (xy 46.938172 -49.436521) (xy 46.993637 -49.500531)
			(xy 47.042766 -49.569523) (xy 47.085115 -49.642873) (xy 47.120299 -49.719916) (xy 47.148001 -49.799955)
			(xy 47.167969 -49.882264) (xy 47.180022 -49.966099) (xy 47.184053 -50.0507) (xy 47.180022 -50.135301)
			(xy 47.167969 -50.219136) (xy 47.148001 -50.301445) (xy 47.120299 -50.381484) (xy 47.085115 -50.458527)
			(xy 47.042766 -50.531877) (xy 46.993637 -50.600869) (xy 46.938172 -50.664879) (xy 46.876874 -50.723327)
			(xy 46.810298 -50.775683) (xy 46.739046 -50.821473) (xy 46.663765 -50.860284) (xy 46.585135 -50.891763)
			(xy 46.503868 -50.915624) (xy 46.420702 -50.931653) (xy 46.336388 -50.939704) (xy 46.29404 -50.940208)
			(xy 46.250922 -50.939691) (xy 46.165089 -50.931346) (xy 46.080468 -50.914731) (xy 45.997853 -50.890002)
			(xy 45.957744 -50.874168) (xy 45.948373 -50.870842) (xy 45.928507 -50.870842) (xy 45.919136 -50.874168)
			(xy 45.879023 -50.889992) (xy 45.796409 -50.914725) (xy 45.71179 -50.931346) (xy 45.625958 -50.939697)
			(xy 45.58284 -50.940208) (xy 45.538075 -50.939695) (xy 45.448993 -50.930761) (xy 45.36126 -50.912917)
			(xy 45.275765 -50.886346) (xy 45.234352 -50.869342) (xy 45.224761 -50.865777) (xy 45.204319 -50.865777)
			(xy 45.194728 -50.869342) (xy 45.179488 -50.875438) (xy 45.169328 -50.879756) (xy 45.154088 -50.895758)
			(xy 45.122084 -50.989738) (xy 45.12437 -51.011836) (xy 45.129958 -51.021234) (xy 45.14965 -51.055481)
			(xy 45.183574 -51.126832) (xy 45.211034 -51.200912) (xy 45.231814 -51.277135) (xy 45.24575 -51.354901)
			(xy 45.252732 -51.433597) (xy 45.253148 -51.4731) (xy 45.252732 -51.512867) (xy 45.245691 -51.59209)
			(xy 45.231604 -51.670366) (xy 45.210582 -51.747072) (xy 45.182794 -51.821594) (xy 45.166026 -51.857656)
			(xy 45.161691 -51.868157) (xy 45.161691 -51.890843) (xy 45.166026 -51.901344) (xy 45.182773 -51.937415)
			(xy 45.210551 -52.011938) (xy 45.231572 -52.088642) (xy 45.245668 -52.166915) (xy 45.252726 -52.246134)
			(xy 45.253148 -52.2859) (xy 45.252644 -52.328248) (xy 45.244593 -52.412562) (xy 45.228564 -52.495728)
			(xy 45.204703 -52.576995) (xy 45.173224 -52.655625) (xy 45.134413 -52.730906) (xy 45.088623 -52.802158)
			(xy 45.036267 -52.868734) (xy 44.986526 -52.9209) (xy 46.166532 -52.9209) (xy 46.167111 -52.874504)
			(xy 46.176757 -52.782216) (xy 46.195954 -52.691432) (xy 46.224493 -52.603139) (xy 46.242732 -52.560474)
			(xy 46.246541 -52.550532) (xy 46.246541 -52.529268) (xy 46.242732 -52.519326) (xy 46.22449 -52.476663)
			(xy 46.195944 -52.388371) (xy 46.176751 -52.297586) (xy 46.167117 -52.205296) (xy 46.166532 -52.1589)
			(xy 46.167036 -52.116552) (xy 46.175087 -52.032238) (xy 46.191116 -51.949072) (xy 46.214977 -51.867805)
			(xy 46.246456 -51.789175) (xy 46.285267 -51.713894) (xy 46.331057 -51.642642) (xy 46.383413 -51.576066)
			(xy 46.441861 -51.514768) (xy 46.505871 -51.459303) (xy 46.574863 -51.410174) (xy 46.648213 -51.367825)
			(xy 46.725256 -51.332641) (xy 46.805295 -51.304939) (xy 46.887604 -51.284971) (xy 46.971439 -51.272918)
			(xy 47.05604 -51.268888) (xy 47.140641 -51.272918) (xy 47.224476 -51.284971) (xy 47.306785 -51.304939)
			(xy 47.386824 -51.332641) (xy 47.463867 -51.367825) (xy 47.537217 -51.410174) (xy 47.606209 -51.459303)
			(xy 47.670219 -51.514768) (xy 47.728667 -51.576066) (xy 47.781023 -51.642642) (xy 47.826813 -51.713894)
			(xy 47.865624 -51.789175) (xy 47.897103 -51.867805) (xy 47.920964 -51.949072) (xy 47.936993 -52.032238)
			(xy 47.945044 -52.116552) (xy 47.945548 -52.1589) (xy 47.94497 -52.205296) (xy 47.935324 -52.297584)
			(xy 47.916127 -52.388368) (xy 47.887587 -52.476662) (xy 47.869348 -52.519326) (xy 47.86554 -52.529268)
			(xy 47.86554 -52.550532) (xy 47.869348 -52.560474) (xy 47.887595 -52.603135) (xy 47.916138 -52.691428)
			(xy 47.93533 -52.782213) (xy 47.944963 -52.874504) (xy 47.945068 -52.8828) (xy 48.427132 -52.8828)
			(xy 48.427711 -52.836404) (xy 48.437357 -52.744116) (xy 48.456554 -52.653332) (xy 48.485093 -52.565039)
			(xy 48.503332 -52.522374) (xy 48.507141 -52.512432) (xy 48.507141 -52.491168) (xy 48.503332 -52.481226)
			(xy 48.48509 -52.438563) (xy 48.456544 -52.350271) (xy 48.437351 -52.259486) (xy 48.427717 -52.167196)
			(xy 48.427132 -52.1208) (xy 48.427552 -52.079696) (xy 48.435138 -51.997838) (xy 48.450244 -51.917029)
			(xy 48.472742 -51.837959) (xy 48.50244 -51.761302) (xy 48.539085 -51.687712) (xy 48.582363 -51.617817)
			(xy 48.631906 -51.552214) (xy 48.687291 -51.491463) (xy 48.748045 -51.43608) (xy 48.81365 -51.38654)
			(xy 48.883547 -51.343265) (xy 48.957138 -51.306624) (xy 49.033797 -51.276929) (xy 49.112868 -51.254435)
			(xy 49.193677 -51.239332) (xy 49.275536 -51.23175) (xy 49.31664 -51.231292) (xy 49.363035 -51.231896)
			(xy 49.455323 -51.241535) (xy 49.546107 -51.260725) (xy 49.634401 -51.289257) (xy 49.677066 -51.307492)
			(xy 49.687008 -51.311298) (xy 49.708272 -51.311298) (xy 49.718214 -51.307492) (xy 49.760871 -51.289234)
			(xy 49.849165 -51.260693) (xy 49.939952 -51.241504) (xy 50.032243 -51.231875) (xy 50.07864 -51.231292)
			(xy 50.125035 -51.231896) (xy 50.217323 -51.241535) (xy 50.308107 -51.260725) (xy 50.396401 -51.289257)
			(xy 50.439066 -51.307492) (xy 50.449008 -51.311298) (xy 50.470272 -51.311298) (xy 50.480214 -51.307492)
			(xy 50.522871 -51.289234) (xy 50.611165 -51.260693) (xy 50.701952 -51.241504) (xy 50.794243 -51.231875)
			(xy 50.84064 -51.231292) (xy 50.881743 -51.231728) (xy 50.963598 -51.239317) (xy 51.044404 -51.254426)
			(xy 51.123472 -51.276925) (xy 51.200126 -51.306624) (xy 51.273713 -51.343269) (xy 51.343605 -51.386547)
			(xy 51.409206 -51.436089) (xy 51.469955 -51.491473) (xy 51.525336 -51.552225) (xy 51.574875 -51.617828)
			(xy 51.61815 -51.687722) (xy 51.654792 -51.761311) (xy 51.684487 -51.837966) (xy 51.706984 -51.917034)
			(xy 51.722089 -51.997841) (xy 51.729673 -52.079697) (xy 51.730148 -52.1208) (xy 51.72957 -52.167196)
			(xy 51.719924 -52.259484) (xy 51.706282 -52.324) (xy 70.992492 -52.324) (xy 70.99288 -52.285716)
			(xy 70.999419 -52.209427) (xy 71.0125 -52.133985) (xy 71.032027 -52.059948) (xy 71.044562 -52.023772)
			(xy 71.047213 -52.015335) (xy 71.047213 -51.997665) (xy 71.044562 -51.989228) (xy 71.032037 -51.95305)
			(xy 71.012529 -51.87901) (xy 70.999449 -51.803569) (xy 70.992894 -51.727283) (xy 70.992492 -51.689)
			(xy 70.992943 -51.648953) (xy 71.000117 -51.569181) (xy 71.014434 -51.490378) (xy 71.035778 -51.413181)
			(xy 71.063976 -51.338215) (xy 71.0988 -51.266088) (xy 71.139968 -51.197385) (xy 71.187146 -51.13266)
			(xy 71.213218 -51.10226) (xy 71.218983 -51.095171) (xy 71.225495 -51.078114) (xy 71.225918 -51.068986)
			(xy 71.225918 -51.039014) (xy 71.225484 -51.029891) (xy 71.218964 -51.012841) (xy 71.213218 -51.00574)
			(xy 71.187158 -50.975329) (xy 71.139979 -50.910606) (xy 71.098809 -50.841904) (xy 71.063981 -50.769779)
			(xy 71.035779 -50.694815) (xy 71.014429 -50.61762) (xy 71.000105 -50.538818) (xy 70.992923 -50.459047)
			(xy 70.992492 -50.419) (xy 70.99288 -50.380716) (xy 70.999419 -50.304427) (xy 71.0125 -50.228985)
			(xy 71.032027 -50.154948) (xy 71.044562 -50.118772) (xy 71.047213 -50.110335) (xy 71.047213 -50.092665)
			(xy 71.044562 -50.084228) (xy 71.032037 -50.04805) (xy 71.012529 -49.97401) (xy 70.999449 -49.898569)
			(xy 70.992894 -49.822283) (xy 70.992492 -49.784) (xy 70.992996 -49.741652) (xy 71.001047 -49.657338)
			(xy 71.017076 -49.574172) (xy 71.040937 -49.492905) (xy 71.072416 -49.414275) (xy 71.111227 -49.338994)
			(xy 71.157017 -49.267742) (xy 71.209373 -49.201166) (xy 71.267821 -49.139868) (xy 71.331831 -49.084403)
			(xy 71.400823 -49.035274) (xy 71.474173 -48.992925) (xy 71.551216 -48.957741) (xy 71.631255 -48.930039)
			(xy 71.713564 -48.910071) (xy 71.797399 -48.898018) (xy 71.882 -48.893988) (xy 71.966601 -48.898018)
			(xy 72.050436 -48.910071) (xy 72.132745 -48.930039) (xy 72.212784 -48.957741) (xy 72.289827 -48.992925)
			(xy 72.363177 -49.035274) (xy 72.432169 -49.084403) (xy 72.496179 -49.139868) (xy 72.554627 -49.201166)
			(xy 72.606983 -49.267742) (xy 72.652773 -49.338994) (xy 72.691584 -49.414275) (xy 72.723063 -49.492905)
			(xy 72.746924 -49.574172) (xy 72.762953 -49.657338) (xy 72.771004 -49.741652) (xy 72.771508 -49.784)
			(xy 72.77112 -49.822284) (xy 72.764581 -49.898573) (xy 72.7515 -49.974015) (xy 72.731973 -50.048052)
			(xy 72.719438 -50.084228) (xy 72.716787 -50.092665) (xy 72.716787 -50.110335) (xy 72.719438 -50.118772)
			(xy 72.731963 -50.15495) (xy 72.751471 -50.22899) (xy 72.764551 -50.304431) (xy 72.771106 -50.380717)
			(xy 72.771508 -50.419) (xy 72.771057 -50.459047) (xy 72.763883 -50.538819) (xy 72.749566 -50.617622)
			(xy 72.728222 -50.694819) (xy 72.700024 -50.769785) (xy 72.6652 -50.841912) (xy 72.624032 -50.910615)
			(xy 72.576854 -50.97534) (xy 72.550782 -51.00574) (xy 72.545017 -51.012829) (xy 72.538505 -51.029886)
			(xy 72.538082 -51.039014) (xy 72.538082 -51.068986) (xy 72.538516 -51.078109) (xy 72.545036 -51.095159)
			(xy 72.550782 -51.10226) (xy 72.576842 -51.132671) (xy 72.624021 -51.197394) (xy 72.665191 -51.266096)
			(xy 72.700019 -51.338221) (xy 72.728221 -51.413185) (xy 72.749571 -51.49038) (xy 72.763895 -51.569182)
			(xy 72.771077 -51.648953) (xy 72.771508 -51.689) (xy 72.77112 -51.727284) (xy 72.764581 -51.803573)
			(xy 72.7515 -51.879015) (xy 72.731973 -51.953052) (xy 72.719438 -51.989228) (xy 72.716787 -51.997665)
			(xy 72.716787 -52.015335) (xy 72.719438 -52.023772) (xy 72.731963 -52.05995) (xy 72.751471 -52.13399)
			(xy 72.764551 -52.209431) (xy 72.771106 -52.285717) (xy 72.771508 -52.324) (xy 76.453492 -52.324)
			(xy 76.45388 -52.285716) (xy 76.460419 -52.209427) (xy 76.4735 -52.133985) (xy 76.493027 -52.059948)
			(xy 76.505562 -52.023772) (xy 76.508213 -52.015335) (xy 76.508213 -51.997665) (xy 76.505562 -51.989228)
			(xy 76.493037 -51.95305) (xy 76.473529 -51.87901) (xy 76.460449 -51.803569) (xy 76.453894 -51.727283)
			(xy 76.453492 -51.689) (xy 76.453943 -51.648953) (xy 76.461117 -51.569181) (xy 76.475434 -51.490378)
			(xy 76.496778 -51.413181) (xy 76.524976 -51.338215) (xy 76.5598 -51.266088) (xy 76.600968 -51.197385)
			(xy 76.648146 -51.13266) (xy 76.674218 -51.10226) (xy 76.679983 -51.095171) (xy 76.686495 -51.078114)
			(xy 76.686918 -51.068986) (xy 76.686918 -51.039014) (xy 76.686484 -51.029891) (xy 76.679964 -51.012841)
			(xy 76.674218 -51.00574) (xy 76.648158 -50.975329) (xy 76.600979 -50.910606) (xy 76.559809 -50.841904)
			(xy 76.524981 -50.769779) (xy 76.496779 -50.694815) (xy 76.475429 -50.61762) (xy 76.461105 -50.538818)
			(xy 76.453923 -50.459047) (xy 76.453492 -50.419) (xy 76.45388 -50.380716) (xy 76.460419 -50.304427)
			(xy 76.4735 -50.228985) (xy 76.493027 -50.154948) (xy 76.505562 -50.118772) (xy 76.508213 -50.110335)
			(xy 76.508213 -50.092665) (xy 76.505562 -50.084228) (xy 76.493037 -50.04805) (xy 76.473529 -49.97401)
			(xy 76.460449 -49.898569) (xy 76.453894 -49.822283) (xy 76.453492 -49.784) (xy 76.453996 -49.741652)
			(xy 76.462047 -49.657338) (xy 76.478076 -49.574172) (xy 76.501937 -49.492905) (xy 76.533416 -49.414275)
			(xy 76.572227 -49.338994) (xy 76.618017 -49.267742) (xy 76.670373 -49.201166) (xy 76.728821 -49.139868)
			(xy 76.792831 -49.084403) (xy 76.861823 -49.035274) (xy 76.935173 -48.992925) (xy 77.012216 -48.957741)
			(xy 77.092255 -48.930039) (xy 77.174564 -48.910071) (xy 77.258399 -48.898018) (xy 77.343 -48.893988)
			(xy 77.427601 -48.898018) (xy 77.511436 -48.910071) (xy 77.593745 -48.930039) (xy 77.673784 -48.957741)
			(xy 77.750827 -48.992925) (xy 77.824177 -49.035274) (xy 77.893169 -49.084403) (xy 77.957179 -49.139868)
			(xy 78.015627 -49.201166) (xy 78.067983 -49.267742) (xy 78.113773 -49.338994) (xy 78.152584 -49.414275)
			(xy 78.184063 -49.492905) (xy 78.207924 -49.574172) (xy 78.223953 -49.657338) (xy 78.232004 -49.741652)
			(xy 78.232508 -49.784) (xy 78.23212 -49.822284) (xy 78.225581 -49.898573) (xy 78.2125 -49.974015)
			(xy 78.192973 -50.048052) (xy 78.180438 -50.084228) (xy 78.177787 -50.092665) (xy 78.177787 -50.110335)
			(xy 78.180438 -50.118772) (xy 78.192963 -50.15495) (xy 78.212471 -50.22899) (xy 78.225551 -50.304431)
			(xy 78.232106 -50.380717) (xy 78.232508 -50.419) (xy 78.232057 -50.459047) (xy 78.224883 -50.538819)
			(xy 78.210566 -50.617622) (xy 78.189222 -50.694819) (xy 78.161024 -50.769785) (xy 78.1262 -50.841912)
			(xy 78.085032 -50.910615) (xy 78.037854 -50.97534) (xy 78.011782 -51.00574) (xy 78.006017 -51.012829)
			(xy 77.999505 -51.029886) (xy 77.999082 -51.039014) (xy 77.999082 -51.068986) (xy 77.999516 -51.078109)
			(xy 78.006036 -51.095159) (xy 78.011782 -51.10226) (xy 78.037842 -51.132671) (xy 78.085021 -51.197394)
			(xy 78.126191 -51.266096) (xy 78.161019 -51.338221) (xy 78.189221 -51.413185) (xy 78.210571 -51.49038)
			(xy 78.224895 -51.569182) (xy 78.232077 -51.648953) (xy 78.232508 -51.689) (xy 78.23212 -51.727284)
			(xy 78.225581 -51.803573) (xy 78.2125 -51.879015) (xy 78.192973 -51.953052) (xy 78.180438 -51.989228)
			(xy 78.177787 -51.997665) (xy 78.177787 -52.015335) (xy 78.180438 -52.023772) (xy 78.192963 -52.05995)
			(xy 78.212471 -52.13399) (xy 78.225551 -52.209431) (xy 78.232106 -52.285717) (xy 78.232508 -52.324)
			(xy 81.914492 -52.324) (xy 81.91488 -52.285716) (xy 81.921419 -52.209427) (xy 81.9345 -52.133985)
			(xy 81.954027 -52.059948) (xy 81.966562 -52.023772) (xy 81.969213 -52.015335) (xy 81.969213 -51.997665)
			(xy 81.966562 -51.989228) (xy 81.954037 -51.95305) (xy 81.934529 -51.87901) (xy 81.921449 -51.803569)
			(xy 81.914894 -51.727283) (xy 81.914492 -51.689) (xy 81.914943 -51.648953) (xy 81.922117 -51.569181)
			(xy 81.936434 -51.490378) (xy 81.957778 -51.413181) (xy 81.985976 -51.338215) (xy 82.0208 -51.266088)
			(xy 82.061968 -51.197385) (xy 82.109146 -51.13266) (xy 82.135218 -51.10226) (xy 82.140983 -51.095171)
			(xy 82.147495 -51.078114) (xy 82.147918 -51.068986) (xy 82.147918 -51.039014) (xy 82.147484 -51.029891)
			(xy 82.140964 -51.012841) (xy 82.135218 -51.00574) (xy 82.109158 -50.975329) (xy 82.061979 -50.910606)
			(xy 82.020809 -50.841904) (xy 81.985981 -50.769779) (xy 81.957779 -50.694815) (xy 81.936429 -50.61762)
			(xy 81.922105 -50.538818) (xy 81.914923 -50.459047) (xy 81.914492 -50.419) (xy 81.91488 -50.380716)
			(xy 81.921419 -50.304427) (xy 81.9345 -50.228985) (xy 81.954027 -50.154948) (xy 81.966562 -50.118772)
			(xy 81.969213 -50.110335) (xy 81.969213 -50.092665) (xy 81.966562 -50.084228) (xy 81.954037 -50.04805)
			(xy 81.934529 -49.97401) (xy 81.921449 -49.898569) (xy 81.914894 -49.822283) (xy 81.914492 -49.784)
			(xy 81.914996 -49.741652) (xy 81.923047 -49.657338) (xy 81.939076 -49.574172) (xy 81.962937 -49.492905)
			(xy 81.994416 -49.414275) (xy 82.033227 -49.338994) (xy 82.079017 -49.267742) (xy 82.131373 -49.201166)
			(xy 82.189821 -49.139868) (xy 82.253831 -49.084403) (xy 82.322823 -49.035274) (xy 82.396173 -48.992925)
			(xy 82.473216 -48.957741) (xy 82.553255 -48.930039) (xy 82.635564 -48.910071) (xy 82.719399 -48.898018)
			(xy 82.804 -48.893988) (xy 82.888601 -48.898018) (xy 82.972436 -48.910071) (xy 83.054745 -48.930039)
			(xy 83.134784 -48.957741) (xy 83.211827 -48.992925) (xy 83.285177 -49.035274) (xy 83.354169 -49.084403)
			(xy 83.418179 -49.139868) (xy 83.476627 -49.201166) (xy 83.528983 -49.267742) (xy 83.574773 -49.338994)
			(xy 83.613584 -49.414275) (xy 83.645063 -49.492905) (xy 83.668924 -49.574172) (xy 83.684953 -49.657338)
			(xy 83.693004 -49.741652) (xy 83.693508 -49.784) (xy 83.69312 -49.822284) (xy 83.686581 -49.898573)
			(xy 83.6735 -49.974015) (xy 83.653973 -50.048052) (xy 83.641438 -50.084228) (xy 83.638787 -50.092665)
			(xy 83.638787 -50.110335) (xy 83.641438 -50.118772) (xy 83.653963 -50.15495) (xy 83.673471 -50.22899)
			(xy 83.686551 -50.304431) (xy 83.693106 -50.380717) (xy 83.693508 -50.419) (xy 83.693057 -50.459047)
			(xy 83.685883 -50.538819) (xy 83.671566 -50.617622) (xy 83.650222 -50.694819) (xy 83.622024 -50.769785)
			(xy 83.5872 -50.841912) (xy 83.546032 -50.910615) (xy 83.498854 -50.97534) (xy 83.472782 -51.00574)
			(xy 83.467017 -51.012829) (xy 83.460505 -51.029886) (xy 83.460082 -51.039014) (xy 83.460082 -51.068986)
			(xy 83.460516 -51.078109) (xy 83.467036 -51.095159) (xy 83.472782 -51.10226) (xy 83.498842 -51.132671)
			(xy 83.546021 -51.197394) (xy 83.587191 -51.266096) (xy 83.622019 -51.338221) (xy 83.650221 -51.413185)
			(xy 83.671571 -51.49038) (xy 83.685895 -51.569182) (xy 83.693077 -51.648953) (xy 83.693508 -51.689)
			(xy 83.69312 -51.727284) (xy 83.686581 -51.803573) (xy 83.6735 -51.879015) (xy 83.653973 -51.953052)
			(xy 83.641438 -51.989228) (xy 83.638787 -51.997665) (xy 83.638787 -52.015335) (xy 83.641438 -52.023772)
			(xy 83.653963 -52.05995) (xy 83.673471 -52.13399) (xy 83.686551 -52.209431) (xy 83.693106 -52.285717)
			(xy 83.693508 -52.324) (xy 87.375492 -52.324) (xy 87.37588 -52.285716) (xy 87.382419 -52.209427)
			(xy 87.3955 -52.133985) (xy 87.415027 -52.059948) (xy 87.427562 -52.023772) (xy 87.430213 -52.015335)
			(xy 87.430213 -51.997665) (xy 87.427562 -51.989228) (xy 87.415037 -51.95305) (xy 87.395529 -51.87901)
			(xy 87.382449 -51.803569) (xy 87.375894 -51.727283) (xy 87.375492 -51.689) (xy 87.375943 -51.648953)
			(xy 87.383117 -51.569181) (xy 87.397434 -51.490378) (xy 87.418778 -51.413181) (xy 87.446976 -51.338215)
			(xy 87.4818 -51.266088) (xy 87.522968 -51.197385) (xy 87.570146 -51.13266) (xy 87.596218 -51.10226)
			(xy 87.601983 -51.095171) (xy 87.608495 -51.078114) (xy 87.608918 -51.068986) (xy 87.608918 -51.039014)
			(xy 87.608484 -51.029891) (xy 87.601964 -51.012841) (xy 87.596218 -51.00574) (xy 87.570158 -50.975329)
			(xy 87.522979 -50.910606) (xy 87.481809 -50.841904) (xy 87.446981 -50.769779) (xy 87.418779 -50.694815)
			(xy 87.397429 -50.61762) (xy 87.383105 -50.538818) (xy 87.375923 -50.459047) (xy 87.375492 -50.419)
			(xy 87.37588 -50.380716) (xy 87.382419 -50.304427) (xy 87.3955 -50.228985) (xy 87.415027 -50.154948)
			(xy 87.427562 -50.118772) (xy 87.430213 -50.110335) (xy 87.430213 -50.092665) (xy 87.427562 -50.084228)
			(xy 87.415037 -50.04805) (xy 87.395529 -49.97401) (xy 87.382449 -49.898569) (xy 87.375894 -49.822283)
			(xy 87.375492 -49.784) (xy 87.375996 -49.741652) (xy 87.384047 -49.657338) (xy 87.400076 -49.574172)
			(xy 87.423937 -49.492905) (xy 87.455416 -49.414275) (xy 87.494227 -49.338994) (xy 87.540017 -49.267742)
			(xy 87.592373 -49.201166) (xy 87.650821 -49.139868) (xy 87.714831 -49.084403) (xy 87.783823 -49.035274)
			(xy 87.857173 -48.992925) (xy 87.934216 -48.957741) (xy 88.014255 -48.930039) (xy 88.096564 -48.910071)
			(xy 88.180399 -48.898018) (xy 88.265 -48.893988) (xy 88.349601 -48.898018) (xy 88.433436 -48.910071)
			(xy 88.515745 -48.930039) (xy 88.595784 -48.957741) (xy 88.672827 -48.992925) (xy 88.746177 -49.035274)
			(xy 88.815169 -49.084403) (xy 88.879179 -49.139868) (xy 88.937627 -49.201166) (xy 88.989983 -49.267742)
			(xy 89.035773 -49.338994) (xy 89.074584 -49.414275) (xy 89.106063 -49.492905) (xy 89.129924 -49.574172)
			(xy 89.145953 -49.657338) (xy 89.154004 -49.741652) (xy 89.154508 -49.784) (xy 89.15412 -49.822284)
			(xy 89.147581 -49.898573) (xy 89.1345 -49.974015) (xy 89.114973 -50.048052) (xy 89.102438 -50.084228)
			(xy 89.099787 -50.092665) (xy 89.099787 -50.110335) (xy 89.102438 -50.118772) (xy 89.114963 -50.15495)
			(xy 89.134471 -50.22899) (xy 89.147551 -50.304431) (xy 89.154106 -50.380717) (xy 89.154508 -50.419)
			(xy 89.154057 -50.459047) (xy 89.146883 -50.538819) (xy 89.132566 -50.617622) (xy 89.111222 -50.694819)
			(xy 89.083024 -50.769785) (xy 89.0482 -50.841912) (xy 89.007032 -50.910615) (xy 88.959854 -50.97534)
			(xy 88.933782 -51.00574) (xy 88.928017 -51.012829) (xy 88.921505 -51.029886) (xy 88.921082 -51.039014)
			(xy 88.921082 -51.068986) (xy 88.921516 -51.078109) (xy 88.928036 -51.095159) (xy 88.933782 -51.10226)
			(xy 88.959842 -51.132671) (xy 89.007021 -51.197394) (xy 89.048191 -51.266096) (xy 89.083019 -51.338221)
			(xy 89.111221 -51.413185) (xy 89.132571 -51.49038) (xy 89.146895 -51.569182) (xy 89.154077 -51.648953)
			(xy 89.154508 -51.689) (xy 89.15412 -51.727284) (xy 89.147581 -51.803573) (xy 89.1345 -51.879015)
			(xy 89.114973 -51.953052) (xy 89.102438 -51.989228) (xy 89.099787 -51.997665) (xy 89.099787 -52.015335)
			(xy 89.102438 -52.023772) (xy 89.114963 -52.05995) (xy 89.134471 -52.13399) (xy 89.147551 -52.209431)
			(xy 89.154106 -52.285717) (xy 89.154508 -52.324) (xy 92.836492 -52.324) (xy 92.83688 -52.285716)
			(xy 92.843419 -52.209427) (xy 92.8565 -52.133985) (xy 92.876027 -52.059948) (xy 92.888562 -52.023772)
			(xy 92.891213 -52.015335) (xy 92.891213 -51.997665) (xy 92.888562 -51.989228) (xy 92.876037 -51.95305)
			(xy 92.856529 -51.87901) (xy 92.843449 -51.803569) (xy 92.836894 -51.727283) (xy 92.836492 -51.689)
			(xy 92.836943 -51.648953) (xy 92.844117 -51.569181) (xy 92.858434 -51.490378) (xy 92.879778 -51.413181)
			(xy 92.907976 -51.338215) (xy 92.9428 -51.266088) (xy 92.983968 -51.197385) (xy 93.031146 -51.13266)
			(xy 93.057218 -51.10226) (xy 93.062983 -51.095171) (xy 93.069495 -51.078114) (xy 93.069918 -51.068986)
			(xy 93.069918 -51.039014) (xy 93.069484 -51.029891) (xy 93.062964 -51.012841) (xy 93.057218 -51.00574)
			(xy 93.031158 -50.975329) (xy 92.983979 -50.910606) (xy 92.942809 -50.841904) (xy 92.907981 -50.769779)
			(xy 92.879779 -50.694815) (xy 92.858429 -50.61762) (xy 92.844105 -50.538818) (xy 92.836923 -50.459047)
			(xy 92.836492 -50.419) (xy 92.83688 -50.380716) (xy 92.843419 -50.304427) (xy 92.8565 -50.228985)
			(xy 92.876027 -50.154948) (xy 92.888562 -50.118772) (xy 92.891213 -50.110335) (xy 92.891213 -50.092665)
			(xy 92.888562 -50.084228) (xy 92.876037 -50.04805) (xy 92.856529 -49.97401) (xy 92.843449 -49.898569)
			(xy 92.836894 -49.822283) (xy 92.836492 -49.784) (xy 92.836996 -49.741652) (xy 92.845047 -49.657338)
			(xy 92.861076 -49.574172) (xy 92.884937 -49.492905) (xy 92.916416 -49.414275) (xy 92.955227 -49.338994)
			(xy 93.001017 -49.267742) (xy 93.053373 -49.201166) (xy 93.111821 -49.139868) (xy 93.175831 -49.084403)
			(xy 93.244823 -49.035274) (xy 93.318173 -48.992925) (xy 93.395216 -48.957741) (xy 93.475255 -48.930039)
			(xy 93.557564 -48.910071) (xy 93.641399 -48.898018) (xy 93.726 -48.893988) (xy 93.810601 -48.898018)
			(xy 93.894436 -48.910071) (xy 93.976745 -48.930039) (xy 94.056784 -48.957741) (xy 94.133827 -48.992925)
			(xy 94.207177 -49.035274) (xy 94.276169 -49.084403) (xy 94.340179 -49.139868) (xy 94.398627 -49.201166)
			(xy 94.450983 -49.267742) (xy 94.496773 -49.338994) (xy 94.535584 -49.414275) (xy 94.567063 -49.492905)
			(xy 94.590924 -49.574172) (xy 94.606953 -49.657338) (xy 94.615004 -49.741652) (xy 94.615508 -49.784)
			(xy 94.61512 -49.822284) (xy 94.608581 -49.898573) (xy 94.5955 -49.974015) (xy 94.575973 -50.048052)
			(xy 94.563438 -50.084228) (xy 94.560787 -50.092665) (xy 94.560787 -50.110335) (xy 94.563438 -50.118772)
			(xy 94.575963 -50.15495) (xy 94.595471 -50.22899) (xy 94.608551 -50.304431) (xy 94.615106 -50.380717)
			(xy 94.615508 -50.419) (xy 94.615057 -50.459047) (xy 94.607883 -50.538819) (xy 94.593566 -50.617622)
			(xy 94.572222 -50.694819) (xy 94.544024 -50.769785) (xy 94.5092 -50.841912) (xy 94.468032 -50.910615)
			(xy 94.420854 -50.97534) (xy 94.394782 -51.00574) (xy 94.389017 -51.012829) (xy 94.382505 -51.029886)
			(xy 94.382082 -51.039014) (xy 94.382082 -51.068986) (xy 94.382516 -51.078109) (xy 94.389036 -51.095159)
			(xy 94.394782 -51.10226) (xy 94.420842 -51.132671) (xy 94.468021 -51.197394) (xy 94.509191 -51.266096)
			(xy 94.544019 -51.338221) (xy 94.572221 -51.413185) (xy 94.593571 -51.49038) (xy 94.607895 -51.569182)
			(xy 94.615077 -51.648953) (xy 94.615508 -51.689) (xy 94.61512 -51.727284) (xy 94.608581 -51.803573)
			(xy 94.5955 -51.879015) (xy 94.575973 -51.953052) (xy 94.563438 -51.989228) (xy 94.560787 -51.997665)
			(xy 94.560787 -52.015335) (xy 94.563438 -52.023772) (xy 94.575963 -52.05995) (xy 94.595471 -52.13399)
			(xy 94.608551 -52.209431) (xy 94.615106 -52.285717) (xy 94.615508 -52.324) (xy 98.297492 -52.324)
			(xy 98.29788 -52.285716) (xy 98.304419 -52.209427) (xy 98.3175 -52.133985) (xy 98.337027 -52.059948)
			(xy 98.349562 -52.023772) (xy 98.352213 -52.015335) (xy 98.352213 -51.997665) (xy 98.349562 -51.989228)
			(xy 98.337037 -51.95305) (xy 98.317529 -51.87901) (xy 98.304449 -51.803569) (xy 98.297894 -51.727283)
			(xy 98.297492 -51.689) (xy 98.297943 -51.648953) (xy 98.305117 -51.569181) (xy 98.319434 -51.490378)
			(xy 98.340778 -51.413181) (xy 98.368976 -51.338215) (xy 98.4038 -51.266088) (xy 98.444968 -51.197385)
			(xy 98.492146 -51.13266) (xy 98.518218 -51.10226) (xy 98.523983 -51.095171) (xy 98.530495 -51.078114)
			(xy 98.530918 -51.068986) (xy 98.530918 -51.039014) (xy 98.530484 -51.029891) (xy 98.523964 -51.012841)
			(xy 98.518218 -51.00574) (xy 98.492158 -50.975329) (xy 98.444979 -50.910606) (xy 98.403809 -50.841904)
			(xy 98.368981 -50.769779) (xy 98.340779 -50.694815) (xy 98.319429 -50.61762) (xy 98.305105 -50.538818)
			(xy 98.297923 -50.459047) (xy 98.297492 -50.419) (xy 98.29788 -50.380716) (xy 98.304419 -50.304427)
			(xy 98.3175 -50.228985) (xy 98.337027 -50.154948) (xy 98.349562 -50.118772) (xy 98.352213 -50.110335)
			(xy 98.352213 -50.092665) (xy 98.349562 -50.084228) (xy 98.337037 -50.04805) (xy 98.317529 -49.97401)
			(xy 98.304449 -49.898569) (xy 98.297894 -49.822283) (xy 98.297492 -49.784) (xy 98.297996 -49.741652)
			(xy 98.306047 -49.657338) (xy 98.322076 -49.574172) (xy 98.345937 -49.492905) (xy 98.377416 -49.414275)
			(xy 98.416227 -49.338994) (xy 98.462017 -49.267742) (xy 98.514373 -49.201166) (xy 98.572821 -49.139868)
			(xy 98.636831 -49.084403) (xy 98.705823 -49.035274) (xy 98.779173 -48.992925) (xy 98.856216 -48.957741)
			(xy 98.936255 -48.930039) (xy 99.018564 -48.910071) (xy 99.102399 -48.898018) (xy 99.187 -48.893988)
			(xy 99.271601 -48.898018) (xy 99.355436 -48.910071) (xy 99.437745 -48.930039) (xy 99.517784 -48.957741)
			(xy 99.594827 -48.992925) (xy 99.668177 -49.035274) (xy 99.737169 -49.084403) (xy 99.801179 -49.139868)
			(xy 99.859627 -49.201166) (xy 99.911983 -49.267742) (xy 99.957773 -49.338994) (xy 99.996584 -49.414275)
			(xy 100.028063 -49.492905) (xy 100.051924 -49.574172) (xy 100.067953 -49.657338) (xy 100.076004 -49.741652)
			(xy 100.076508 -49.784) (xy 100.07612 -49.822284) (xy 100.069581 -49.898573) (xy 100.0565 -49.974015)
			(xy 100.036973 -50.048052) (xy 100.024438 -50.084228) (xy 100.021787 -50.092665) (xy 100.021787 -50.110335)
			(xy 100.024438 -50.118772) (xy 100.036963 -50.15495) (xy 100.056471 -50.22899) (xy 100.069551 -50.304431)
			(xy 100.076106 -50.380717) (xy 100.076508 -50.419) (xy 100.076057 -50.459047) (xy 100.068883 -50.538819)
			(xy 100.054566 -50.617622) (xy 100.033222 -50.694819) (xy 100.005024 -50.769785) (xy 99.9702 -50.841912)
			(xy 99.929032 -50.910615) (xy 99.881854 -50.97534) (xy 99.855782 -51.00574) (xy 99.850017 -51.012829)
			(xy 99.843505 -51.029886) (xy 99.843082 -51.039014) (xy 99.843082 -51.068986) (xy 99.843516 -51.078109)
			(xy 99.850036 -51.095159) (xy 99.855782 -51.10226) (xy 99.881842 -51.132671) (xy 99.929021 -51.197394)
			(xy 99.970191 -51.266096) (xy 100.005019 -51.338221) (xy 100.033221 -51.413185) (xy 100.054571 -51.49038)
			(xy 100.068895 -51.569182) (xy 100.076077 -51.648953) (xy 100.076508 -51.689) (xy 100.07612 -51.727284)
			(xy 100.069581 -51.803573) (xy 100.0565 -51.879015) (xy 100.036973 -51.953052) (xy 100.024438 -51.989228)
			(xy 100.021787 -51.997665) (xy 100.021787 -52.015335) (xy 100.024438 -52.023772) (xy 100.036963 -52.05995)
			(xy 100.056471 -52.13399) (xy 100.069551 -52.209431) (xy 100.076106 -52.285717) (xy 100.076508 -52.324)
			(xy 103.758492 -52.324) (xy 103.75888 -52.285716) (xy 103.765419 -52.209427) (xy 103.7785 -52.133985)
			(xy 103.798027 -52.059948) (xy 103.810562 -52.023772) (xy 103.813213 -52.015335) (xy 103.813213 -51.997665)
			(xy 103.810562 -51.989228) (xy 103.798037 -51.95305) (xy 103.778529 -51.87901) (xy 103.765449 -51.803569)
			(xy 103.758894 -51.727283) (xy 103.758492 -51.689) (xy 103.758943 -51.648953) (xy 103.766117 -51.569181)
			(xy 103.780434 -51.490378) (xy 103.801778 -51.413181) (xy 103.829976 -51.338215) (xy 103.8648 -51.266088)
			(xy 103.905968 -51.197385) (xy 103.953146 -51.13266) (xy 103.979218 -51.10226) (xy 103.984983 -51.095171)
			(xy 103.991495 -51.078114) (xy 103.991918 -51.068986) (xy 103.991918 -51.039014) (xy 103.991484 -51.029891)
			(xy 103.984964 -51.012841) (xy 103.979218 -51.00574) (xy 103.953158 -50.975329) (xy 103.905979 -50.910606)
			(xy 103.864809 -50.841904) (xy 103.829981 -50.769779) (xy 103.801779 -50.694815) (xy 103.780429 -50.61762)
			(xy 103.766105 -50.538818) (xy 103.758923 -50.459047) (xy 103.758492 -50.419) (xy 103.75888 -50.380716)
			(xy 103.765419 -50.304427) (xy 103.7785 -50.228985) (xy 103.798027 -50.154948) (xy 103.810562 -50.118772)
			(xy 103.813213 -50.110335) (xy 103.813213 -50.092665) (xy 103.810562 -50.084228) (xy 103.798037 -50.04805)
			(xy 103.778529 -49.97401) (xy 103.765449 -49.898569) (xy 103.758894 -49.822283) (xy 103.758492 -49.784)
			(xy 103.758996 -49.741652) (xy 103.767047 -49.657338) (xy 103.783076 -49.574172) (xy 103.806937 -49.492905)
			(xy 103.838416 -49.414275) (xy 103.877227 -49.338994) (xy 103.923017 -49.267742) (xy 103.975373 -49.201166)
			(xy 104.033821 -49.139868) (xy 104.097831 -49.084403) (xy 104.166823 -49.035274) (xy 104.240173 -48.992925)
			(xy 104.317216 -48.957741) (xy 104.397255 -48.930039) (xy 104.479564 -48.910071) (xy 104.563399 -48.898018)
			(xy 104.648 -48.893988) (xy 104.732601 -48.898018) (xy 104.816436 -48.910071) (xy 104.898745 -48.930039)
			(xy 104.978784 -48.957741) (xy 105.055827 -48.992925) (xy 105.129177 -49.035274) (xy 105.198169 -49.084403)
			(xy 105.262179 -49.139868) (xy 105.320627 -49.201166) (xy 105.372983 -49.267742) (xy 105.418773 -49.338994)
			(xy 105.457584 -49.414275) (xy 105.489063 -49.492905) (xy 105.512924 -49.574172) (xy 105.528953 -49.657338)
			(xy 105.537004 -49.741652) (xy 105.537508 -49.784) (xy 105.53712 -49.822284) (xy 105.530581 -49.898573)
			(xy 105.5175 -49.974015) (xy 105.497973 -50.048052) (xy 105.485438 -50.084228) (xy 105.482787 -50.092665)
			(xy 105.482787 -50.110335) (xy 105.485438 -50.118772) (xy 105.497963 -50.15495) (xy 105.517471 -50.22899)
			(xy 105.530551 -50.304431) (xy 105.537106 -50.380717) (xy 105.537508 -50.419) (xy 105.537057 -50.459047)
			(xy 105.529883 -50.538819) (xy 105.515566 -50.617622) (xy 105.494222 -50.694819) (xy 105.466024 -50.769785)
			(xy 105.4312 -50.841912) (xy 105.390032 -50.910615) (xy 105.342854 -50.97534) (xy 105.316782 -51.00574)
			(xy 105.311017 -51.012829) (xy 105.304505 -51.029886) (xy 105.304082 -51.039014) (xy 105.304082 -51.068986)
			(xy 105.304516 -51.078109) (xy 105.311036 -51.095159) (xy 105.316782 -51.10226) (xy 105.342842 -51.132671)
			(xy 105.390021 -51.197394) (xy 105.431191 -51.266096) (xy 105.466019 -51.338221) (xy 105.494221 -51.413185)
			(xy 105.515571 -51.49038) (xy 105.529895 -51.569182) (xy 105.537077 -51.648953) (xy 105.537508 -51.689)
			(xy 105.53712 -51.727284) (xy 105.530581 -51.803573) (xy 105.5175 -51.879015) (xy 105.497973 -51.953052)
			(xy 105.485438 -51.989228) (xy 105.482787 -51.997665) (xy 105.482787 -52.015335) (xy 105.485438 -52.023772)
			(xy 105.497963 -52.05995) (xy 105.517471 -52.13399) (xy 105.528396 -52.197) (xy 149.097492 -52.197)
			(xy 149.09788 -52.158716) (xy 149.104419 -52.082427) (xy 149.1175 -52.006985) (xy 149.137027 -51.932948)
			(xy 149.149562 -51.896772) (xy 149.152213 -51.888335) (xy 149.152213 -51.870665) (xy 149.149562 -51.862228)
			(xy 149.137037 -51.82605) (xy 149.117529 -51.75201) (xy 149.104449 -51.676569) (xy 149.097894 -51.600283)
			(xy 149.097492 -51.562) (xy 149.097943 -51.521953) (xy 149.105117 -51.442181) (xy 149.119434 -51.363378)
			(xy 149.140778 -51.286181) (xy 149.168976 -51.211215) (xy 149.2038 -51.139088) (xy 149.244968 -51.070385)
			(xy 149.292146 -51.00566) (xy 149.318218 -50.97526) (xy 149.323983 -50.968171) (xy 149.330495 -50.951114)
			(xy 149.330918 -50.941986) (xy 149.330918 -50.912014) (xy 149.330484 -50.902891) (xy 149.323964 -50.885841)
			(xy 149.318218 -50.87874) (xy 149.292158 -50.848329) (xy 149.244979 -50.783606) (xy 149.203809 -50.714904)
			(xy 149.168981 -50.642779) (xy 149.140779 -50.567815) (xy 149.119429 -50.49062) (xy 149.105105 -50.411818)
			(xy 149.097923 -50.332047) (xy 149.097492 -50.292) (xy 149.09788 -50.253716) (xy 149.104419 -50.177427)
			(xy 149.1175 -50.101985) (xy 149.137027 -50.027948) (xy 149.149562 -49.991772) (xy 149.152213 -49.983335)
			(xy 149.152213 -49.965665) (xy 149.149562 -49.957228) (xy 149.137037 -49.92105) (xy 149.117529 -49.84701)
			(xy 149.104449 -49.771569) (xy 149.097894 -49.695283) (xy 149.097492 -49.657) (xy 149.097996 -49.614652)
			(xy 149.106047 -49.530338) (xy 149.122076 -49.447172) (xy 149.145937 -49.365905) (xy 149.177416 -49.287275)
			(xy 149.216227 -49.211994) (xy 149.262017 -49.140742) (xy 149.314373 -49.074166) (xy 149.372821 -49.012868)
			(xy 149.436831 -48.957403) (xy 149.505823 -48.908274) (xy 149.579173 -48.865925) (xy 149.656216 -48.830741)
			(xy 149.736255 -48.803039) (xy 149.818564 -48.783071) (xy 149.902399 -48.771018) (xy 149.987 -48.766988)
			(xy 150.071601 -48.771018) (xy 150.155436 -48.783071) (xy 150.237745 -48.803039) (xy 150.317784 -48.830741)
			(xy 150.394827 -48.865925) (xy 150.468177 -48.908274) (xy 150.537169 -48.957403) (xy 150.601179 -49.012868)
			(xy 150.659627 -49.074166) (xy 150.711983 -49.140742) (xy 150.757773 -49.211994) (xy 150.796584 -49.287275)
			(xy 150.828063 -49.365905) (xy 150.851924 -49.447172) (xy 150.867953 -49.530338) (xy 150.876004 -49.614652)
			(xy 150.876508 -49.657) (xy 150.87612 -49.695284) (xy 150.869581 -49.771573) (xy 150.8565 -49.847015)
			(xy 150.836973 -49.921052) (xy 150.824438 -49.957228) (xy 150.821787 -49.965665) (xy 150.821787 -49.983335)
			(xy 150.824438 -49.991772) (xy 150.836963 -50.02795) (xy 150.856471 -50.10199) (xy 150.869551 -50.177431)
			(xy 150.876106 -50.253717) (xy 150.876508 -50.292) (xy 150.876057 -50.332047) (xy 150.868883 -50.411819)
			(xy 150.854566 -50.490622) (xy 150.833222 -50.567819) (xy 150.805024 -50.642785) (xy 150.7702 -50.714912)
			(xy 150.729032 -50.783615) (xy 150.681854 -50.84834) (xy 150.655782 -50.87874) (xy 150.650017 -50.885829)
			(xy 150.643505 -50.902886) (xy 150.643082 -50.912014) (xy 150.643082 -50.941986) (xy 150.643516 -50.951109)
			(xy 150.650036 -50.968159) (xy 150.655782 -50.97526) (xy 150.681842 -51.005671) (xy 150.729021 -51.070394)
			(xy 150.770191 -51.139096) (xy 150.805019 -51.211221) (xy 150.833221 -51.286185) (xy 150.854571 -51.36338)
			(xy 150.868895 -51.442182) (xy 150.876077 -51.521953) (xy 150.876508 -51.562) (xy 150.87612 -51.600284)
			(xy 150.869581 -51.676573) (xy 150.8565 -51.752015) (xy 150.836973 -51.826052) (xy 150.824438 -51.862228)
			(xy 150.821787 -51.870665) (xy 150.821787 -51.888335) (xy 150.824438 -51.896772) (xy 150.836963 -51.93295)
			(xy 150.856471 -52.00699) (xy 150.869551 -52.082431) (xy 150.876106 -52.158717) (xy 150.876508 -52.197)
			(xy 154.558492 -52.197) (xy 154.55888 -52.158716) (xy 154.565419 -52.082427) (xy 154.5785 -52.006985)
			(xy 154.598027 -51.932948) (xy 154.610562 -51.896772) (xy 154.613213 -51.888335) (xy 154.613213 -51.870665)
			(xy 154.610562 -51.862228) (xy 154.598037 -51.82605) (xy 154.578529 -51.75201) (xy 154.565449 -51.676569)
			(xy 154.558894 -51.600283) (xy 154.558492 -51.562) (xy 154.558943 -51.521953) (xy 154.566117 -51.442181)
			(xy 154.580434 -51.363378) (xy 154.601778 -51.286181) (xy 154.629976 -51.211215) (xy 154.6648 -51.139088)
			(xy 154.705968 -51.070385) (xy 154.753146 -51.00566) (xy 154.779218 -50.97526) (xy 154.784983 -50.968171)
			(xy 154.791495 -50.951114) (xy 154.791918 -50.941986) (xy 154.791918 -50.912014) (xy 154.791484 -50.902891)
			(xy 154.784964 -50.885841) (xy 154.779218 -50.87874) (xy 154.753158 -50.848329) (xy 154.705979 -50.783606)
			(xy 154.664809 -50.714904) (xy 154.629981 -50.642779) (xy 154.601779 -50.567815) (xy 154.580429 -50.49062)
			(xy 154.566105 -50.411818) (xy 154.558923 -50.332047) (xy 154.558492 -50.292) (xy 154.55888 -50.253716)
			(xy 154.565419 -50.177427) (xy 154.5785 -50.101985) (xy 154.598027 -50.027948) (xy 154.610562 -49.991772)
			(xy 154.613213 -49.983335) (xy 154.613213 -49.965665) (xy 154.610562 -49.957228) (xy 154.598037 -49.92105)
			(xy 154.578529 -49.84701) (xy 154.565449 -49.771569) (xy 154.558894 -49.695283) (xy 154.558492 -49.657)
			(xy 154.558996 -49.614652) (xy 154.567047 -49.530338) (xy 154.583076 -49.447172) (xy 154.606937 -49.365905)
			(xy 154.638416 -49.287275) (xy 154.677227 -49.211994) (xy 154.723017 -49.140742) (xy 154.775373 -49.074166)
			(xy 154.833821 -49.012868) (xy 154.897831 -48.957403) (xy 154.966823 -48.908274) (xy 155.040173 -48.865925)
			(xy 155.117216 -48.830741) (xy 155.197255 -48.803039) (xy 155.279564 -48.783071) (xy 155.363399 -48.771018)
			(xy 155.448 -48.766988) (xy 155.532601 -48.771018) (xy 155.616436 -48.783071) (xy 155.698745 -48.803039)
			(xy 155.778784 -48.830741) (xy 155.855827 -48.865925) (xy 155.929177 -48.908274) (xy 155.998169 -48.957403)
			(xy 156.062179 -49.012868) (xy 156.120627 -49.074166) (xy 156.172983 -49.140742) (xy 156.218773 -49.211994)
			(xy 156.257584 -49.287275) (xy 156.289063 -49.365905) (xy 156.312924 -49.447172) (xy 156.328953 -49.530338)
			(xy 156.337004 -49.614652) (xy 156.337508 -49.657) (xy 156.33712 -49.695284) (xy 156.330581 -49.771573)
			(xy 156.3175 -49.847015) (xy 156.297973 -49.921052) (xy 156.285438 -49.957228) (xy 156.282787 -49.965665)
			(xy 156.282787 -49.983335) (xy 156.285438 -49.991772) (xy 156.297963 -50.02795) (xy 156.317471 -50.10199)
			(xy 156.330551 -50.177431) (xy 156.337106 -50.253717) (xy 156.337508 -50.292) (xy 156.337057 -50.332047)
			(xy 156.329883 -50.411819) (xy 156.315566 -50.490622) (xy 156.294222 -50.567819) (xy 156.266024 -50.642785)
			(xy 156.2312 -50.714912) (xy 156.190032 -50.783615) (xy 156.142854 -50.84834) (xy 156.116782 -50.87874)
			(xy 156.111017 -50.885829) (xy 156.104505 -50.902886) (xy 156.104082 -50.912014) (xy 156.104082 -50.941986)
			(xy 156.104516 -50.951109) (xy 156.111036 -50.968159) (xy 156.116782 -50.97526) (xy 156.142842 -51.005671)
			(xy 156.190021 -51.070394) (xy 156.231191 -51.139096) (xy 156.266019 -51.211221) (xy 156.294221 -51.286185)
			(xy 156.315571 -51.36338) (xy 156.329895 -51.442182) (xy 156.337077 -51.521953) (xy 156.337508 -51.562)
			(xy 156.33712 -51.600284) (xy 156.330581 -51.676573) (xy 156.3175 -51.752015) (xy 156.297973 -51.826052)
			(xy 156.285438 -51.862228) (xy 156.282787 -51.870665) (xy 156.282787 -51.888335) (xy 156.285438 -51.896772)
			(xy 156.297963 -51.93295) (xy 156.317471 -52.00699) (xy 156.330551 -52.082431) (xy 156.337106 -52.158717)
			(xy 156.337508 -52.197) (xy 160.019492 -52.197) (xy 160.01988 -52.158716) (xy 160.026419 -52.082427)
			(xy 160.0395 -52.006985) (xy 160.059027 -51.932948) (xy 160.071562 -51.896772) (xy 160.074213 -51.888335)
			(xy 160.074213 -51.870665) (xy 160.071562 -51.862228) (xy 160.059037 -51.82605) (xy 160.039529 -51.75201)
			(xy 160.026449 -51.676569) (xy 160.019894 -51.600283) (xy 160.019492 -51.562) (xy 160.019943 -51.521953)
			(xy 160.027117 -51.442181) (xy 160.041434 -51.363378) (xy 160.062778 -51.286181) (xy 160.090976 -51.211215)
			(xy 160.1258 -51.139088) (xy 160.166968 -51.070385) (xy 160.214146 -51.00566) (xy 160.240218 -50.97526)
			(xy 160.245983 -50.968171) (xy 160.252495 -50.951114) (xy 160.252918 -50.941986) (xy 160.252918 -50.912014)
			(xy 160.252484 -50.902891) (xy 160.245964 -50.885841) (xy 160.240218 -50.87874) (xy 160.214158 -50.848329)
			(xy 160.166979 -50.783606) (xy 160.125809 -50.714904) (xy 160.090981 -50.642779) (xy 160.062779 -50.567815)
			(xy 160.041429 -50.49062) (xy 160.027105 -50.411818) (xy 160.019923 -50.332047) (xy 160.019492 -50.292)
			(xy 160.01988 -50.253716) (xy 160.026419 -50.177427) (xy 160.0395 -50.101985) (xy 160.059027 -50.027948)
			(xy 160.071562 -49.991772) (xy 160.074213 -49.983335) (xy 160.074213 -49.965665) (xy 160.071562 -49.957228)
			(xy 160.059037 -49.92105) (xy 160.039529 -49.84701) (xy 160.026449 -49.771569) (xy 160.019894 -49.695283)
			(xy 160.019492 -49.657) (xy 160.019996 -49.614652) (xy 160.028047 -49.530338) (xy 160.044076 -49.447172)
			(xy 160.067937 -49.365905) (xy 160.099416 -49.287275) (xy 160.138227 -49.211994) (xy 160.184017 -49.140742)
			(xy 160.236373 -49.074166) (xy 160.294821 -49.012868) (xy 160.358831 -48.957403) (xy 160.427823 -48.908274)
			(xy 160.501173 -48.865925) (xy 160.578216 -48.830741) (xy 160.658255 -48.803039) (xy 160.740564 -48.783071)
			(xy 160.824399 -48.771018) (xy 160.909 -48.766988) (xy 160.993601 -48.771018) (xy 161.077436 -48.783071)
			(xy 161.159745 -48.803039) (xy 161.239784 -48.830741) (xy 161.316827 -48.865925) (xy 161.390177 -48.908274)
			(xy 161.459169 -48.957403) (xy 161.523179 -49.012868) (xy 161.581627 -49.074166) (xy 161.633983 -49.140742)
			(xy 161.679773 -49.211994) (xy 161.718584 -49.287275) (xy 161.750063 -49.365905) (xy 161.773924 -49.447172)
			(xy 161.789953 -49.530338) (xy 161.798004 -49.614652) (xy 161.798508 -49.657) (xy 161.79812 -49.695284)
			(xy 161.791581 -49.771573) (xy 161.7785 -49.847015) (xy 161.758973 -49.921052) (xy 161.746438 -49.957228)
			(xy 161.743787 -49.965665) (xy 161.743787 -49.983335) (xy 161.746438 -49.991772) (xy 161.758963 -50.02795)
			(xy 161.778471 -50.10199) (xy 161.791551 -50.177431) (xy 161.798106 -50.253717) (xy 161.798508 -50.292)
			(xy 161.798057 -50.332047) (xy 161.790883 -50.411819) (xy 161.776566 -50.490622) (xy 161.755222 -50.567819)
			(xy 161.727024 -50.642785) (xy 161.6922 -50.714912) (xy 161.651032 -50.783615) (xy 161.603854 -50.84834)
			(xy 161.577782 -50.87874) (xy 161.572017 -50.885829) (xy 161.565505 -50.902886) (xy 161.565082 -50.912014)
			(xy 161.565082 -50.941986) (xy 161.565516 -50.951109) (xy 161.572036 -50.968159) (xy 161.577782 -50.97526)
			(xy 161.603842 -51.005671) (xy 161.651021 -51.070394) (xy 161.692191 -51.139096) (xy 161.727019 -51.211221)
			(xy 161.755221 -51.286185) (xy 161.776571 -51.36338) (xy 161.790895 -51.442182) (xy 161.798077 -51.521953)
			(xy 161.798508 -51.562) (xy 161.79812 -51.600284) (xy 161.791581 -51.676573) (xy 161.7785 -51.752015)
			(xy 161.758973 -51.826052) (xy 161.746438 -51.862228) (xy 161.743787 -51.870665) (xy 161.743787 -51.888335)
			(xy 161.746438 -51.896772) (xy 161.758963 -51.93295) (xy 161.778471 -52.00699) (xy 161.791551 -52.082431)
			(xy 161.798106 -52.158717) (xy 161.798508 -52.197) (xy 165.480492 -52.197) (xy 165.48088 -52.158716)
			(xy 165.487419 -52.082427) (xy 165.5005 -52.006985) (xy 165.520027 -51.932948) (xy 165.532562 -51.896772)
			(xy 165.535213 -51.888335) (xy 165.535213 -51.870665) (xy 165.532562 -51.862228) (xy 165.520037 -51.82605)
			(xy 165.500529 -51.75201) (xy 165.487449 -51.676569) (xy 165.480894 -51.600283) (xy 165.480492 -51.562)
			(xy 165.480943 -51.521953) (xy 165.488117 -51.442181) (xy 165.502434 -51.363378) (xy 165.523778 -51.286181)
			(xy 165.551976 -51.211215) (xy 165.5868 -51.139088) (xy 165.627968 -51.070385) (xy 165.675146 -51.00566)
			(xy 165.701218 -50.97526) (xy 165.706983 -50.968171) (xy 165.713495 -50.951114) (xy 165.713918 -50.941986)
			(xy 165.713918 -50.912014) (xy 165.713484 -50.902891) (xy 165.706964 -50.885841) (xy 165.701218 -50.87874)
			(xy 165.675158 -50.848329) (xy 165.627979 -50.783606) (xy 165.586809 -50.714904) (xy 165.551981 -50.642779)
			(xy 165.523779 -50.567815) (xy 165.502429 -50.49062) (xy 165.488105 -50.411818) (xy 165.480923 -50.332047)
			(xy 165.480492 -50.292) (xy 165.48088 -50.253716) (xy 165.487419 -50.177427) (xy 165.5005 -50.101985)
			(xy 165.520027 -50.027948) (xy 165.532562 -49.991772) (xy 165.535213 -49.983335) (xy 165.535213 -49.965665)
			(xy 165.532562 -49.957228) (xy 165.520037 -49.92105) (xy 165.500529 -49.84701) (xy 165.487449 -49.771569)
			(xy 165.480894 -49.695283) (xy 165.480492 -49.657) (xy 165.480996 -49.614652) (xy 165.489047 -49.530338)
			(xy 165.505076 -49.447172) (xy 165.528937 -49.365905) (xy 165.560416 -49.287275) (xy 165.599227 -49.211994)
			(xy 165.645017 -49.140742) (xy 165.697373 -49.074166) (xy 165.755821 -49.012868) (xy 165.819831 -48.957403)
			(xy 165.888823 -48.908274) (xy 165.962173 -48.865925) (xy 166.039216 -48.830741) (xy 166.119255 -48.803039)
			(xy 166.201564 -48.783071) (xy 166.285399 -48.771018) (xy 166.37 -48.766988) (xy 166.454601 -48.771018)
			(xy 166.538436 -48.783071) (xy 166.620745 -48.803039) (xy 166.700784 -48.830741) (xy 166.777827 -48.865925)
			(xy 166.851177 -48.908274) (xy 166.920169 -48.957403) (xy 166.984179 -49.012868) (xy 167.042627 -49.074166)
			(xy 167.094983 -49.140742) (xy 167.140773 -49.211994) (xy 167.179584 -49.287275) (xy 167.211063 -49.365905)
			(xy 167.234924 -49.447172) (xy 167.250953 -49.530338) (xy 167.259004 -49.614652) (xy 167.259508 -49.657)
			(xy 167.25912 -49.695284) (xy 167.252581 -49.771573) (xy 167.2395 -49.847015) (xy 167.219973 -49.921052)
			(xy 167.207438 -49.957228) (xy 167.204787 -49.965665) (xy 167.204787 -49.983335) (xy 167.207438 -49.991772)
			(xy 167.219963 -50.02795) (xy 167.239471 -50.10199) (xy 167.252551 -50.177431) (xy 167.259106 -50.253717)
			(xy 167.259508 -50.292) (xy 167.259057 -50.332047) (xy 167.251883 -50.411819) (xy 167.237566 -50.490622)
			(xy 167.216222 -50.567819) (xy 167.188024 -50.642785) (xy 167.1532 -50.714912) (xy 167.112032 -50.783615)
			(xy 167.064854 -50.84834) (xy 167.038782 -50.87874) (xy 167.033017 -50.885829) (xy 167.026505 -50.902886)
			(xy 167.026082 -50.912014) (xy 167.026082 -50.941986) (xy 167.026516 -50.951109) (xy 167.033036 -50.968159)
			(xy 167.038782 -50.97526) (xy 167.064842 -51.005671) (xy 167.112021 -51.070394) (xy 167.153191 -51.139096)
			(xy 167.188019 -51.211221) (xy 167.216221 -51.286185) (xy 167.237571 -51.36338) (xy 167.251895 -51.442182)
			(xy 167.259077 -51.521953) (xy 167.259508 -51.562) (xy 167.25912 -51.600284) (xy 167.252581 -51.676573)
			(xy 167.2395 -51.752015) (xy 167.219973 -51.826052) (xy 167.207438 -51.862228) (xy 167.204787 -51.870665)
			(xy 167.204787 -51.888335) (xy 167.207438 -51.896772) (xy 167.219963 -51.93295) (xy 167.239471 -52.00699)
			(xy 167.252551 -52.082431) (xy 167.259106 -52.158717) (xy 167.259508 -52.197) (xy 170.941492 -52.197)
			(xy 170.94188 -52.158716) (xy 170.948419 -52.082427) (xy 170.9615 -52.006985) (xy 170.981027 -51.932948)
			(xy 170.993562 -51.896772) (xy 170.996213 -51.888335) (xy 170.996213 -51.870665) (xy 170.993562 -51.862228)
			(xy 170.981037 -51.82605) (xy 170.961529 -51.75201) (xy 170.948449 -51.676569) (xy 170.941894 -51.600283)
			(xy 170.941492 -51.562) (xy 170.941943 -51.521953) (xy 170.949117 -51.442181) (xy 170.963434 -51.363378)
			(xy 170.984778 -51.286181) (xy 171.012976 -51.211215) (xy 171.0478 -51.139088) (xy 171.088968 -51.070385)
			(xy 171.136146 -51.00566) (xy 171.162218 -50.97526) (xy 171.167983 -50.968171) (xy 171.174495 -50.951114)
			(xy 171.174918 -50.941986) (xy 171.174918 -50.912014) (xy 171.174484 -50.902891) (xy 171.167964 -50.885841)
			(xy 171.162218 -50.87874) (xy 171.136158 -50.848329) (xy 171.088979 -50.783606) (xy 171.047809 -50.714904)
			(xy 171.012981 -50.642779) (xy 170.984779 -50.567815) (xy 170.963429 -50.49062) (xy 170.949105 -50.411818)
			(xy 170.941923 -50.332047) (xy 170.941492 -50.292) (xy 170.94188 -50.253716) (xy 170.948419 -50.177427)
			(xy 170.9615 -50.101985) (xy 170.981027 -50.027948) (xy 170.993562 -49.991772) (xy 170.996213 -49.983335)
			(xy 170.996213 -49.965665) (xy 170.993562 -49.957228) (xy 170.981037 -49.92105) (xy 170.961529 -49.84701)
			(xy 170.948449 -49.771569) (xy 170.941894 -49.695283) (xy 170.941492 -49.657) (xy 170.941996 -49.614652)
			(xy 170.950047 -49.530338) (xy 170.966076 -49.447172) (xy 170.989937 -49.365905) (xy 171.021416 -49.287275)
			(xy 171.060227 -49.211994) (xy 171.106017 -49.140742) (xy 171.158373 -49.074166) (xy 171.216821 -49.012868)
			(xy 171.280831 -48.957403) (xy 171.349823 -48.908274) (xy 171.423173 -48.865925) (xy 171.500216 -48.830741)
			(xy 171.580255 -48.803039) (xy 171.662564 -48.783071) (xy 171.746399 -48.771018) (xy 171.831 -48.766988)
			(xy 171.915601 -48.771018) (xy 171.999436 -48.783071) (xy 172.081745 -48.803039) (xy 172.161784 -48.830741)
			(xy 172.238827 -48.865925) (xy 172.312177 -48.908274) (xy 172.381169 -48.957403) (xy 172.445179 -49.012868)
			(xy 172.503627 -49.074166) (xy 172.555983 -49.140742) (xy 172.601773 -49.211994) (xy 172.640584 -49.287275)
			(xy 172.672063 -49.365905) (xy 172.695924 -49.447172) (xy 172.711953 -49.530338) (xy 172.720004 -49.614652)
			(xy 172.720508 -49.657) (xy 172.72012 -49.695284) (xy 172.713581 -49.771573) (xy 172.7005 -49.847015)
			(xy 172.680973 -49.921052) (xy 172.668438 -49.957228) (xy 172.665787 -49.965665) (xy 172.665787 -49.983335)
			(xy 172.668438 -49.991772) (xy 172.680963 -50.02795) (xy 172.700471 -50.10199) (xy 172.713551 -50.177431)
			(xy 172.720106 -50.253717) (xy 172.720508 -50.292) (xy 172.720057 -50.332047) (xy 172.712883 -50.411819)
			(xy 172.698566 -50.490622) (xy 172.677222 -50.567819) (xy 172.649024 -50.642785) (xy 172.6142 -50.714912)
			(xy 172.573032 -50.783615) (xy 172.525854 -50.84834) (xy 172.499782 -50.87874) (xy 172.494017 -50.885829)
			(xy 172.487505 -50.902886) (xy 172.487082 -50.912014) (xy 172.487082 -50.941986) (xy 172.487516 -50.951109)
			(xy 172.494036 -50.968159) (xy 172.499782 -50.97526) (xy 172.525842 -51.005671) (xy 172.573021 -51.070394)
			(xy 172.614191 -51.139096) (xy 172.649019 -51.211221) (xy 172.677221 -51.286185) (xy 172.698571 -51.36338)
			(xy 172.712895 -51.442182) (xy 172.720077 -51.521953) (xy 172.720508 -51.562) (xy 172.72012 -51.600284)
			(xy 172.713581 -51.676573) (xy 172.7005 -51.752015) (xy 172.680973 -51.826052) (xy 172.668438 -51.862228)
			(xy 172.665787 -51.870665) (xy 172.665787 -51.888335) (xy 172.668438 -51.896772) (xy 172.680963 -51.93295)
			(xy 172.700471 -52.00699) (xy 172.713551 -52.082431) (xy 172.720106 -52.158717) (xy 172.720508 -52.197)
			(xy 176.399952 -52.197) (xy 176.400342 -52.158716) (xy 176.406881 -52.082427) (xy 176.419962 -52.006985)
			(xy 176.439487 -51.932948) (xy 176.452022 -51.896772) (xy 176.454674 -51.888335) (xy 176.454674 -51.870665)
			(xy 176.452022 -51.862228) (xy 176.439495 -51.82605) (xy 176.419988 -51.75201) (xy 176.406909 -51.676569)
			(xy 176.400354 -51.600283) (xy 176.399952 -51.562) (xy 176.400388 -51.521953) (xy 176.407563 -51.44218)
			(xy 176.421881 -51.363376) (xy 176.443226 -51.286178) (xy 176.471427 -51.211212) (xy 176.506253 -51.139086)
			(xy 176.547423 -51.070383) (xy 176.594604 -51.00566) (xy 176.620678 -50.97526) (xy 176.626439 -50.968167)
			(xy 176.632954 -50.951113) (xy 176.633378 -50.941986) (xy 176.633378 -50.912014) (xy 176.632931 -50.902892)
			(xy 176.626419 -50.885843) (xy 176.620678 -50.87874) (xy 176.594628 -50.84832) (xy 176.547447 -50.7836)
			(xy 176.506274 -50.714899) (xy 176.471445 -50.642776) (xy 176.443241 -50.567813) (xy 176.42189 -50.490618)
			(xy 176.407565 -50.411817) (xy 176.400383 -50.332047) (xy 176.399952 -50.292) (xy 176.400342 -50.253716)
			(xy 176.406881 -50.177427) (xy 176.419962 -50.101985) (xy 176.439487 -50.027948) (xy 176.452022 -49.991772)
			(xy 176.454674 -49.983335) (xy 176.454674 -49.965665) (xy 176.452022 -49.957228) (xy 176.439495 -49.92105)
			(xy 176.419988 -49.84701) (xy 176.406909 -49.771569) (xy 176.400354 -49.695283) (xy 176.399952 -49.657)
			(xy 176.400456 -49.614652) (xy 176.408507 -49.530338) (xy 176.424536 -49.447172) (xy 176.448397 -49.365905)
			(xy 176.479876 -49.287275) (xy 176.518687 -49.211994) (xy 176.564477 -49.140742) (xy 176.616833 -49.074166)
			(xy 176.675281 -49.012868) (xy 176.739291 -48.957403) (xy 176.808283 -48.908274) (xy 176.881633 -48.865925)
			(xy 176.958676 -48.830741) (xy 177.038715 -48.803039) (xy 177.121024 -48.783071) (xy 177.204859 -48.771018)
			(xy 177.28946 -48.766988) (xy 177.374061 -48.771018) (xy 177.457896 -48.783071) (xy 177.540205 -48.803039)
			(xy 177.620244 -48.830741) (xy 177.697287 -48.865925) (xy 177.770637 -48.908274) (xy 177.839629 -48.957403)
			(xy 177.903639 -49.012868) (xy 177.962087 -49.074166) (xy 178.014443 -49.140742) (xy 178.060233 -49.211994)
			(xy 178.099044 -49.287275) (xy 178.130523 -49.365905) (xy 178.154384 -49.447172) (xy 178.170413 -49.530338)
			(xy 178.178464 -49.614652) (xy 178.178968 -49.657) (xy 178.178577 -49.695284) (xy 178.172038 -49.771573)
			(xy 178.158958 -49.847015) (xy 178.139432 -49.921052) (xy 178.126898 -49.957228) (xy 178.124245 -49.965664)
			(xy 178.124245 -49.983336) (xy 178.126898 -49.991772) (xy 178.139422 -50.027951) (xy 178.15893 -50.10199)
			(xy 178.172011 -50.177431) (xy 178.178566 -50.253717) (xy 178.178968 -50.292) (xy 178.178527 -50.332047)
			(xy 178.171353 -50.411819) (xy 178.157035 -50.490623) (xy 178.13569 -50.567821) (xy 178.10749 -50.642787)
			(xy 178.072665 -50.714913) (xy 178.031495 -50.783617) (xy 177.984315 -50.84834) (xy 177.958242 -50.87874)
			(xy 177.952472 -50.885825) (xy 177.945964 -50.902886) (xy 177.945542 -50.912014) (xy 177.945542 -50.941986)
			(xy 177.945985 -50.951108) (xy 177.9525 -50.968158) (xy 177.958242 -50.97526) (xy 177.984295 -51.005677)
			(xy 178.031476 -51.070398) (xy 178.072647 -51.139099) (xy 178.107476 -51.211223) (xy 178.13568 -51.286186)
			(xy 178.15703 -51.363381) (xy 178.171355 -51.442183) (xy 178.178537 -51.521953) (xy 178.178968 -51.562)
			(xy 178.178577 -51.600284) (xy 178.172038 -51.676573) (xy 178.158958 -51.752015) (xy 178.139432 -51.826052)
			(xy 178.126898 -51.862228) (xy 178.124245 -51.870664) (xy 178.124245 -51.888336) (xy 178.126898 -51.896772)
			(xy 178.139422 -51.932951) (xy 178.15893 -52.00699) (xy 178.172011 -52.082431) (xy 178.178566 -52.158717)
			(xy 178.178968 -52.197) (xy 181.860952 -52.197) (xy 181.861342 -52.158716) (xy 181.867881 -52.082427)
			(xy 181.880962 -52.006985) (xy 181.900487 -51.932948) (xy 181.913022 -51.896772) (xy 181.915674 -51.888335)
			(xy 181.915674 -51.870665) (xy 181.913022 -51.862228) (xy 181.900495 -51.82605) (xy 181.880988 -51.75201)
			(xy 181.867909 -51.676569) (xy 181.861354 -51.600283) (xy 181.860952 -51.562) (xy 181.861388 -51.521953)
			(xy 181.868563 -51.44218) (xy 181.882881 -51.363376) (xy 181.904226 -51.286178) (xy 181.932427 -51.211212)
			(xy 181.967253 -51.139086) (xy 182.008423 -51.070383) (xy 182.055604 -51.00566) (xy 182.081678 -50.97526)
			(xy 182.087439 -50.968167) (xy 182.093954 -50.951113) (xy 182.094378 -50.941986) (xy 182.094378 -50.912014)
			(xy 182.093931 -50.902892) (xy 182.087419 -50.885843) (xy 182.081678 -50.87874) (xy 182.055628 -50.84832)
			(xy 182.008447 -50.7836) (xy 181.967274 -50.714899) (xy 181.932445 -50.642776) (xy 181.904241 -50.567813)
			(xy 181.88289 -50.490618) (xy 181.868565 -50.411817) (xy 181.861383 -50.332047) (xy 181.860952 -50.292)
			(xy 181.861342 -50.253716) (xy 181.867881 -50.177427) (xy 181.880962 -50.101985) (xy 181.900487 -50.027948)
			(xy 181.913022 -49.991772) (xy 181.915674 -49.983335) (xy 181.915674 -49.965665) (xy 181.913022 -49.957228)
			(xy 181.900495 -49.92105) (xy 181.880988 -49.84701) (xy 181.867909 -49.771569) (xy 181.861354 -49.695283)
			(xy 181.860952 -49.657) (xy 181.861456 -49.614652) (xy 181.869507 -49.530338) (xy 181.885536 -49.447172)
			(xy 181.909397 -49.365905) (xy 181.940876 -49.287275) (xy 181.979687 -49.211994) (xy 182.025477 -49.140742)
			(xy 182.077833 -49.074166) (xy 182.136281 -49.012868) (xy 182.200291 -48.957403) (xy 182.269283 -48.908274)
			(xy 182.342633 -48.865925) (xy 182.419676 -48.830741) (xy 182.499715 -48.803039) (xy 182.582024 -48.783071)
			(xy 182.665859 -48.771018) (xy 182.75046 -48.766988) (xy 182.835061 -48.771018) (xy 182.918896 -48.783071)
			(xy 183.001205 -48.803039) (xy 183.081244 -48.830741) (xy 183.158287 -48.865925) (xy 183.231637 -48.908274)
			(xy 183.300629 -48.957403) (xy 183.364639 -49.012868) (xy 183.423087 -49.074166) (xy 183.475443 -49.140742)
			(xy 183.521233 -49.211994) (xy 183.560044 -49.287275) (xy 183.591523 -49.365905) (xy 183.615384 -49.447172)
			(xy 183.631413 -49.530338) (xy 183.639464 -49.614652) (xy 183.639968 -49.657) (xy 183.639577 -49.695284)
			(xy 183.633038 -49.771573) (xy 183.619958 -49.847015) (xy 183.600432 -49.921052) (xy 183.587898 -49.957228)
			(xy 183.585245 -49.965664) (xy 183.585245 -49.983336) (xy 183.587898 -49.991772) (xy 183.600422 -50.027951)
			(xy 183.61993 -50.10199) (xy 183.633011 -50.177431) (xy 183.639566 -50.253717) (xy 183.639791 -50.275179)
			(xy 257.330698 -50.275179) (xy 257.330698 -50.190457) (xy 257.338751 -50.10612) (xy 257.354785 -50.02293)
			(xy 257.378653 -49.94164) (xy 257.410141 -49.862988) (xy 257.448963 -49.787685) (xy 257.494766 -49.716413)
			(xy 257.547137 -49.649817) (xy 257.605602 -49.588502) (xy 257.66963 -49.533021) (xy 257.738642 -49.483878)
			(xy 257.812012 -49.441518) (xy 257.889077 -49.406323) (xy 257.969139 -49.378614) (xy 258.051472 -49.35864)
			(xy 258.135331 -49.346583) (xy 258.219956 -49.342552) (xy 258.304581 -49.346583) (xy 258.38844 -49.35864)
			(xy 258.470773 -49.378614) (xy 258.550835 -49.406323) (xy 258.6279 -49.441518) (xy 258.70127 -49.483878)
			(xy 258.770282 -49.533021) (xy 258.83431 -49.588502) (xy 258.892775 -49.649817) (xy 258.945146 -49.716413)
			(xy 258.990949 -49.787685) (xy 259.029771 -49.862988) (xy 259.061259 -49.94164) (xy 259.085127 -50.02293)
			(xy 259.101161 -50.10612) (xy 259.109214 -50.190457) (xy 259.109718 -50.232818) (xy 259.109214 -50.275179)
			(xy 259.101161 -50.359516) (xy 259.085127 -50.442706) (xy 259.061259 -50.523996) (xy 259.029771 -50.602648)
			(xy 258.990949 -50.677951) (xy 258.945146 -50.749223) (xy 258.892775 -50.815819) (xy 258.83431 -50.877134)
			(xy 258.770282 -50.932615) (xy 258.70127 -50.981758) (xy 258.6279 -51.024118) (xy 258.562469 -51.054)
			(xy 275.335492 -51.054) (xy 275.336075 -51.007604) (xy 275.34572 -50.915316) (xy 275.364916 -50.824532)
			(xy 275.393454 -50.736239) (xy 275.411692 -50.693574) (xy 275.415498 -50.683632) (xy 275.415498 -50.662368)
			(xy 275.411692 -50.652426) (xy 275.393447 -50.609764) (xy 275.364903 -50.521471) (xy 275.34571 -50.430686)
			(xy 275.336077 -50.338396) (xy 275.335492 -50.292) (xy 275.335996 -50.249652) (xy 275.344047 -50.165338)
			(xy 275.360076 -50.082172) (xy 275.383937 -50.000905) (xy 275.415416 -49.922275) (xy 275.454227 -49.846994)
			(xy 275.500017 -49.775742) (xy 275.552373 -49.709166) (xy 275.610821 -49.647868) (xy 275.674831 -49.592403)
			(xy 275.743823 -49.543274) (xy 275.817173 -49.500925) (xy 275.894216 -49.465741) (xy 275.974255 -49.438039)
			(xy 276.056564 -49.418071) (xy 276.140399 -49.406018) (xy 276.225 -49.401988) (xy 276.309601 -49.406018)
			(xy 276.393436 -49.418071) (xy 276.475745 -49.438039) (xy 276.555784 -49.465741) (xy 276.632827 -49.500925)
			(xy 276.706177 -49.543274) (xy 276.775169 -49.592403) (xy 276.839179 -49.647868) (xy 276.897627 -49.709166)
			(xy 276.949983 -49.775742) (xy 276.995773 -49.846994) (xy 277.034584 -49.922275) (xy 277.066063 -50.000905)
			(xy 277.089924 -50.082172) (xy 277.105953 -50.165338) (xy 277.114004 -50.249652) (xy 277.114508 -50.292)
			(xy 277.113925 -50.338396) (xy 277.10428 -50.430684) (xy 277.085084 -50.521468) (xy 277.056546 -50.609761)
			(xy 277.038308 -50.652426) (xy 277.034502 -50.662368) (xy 277.034502 -50.683632) (xy 277.038308 -50.693574)
			(xy 277.056553 -50.736236) (xy 277.085097 -50.824529) (xy 277.10429 -50.915314) (xy 277.113923 -51.007604)
			(xy 277.114508 -51.054) (xy 277.114004 -51.096348) (xy 277.105953 -51.180662) (xy 277.089924 -51.263828)
			(xy 277.066063 -51.345095) (xy 277.034584 -51.423725) (xy 276.995773 -51.499006) (xy 276.949983 -51.570258)
			(xy 276.897627 -51.636834) (xy 276.839179 -51.698132) (xy 276.775169 -51.753597) (xy 276.706177 -51.802726)
			(xy 276.632827 -51.845075) (xy 276.555784 -51.880259) (xy 276.475745 -51.907961) (xy 276.393436 -51.927929)
			(xy 276.309601 -51.939982) (xy 276.225 -51.944013) (xy 276.140399 -51.939982) (xy 276.056564 -51.927929)
			(xy 275.974255 -51.907961) (xy 275.894216 -51.880259) (xy 275.817173 -51.845075) (xy 275.743823 -51.802726)
			(xy 275.674831 -51.753597) (xy 275.610821 -51.698132) (xy 275.552373 -51.636834) (xy 275.500017 -51.570258)
			(xy 275.454227 -51.499006) (xy 275.415416 -51.423725) (xy 275.383937 -51.345095) (xy 275.360076 -51.263828)
			(xy 275.344047 -51.180662) (xy 275.335996 -51.096348) (xy 275.335492 -51.054) (xy 258.562469 -51.054)
			(xy 258.550835 -51.059313) (xy 258.470773 -51.087022) (xy 258.38844 -51.106996) (xy 258.304581 -51.119053)
			(xy 258.219956 -51.123085) (xy 258.135331 -51.119053) (xy 258.051472 -51.106996) (xy 257.969139 -51.087022)
			(xy 257.889077 -51.059313) (xy 257.812012 -51.024118) (xy 257.738642 -50.981758) (xy 257.66963 -50.932615)
			(xy 257.605602 -50.877134) (xy 257.547137 -50.815819) (xy 257.494766 -50.749223) (xy 257.448963 -50.677951)
			(xy 257.410141 -50.602648) (xy 257.378653 -50.523996) (xy 257.354785 -50.442706) (xy 257.338751 -50.359516)
			(xy 257.330698 -50.275179) (xy 183.639791 -50.275179) (xy 183.639968 -50.292) (xy 183.639527 -50.332047)
			(xy 183.632353 -50.411819) (xy 183.618035 -50.490623) (xy 183.59669 -50.567821) (xy 183.56849 -50.642787)
			(xy 183.533665 -50.714913) (xy 183.492495 -50.783617) (xy 183.445315 -50.84834) (xy 183.419242 -50.87874)
			(xy 183.413472 -50.885825) (xy 183.406964 -50.902886) (xy 183.406542 -50.912014) (xy 183.406542 -50.941986)
			(xy 183.406985 -50.951108) (xy 183.4135 -50.968158) (xy 183.419242 -50.97526) (xy 183.445295 -51.005677)
			(xy 183.492476 -51.070398) (xy 183.533647 -51.139099) (xy 183.568476 -51.211223) (xy 183.59668 -51.286186)
			(xy 183.61803 -51.363381) (xy 183.632355 -51.442183) (xy 183.639537 -51.521953) (xy 183.639968 -51.562)
			(xy 183.639577 -51.600284) (xy 183.633038 -51.676573) (xy 183.619958 -51.752015) (xy 183.600432 -51.826052)
			(xy 183.587898 -51.862228) (xy 183.585245 -51.870664) (xy 183.585245 -51.888336) (xy 183.587898 -51.896772)
			(xy 183.600422 -51.932951) (xy 183.61993 -52.00699) (xy 183.633011 -52.082431) (xy 183.639566 -52.158717)
			(xy 183.639968 -52.197) (xy 183.639464 -52.239348) (xy 183.631413 -52.323662) (xy 183.615384 -52.406828)
			(xy 183.591523 -52.488095) (xy 183.560044 -52.566725) (xy 183.521233 -52.642006) (xy 183.475443 -52.713258)
			(xy 183.423087 -52.779834) (xy 183.364639 -52.841132) (xy 183.300629 -52.896597) (xy 183.231637 -52.945726)
			(xy 183.158287 -52.988075) (xy 183.081244 -53.023259) (xy 183.001205 -53.050961) (xy 182.918896 -53.070929)
			(xy 182.835061 -53.082982) (xy 182.75046 -53.087013) (xy 182.665859 -53.082982) (xy 182.582024 -53.070929)
			(xy 182.499715 -53.050961) (xy 182.419676 -53.023259) (xy 182.342633 -52.988075) (xy 182.269283 -52.945726)
			(xy 182.200291 -52.896597) (xy 182.136281 -52.841132) (xy 182.077833 -52.779834) (xy 182.025477 -52.713258)
			(xy 181.979687 -52.642006) (xy 181.940876 -52.566725) (xy 181.909397 -52.488095) (xy 181.885536 -52.406828)
			(xy 181.869507 -52.323662) (xy 181.861456 -52.239348) (xy 181.860952 -52.197) (xy 178.178968 -52.197)
			(xy 178.178464 -52.239348) (xy 178.170413 -52.323662) (xy 178.154384 -52.406828) (xy 178.130523 -52.488095)
			(xy 178.099044 -52.566725) (xy 178.060233 -52.642006) (xy 178.014443 -52.713258) (xy 177.962087 -52.779834)
			(xy 177.903639 -52.841132) (xy 177.839629 -52.896597) (xy 177.770637 -52.945726) (xy 177.697287 -52.988075)
			(xy 177.620244 -53.023259) (xy 177.540205 -53.050961) (xy 177.457896 -53.070929) (xy 177.374061 -53.082982)
			(xy 177.28946 -53.087013) (xy 177.204859 -53.082982) (xy 177.121024 -53.070929) (xy 177.038715 -53.050961)
			(xy 176.958676 -53.023259) (xy 176.881633 -52.988075) (xy 176.808283 -52.945726) (xy 176.739291 -52.896597)
			(xy 176.675281 -52.841132) (xy 176.616833 -52.779834) (xy 176.564477 -52.713258) (xy 176.518687 -52.642006)
			(xy 176.479876 -52.566725) (xy 176.448397 -52.488095) (xy 176.424536 -52.406828) (xy 176.408507 -52.323662)
			(xy 176.400456 -52.239348) (xy 176.399952 -52.197) (xy 172.720508 -52.197) (xy 172.720004 -52.239348)
			(xy 172.711953 -52.323662) (xy 172.695924 -52.406828) (xy 172.672063 -52.488095) (xy 172.640584 -52.566725)
			(xy 172.601773 -52.642006) (xy 172.555983 -52.713258) (xy 172.503627 -52.779834) (xy 172.445179 -52.841132)
			(xy 172.381169 -52.896597) (xy 172.312177 -52.945726) (xy 172.238827 -52.988075) (xy 172.161784 -53.023259)
			(xy 172.081745 -53.050961) (xy 171.999436 -53.070929) (xy 171.915601 -53.082982) (xy 171.831 -53.087013)
			(xy 171.746399 -53.082982) (xy 171.662564 -53.070929) (xy 171.580255 -53.050961) (xy 171.500216 -53.023259)
			(xy 171.423173 -52.988075) (xy 171.349823 -52.945726) (xy 171.280831 -52.896597) (xy 171.216821 -52.841132)
			(xy 171.158373 -52.779834) (xy 171.106017 -52.713258) (xy 171.060227 -52.642006) (xy 171.021416 -52.566725)
			(xy 170.989937 -52.488095) (xy 170.966076 -52.406828) (xy 170.950047 -52.323662) (xy 170.941996 -52.239348)
			(xy 170.941492 -52.197) (xy 167.259508 -52.197) (xy 167.259004 -52.239348) (xy 167.250953 -52.323662)
			(xy 167.234924 -52.406828) (xy 167.211063 -52.488095) (xy 167.179584 -52.566725) (xy 167.140773 -52.642006)
			(xy 167.094983 -52.713258) (xy 167.042627 -52.779834) (xy 166.984179 -52.841132) (xy 166.920169 -52.896597)
			(xy 166.851177 -52.945726) (xy 166.777827 -52.988075) (xy 166.700784 -53.023259) (xy 166.620745 -53.050961)
			(xy 166.538436 -53.070929) (xy 166.454601 -53.082982) (xy 166.37 -53.087013) (xy 166.285399 -53.082982)
			(xy 166.201564 -53.070929) (xy 166.119255 -53.050961) (xy 166.039216 -53.023259) (xy 165.962173 -52.988075)
			(xy 165.888823 -52.945726) (xy 165.819831 -52.896597) (xy 165.755821 -52.841132) (xy 165.697373 -52.779834)
			(xy 165.645017 -52.713258) (xy 165.599227 -52.642006) (xy 165.560416 -52.566725) (xy 165.528937 -52.488095)
			(xy 165.505076 -52.406828) (xy 165.489047 -52.323662) (xy 165.480996 -52.239348) (xy 165.480492 -52.197)
			(xy 161.798508 -52.197) (xy 161.798004 -52.239348) (xy 161.789953 -52.323662) (xy 161.773924 -52.406828)
			(xy 161.750063 -52.488095) (xy 161.718584 -52.566725) (xy 161.679773 -52.642006) (xy 161.633983 -52.713258)
			(xy 161.581627 -52.779834) (xy 161.523179 -52.841132) (xy 161.459169 -52.896597) (xy 161.390177 -52.945726)
			(xy 161.316827 -52.988075) (xy 161.239784 -53.023259) (xy 161.159745 -53.050961) (xy 161.077436 -53.070929)
			(xy 160.993601 -53.082982) (xy 160.909 -53.087013) (xy 160.824399 -53.082982) (xy 160.740564 -53.070929)
			(xy 160.658255 -53.050961) (xy 160.578216 -53.023259) (xy 160.501173 -52.988075) (xy 160.427823 -52.945726)
			(xy 160.358831 -52.896597) (xy 160.294821 -52.841132) (xy 160.236373 -52.779834) (xy 160.184017 -52.713258)
			(xy 160.138227 -52.642006) (xy 160.099416 -52.566725) (xy 160.067937 -52.488095) (xy 160.044076 -52.406828)
			(xy 160.028047 -52.323662) (xy 160.019996 -52.239348) (xy 160.019492 -52.197) (xy 156.337508 -52.197)
			(xy 156.337004 -52.239348) (xy 156.328953 -52.323662) (xy 156.312924 -52.406828) (xy 156.289063 -52.488095)
			(xy 156.257584 -52.566725) (xy 156.218773 -52.642006) (xy 156.172983 -52.713258) (xy 156.120627 -52.779834)
			(xy 156.062179 -52.841132) (xy 155.998169 -52.896597) (xy 155.929177 -52.945726) (xy 155.855827 -52.988075)
			(xy 155.778784 -53.023259) (xy 155.698745 -53.050961) (xy 155.616436 -53.070929) (xy 155.532601 -53.082982)
			(xy 155.448 -53.087013) (xy 155.363399 -53.082982) (xy 155.279564 -53.070929) (xy 155.197255 -53.050961)
			(xy 155.117216 -53.023259) (xy 155.040173 -52.988075) (xy 154.966823 -52.945726) (xy 154.897831 -52.896597)
			(xy 154.833821 -52.841132) (xy 154.775373 -52.779834) (xy 154.723017 -52.713258) (xy 154.677227 -52.642006)
			(xy 154.638416 -52.566725) (xy 154.606937 -52.488095) (xy 154.583076 -52.406828) (xy 154.567047 -52.323662)
			(xy 154.558996 -52.239348) (xy 154.558492 -52.197) (xy 150.876508 -52.197) (xy 150.876004 -52.239348)
			(xy 150.867953 -52.323662) (xy 150.851924 -52.406828) (xy 150.828063 -52.488095) (xy 150.796584 -52.566725)
			(xy 150.757773 -52.642006) (xy 150.711983 -52.713258) (xy 150.659627 -52.779834) (xy 150.601179 -52.841132)
			(xy 150.537169 -52.896597) (xy 150.468177 -52.945726) (xy 150.394827 -52.988075) (xy 150.317784 -53.023259)
			(xy 150.237745 -53.050961) (xy 150.155436 -53.070929) (xy 150.071601 -53.082982) (xy 149.987 -53.087013)
			(xy 149.902399 -53.082982) (xy 149.818564 -53.070929) (xy 149.736255 -53.050961) (xy 149.656216 -53.023259)
			(xy 149.579173 -52.988075) (xy 149.505823 -52.945726) (xy 149.436831 -52.896597) (xy 149.372821 -52.841132)
			(xy 149.314373 -52.779834) (xy 149.262017 -52.713258) (xy 149.216227 -52.642006) (xy 149.177416 -52.566725)
			(xy 149.145937 -52.488095) (xy 149.122076 -52.406828) (xy 149.106047 -52.323662) (xy 149.097996 -52.239348)
			(xy 149.097492 -52.197) (xy 105.528396 -52.197) (xy 105.530551 -52.209431) (xy 105.537106 -52.285717)
			(xy 105.537508 -52.324) (xy 105.537004 -52.366348) (xy 105.528953 -52.450662) (xy 105.512924 -52.533828)
			(xy 105.489063 -52.615095) (xy 105.457584 -52.693725) (xy 105.418773 -52.769006) (xy 105.372983 -52.840258)
			(xy 105.320627 -52.906834) (xy 105.262179 -52.968132) (xy 105.198169 -53.023597) (xy 105.129177 -53.072726)
			(xy 105.055827 -53.115075) (xy 104.978784 -53.150259) (xy 104.898745 -53.177961) (xy 104.816436 -53.197929)
			(xy 104.732601 -53.209982) (xy 104.648 -53.214013) (xy 104.563399 -53.209982) (xy 104.479564 -53.197929)
			(xy 104.397255 -53.177961) (xy 104.317216 -53.150259) (xy 104.240173 -53.115075) (xy 104.166823 -53.072726)
			(xy 104.097831 -53.023597) (xy 104.033821 -52.968132) (xy 103.975373 -52.906834) (xy 103.923017 -52.840258)
			(xy 103.877227 -52.769006) (xy 103.838416 -52.693725) (xy 103.806937 -52.615095) (xy 103.783076 -52.533828)
			(xy 103.767047 -52.450662) (xy 103.758996 -52.366348) (xy 103.758492 -52.324) (xy 100.076508 -52.324)
			(xy 100.076004 -52.366348) (xy 100.067953 -52.450662) (xy 100.051924 -52.533828) (xy 100.028063 -52.615095)
			(xy 99.996584 -52.693725) (xy 99.957773 -52.769006) (xy 99.911983 -52.840258) (xy 99.859627 -52.906834)
			(xy 99.801179 -52.968132) (xy 99.737169 -53.023597) (xy 99.668177 -53.072726) (xy 99.594827 -53.115075)
			(xy 99.517784 -53.150259) (xy 99.437745 -53.177961) (xy 99.355436 -53.197929) (xy 99.271601 -53.209982)
			(xy 99.187 -53.214013) (xy 99.102399 -53.209982) (xy 99.018564 -53.197929) (xy 98.936255 -53.177961)
			(xy 98.856216 -53.150259) (xy 98.779173 -53.115075) (xy 98.705823 -53.072726) (xy 98.636831 -53.023597)
			(xy 98.572821 -52.968132) (xy 98.514373 -52.906834) (xy 98.462017 -52.840258) (xy 98.416227 -52.769006)
			(xy 98.377416 -52.693725) (xy 98.345937 -52.615095) (xy 98.322076 -52.533828) (xy 98.306047 -52.450662)
			(xy 98.297996 -52.366348) (xy 98.297492 -52.324) (xy 94.615508 -52.324) (xy 94.615004 -52.366348)
			(xy 94.606953 -52.450662) (xy 94.590924 -52.533828) (xy 94.567063 -52.615095) (xy 94.535584 -52.693725)
			(xy 94.496773 -52.769006) (xy 94.450983 -52.840258) (xy 94.398627 -52.906834) (xy 94.340179 -52.968132)
			(xy 94.276169 -53.023597) (xy 94.207177 -53.072726) (xy 94.133827 -53.115075) (xy 94.056784 -53.150259)
			(xy 93.976745 -53.177961) (xy 93.894436 -53.197929) (xy 93.810601 -53.209982) (xy 93.726 -53.214013)
			(xy 93.641399 -53.209982) (xy 93.557564 -53.197929) (xy 93.475255 -53.177961) (xy 93.395216 -53.150259)
			(xy 93.318173 -53.115075) (xy 93.244823 -53.072726) (xy 93.175831 -53.023597) (xy 93.111821 -52.968132)
			(xy 93.053373 -52.906834) (xy 93.001017 -52.840258) (xy 92.955227 -52.769006) (xy 92.916416 -52.693725)
			(xy 92.884937 -52.615095) (xy 92.861076 -52.533828) (xy 92.845047 -52.450662) (xy 92.836996 -52.366348)
			(xy 92.836492 -52.324) (xy 89.154508 -52.324) (xy 89.154004 -52.366348) (xy 89.145953 -52.450662)
			(xy 89.129924 -52.533828) (xy 89.106063 -52.615095) (xy 89.074584 -52.693725) (xy 89.035773 -52.769006)
			(xy 88.989983 -52.840258) (xy 88.937627 -52.906834) (xy 88.879179 -52.968132) (xy 88.815169 -53.023597)
			(xy 88.746177 -53.072726) (xy 88.672827 -53.115075) (xy 88.595784 -53.150259) (xy 88.515745 -53.177961)
			(xy 88.433436 -53.197929) (xy 88.349601 -53.209982) (xy 88.265 -53.214013) (xy 88.180399 -53.209982)
			(xy 88.096564 -53.197929) (xy 88.014255 -53.177961) (xy 87.934216 -53.150259) (xy 87.857173 -53.115075)
			(xy 87.783823 -53.072726) (xy 87.714831 -53.023597) (xy 87.650821 -52.968132) (xy 87.592373 -52.906834)
			(xy 87.540017 -52.840258) (xy 87.494227 -52.769006) (xy 87.455416 -52.693725) (xy 87.423937 -52.615095)
			(xy 87.400076 -52.533828) (xy 87.384047 -52.450662) (xy 87.375996 -52.366348) (xy 87.375492 -52.324)
			(xy 83.693508 -52.324) (xy 83.693004 -52.366348) (xy 83.684953 -52.450662) (xy 83.668924 -52.533828)
			(xy 83.645063 -52.615095) (xy 83.613584 -52.693725) (xy 83.574773 -52.769006) (xy 83.528983 -52.840258)
			(xy 83.476627 -52.906834) (xy 83.418179 -52.968132) (xy 83.354169 -53.023597) (xy 83.285177 -53.072726)
			(xy 83.211827 -53.115075) (xy 83.134784 -53.150259) (xy 83.054745 -53.177961) (xy 82.972436 -53.197929)
			(xy 82.888601 -53.209982) (xy 82.804 -53.214013) (xy 82.719399 -53.209982) (xy 82.635564 -53.197929)
			(xy 82.553255 -53.177961) (xy 82.473216 -53.150259) (xy 82.396173 -53.115075) (xy 82.322823 -53.072726)
			(xy 82.253831 -53.023597) (xy 82.189821 -52.968132) (xy 82.131373 -52.906834) (xy 82.079017 -52.840258)
			(xy 82.033227 -52.769006) (xy 81.994416 -52.693725) (xy 81.962937 -52.615095) (xy 81.939076 -52.533828)
			(xy 81.923047 -52.450662) (xy 81.914996 -52.366348) (xy 81.914492 -52.324) (xy 78.232508 -52.324)
			(xy 78.232004 -52.366348) (xy 78.223953 -52.450662) (xy 78.207924 -52.533828) (xy 78.184063 -52.615095)
			(xy 78.152584 -52.693725) (xy 78.113773 -52.769006) (xy 78.067983 -52.840258) (xy 78.015627 -52.906834)
			(xy 77.957179 -52.968132) (xy 77.893169 -53.023597) (xy 77.824177 -53.072726) (xy 77.750827 -53.115075)
			(xy 77.673784 -53.150259) (xy 77.593745 -53.177961) (xy 77.511436 -53.197929) (xy 77.427601 -53.209982)
			(xy 77.343 -53.214013) (xy 77.258399 -53.209982) (xy 77.174564 -53.197929) (xy 77.092255 -53.177961)
			(xy 77.012216 -53.150259) (xy 76.935173 -53.115075) (xy 76.861823 -53.072726) (xy 76.792831 -53.023597)
			(xy 76.728821 -52.968132) (xy 76.670373 -52.906834) (xy 76.618017 -52.840258) (xy 76.572227 -52.769006)
			(xy 76.533416 -52.693725) (xy 76.501937 -52.615095) (xy 76.478076 -52.533828) (xy 76.462047 -52.450662)
			(xy 76.453996 -52.366348) (xy 76.453492 -52.324) (xy 72.771508 -52.324) (xy 72.771004 -52.366348)
			(xy 72.762953 -52.450662) (xy 72.746924 -52.533828) (xy 72.723063 -52.615095) (xy 72.691584 -52.693725)
			(xy 72.652773 -52.769006) (xy 72.606983 -52.840258) (xy 72.554627 -52.906834) (xy 72.496179 -52.968132)
			(xy 72.432169 -53.023597) (xy 72.363177 -53.072726) (xy 72.289827 -53.115075) (xy 72.212784 -53.150259)
			(xy 72.132745 -53.177961) (xy 72.050436 -53.197929) (xy 71.966601 -53.209982) (xy 71.882 -53.214013)
			(xy 71.797399 -53.209982) (xy 71.713564 -53.197929) (xy 71.631255 -53.177961) (xy 71.551216 -53.150259)
			(xy 71.474173 -53.115075) (xy 71.400823 -53.072726) (xy 71.331831 -53.023597) (xy 71.267821 -52.968132)
			(xy 71.209373 -52.906834) (xy 71.157017 -52.840258) (xy 71.111227 -52.769006) (xy 71.072416 -52.693725)
			(xy 71.040937 -52.615095) (xy 71.017076 -52.533828) (xy 71.001047 -52.450662) (xy 70.992996 -52.366348)
			(xy 70.992492 -52.324) (xy 51.706282 -52.324) (xy 51.700727 -52.350268) (xy 51.672187 -52.438562)
			(xy 51.653948 -52.481226) (xy 51.65014 -52.491168) (xy 51.65014 -52.512432) (xy 51.653948 -52.522374)
			(xy 51.672195 -52.565035) (xy 51.700738 -52.653328) (xy 51.71993 -52.744113) (xy 51.729563 -52.836404)
			(xy 51.730148 -52.8828) (xy 51.729633 -52.923901) (xy 51.722049 -53.005753) (xy 51.706945 -53.086556)
			(xy 51.684449 -53.165621) (xy 51.654755 -53.242273) (xy 51.618115 -53.315858) (xy 51.574842 -53.385749)
			(xy 51.525305 -53.451349) (xy 51.469927 -53.512099) (xy 51.40918 -53.56748) (xy 51.343582 -53.61702)
			(xy 51.273693 -53.660296) (xy 51.20011 -53.696939) (xy 51.123459 -53.726637) (xy 51.044395 -53.749136)
			(xy 50.963593 -53.764243) (xy 50.881741 -53.771832) (xy 50.84064 -53.772308) (xy 50.794245 -53.771711)
			(xy 50.701957 -53.76207) (xy 50.611173 -53.742878) (xy 50.522879 -53.714344) (xy 50.480214 -53.696108)
			(xy 50.470272 -53.692302) (xy 50.449008 -53.692302) (xy 50.439066 -53.696108) (xy 50.396398 -53.71434)
			(xy 50.308108 -53.742887) (xy 50.217325 -53.762084) (xy 50.125036 -53.771721) (xy 50.07864 -53.772308)
			(xy 50.032245 -53.771711) (xy 49.939957 -53.76207) (xy 49.849173 -53.742878) (xy 49.760879 -53.714344)
			(xy 49.718214 -53.696108) (xy 49.708272 -53.692302) (xy 49.687008 -53.692302) (xy 49.677066 -53.696108)
			(xy 49.634398 -53.71434) (xy 49.546108 -53.742887) (xy 49.455325 -53.762084) (xy 49.363036 -53.771721)
			(xy 49.31664 -53.772308) (xy 49.275537 -53.77181) (xy 49.193683 -53.764228) (xy 49.112877 -53.749126)
			(xy 49.033809 -53.726633) (xy 48.957154 -53.69694) (xy 48.883566 -53.6603) (xy 48.813673 -53.617027)
			(xy 48.748071 -53.567489) (xy 48.687319 -53.512109) (xy 48.631937 -53.45136) (xy 48.582396 -53.38576)
			(xy 48.53912 -53.315869) (xy 48.502477 -53.242282) (xy 48.47278 -53.165629) (xy 48.450283 -53.086562)
			(xy 48.435177 -53.005757) (xy 48.427592 -52.923902) (xy 48.427132 -52.8828) (xy 47.945068 -52.8828)
			(xy 47.945548 -52.9209) (xy 47.945044 -52.963248) (xy 47.936993 -53.047562) (xy 47.920964 -53.130728)
			(xy 47.897103 -53.211995) (xy 47.865624 -53.290625) (xy 47.826813 -53.365906) (xy 47.781023 -53.437158)
			(xy 47.728667 -53.503734) (xy 47.670219 -53.565032) (xy 47.606209 -53.620497) (xy 47.537217 -53.669626)
			(xy 47.463867 -53.711975) (xy 47.386824 -53.747159) (xy 47.306785 -53.774861) (xy 47.224476 -53.794829)
			(xy 47.140641 -53.806882) (xy 47.05604 -53.810913) (xy 46.971439 -53.806882) (xy 46.887604 -53.794829)
			(xy 46.805295 -53.774861) (xy 46.725256 -53.747159) (xy 46.648213 -53.711975) (xy 46.574863 -53.669626)
			(xy 46.505871 -53.620497) (xy 46.441861 -53.565032) (xy 46.383413 -53.503734) (xy 46.331057 -53.437158)
			(xy 46.285267 -53.365906) (xy 46.246456 -53.290625) (xy 46.214977 -53.211995) (xy 46.191116 -53.130728)
			(xy 46.175087 -53.047562) (xy 46.167036 -52.963248) (xy 46.166532 -52.9209) (xy 44.986526 -52.9209)
			(xy 44.977819 -52.930032) (xy 44.913809 -52.985497) (xy 44.844817 -53.034626) (xy 44.771467 -53.076975)
			(xy 44.694424 -53.112159) (xy 44.614385 -53.139861) (xy 44.532076 -53.159829) (xy 44.448241 -53.171882)
			(xy 44.36364 -53.175913) (xy 44.279039 -53.171882) (xy 44.195204 -53.159829) (xy 44.112895 -53.139861)
			(xy 44.032856 -53.112159) (xy 43.955813 -53.076975) (xy 43.882463 -53.034626) (xy 43.813471 -52.985497)
			(xy 43.749461 -52.930032) (xy 43.691013 -52.868734) (xy 43.638657 -52.802158) (xy 43.592867 -52.730906)
			(xy 43.554056 -52.655625) (xy 43.522577 -52.576995) (xy 43.498716 -52.495728) (xy 43.482687 -52.412562)
			(xy 43.474636 -52.328248) (xy 43.474132 -52.2859) (xy 0.509016 -52.2859) (xy 0.509016 -54.399942)
			(xy 3.446023 -54.399942) (xy 3.450044 -54.28608) (xy 3.462086 -54.172786) (xy 3.482091 -54.060624)
			(xy 3.509957 -53.950152) (xy 3.545546 -53.84192) (xy 3.588681 -53.736469) (xy 3.639147 -53.634323)
			(xy 3.696693 -53.535992) (xy 3.761032 -53.441964) (xy 3.831843 -53.352709) (xy 3.908773 -53.268672)
			(xy 3.99144 -53.19027) (xy 4.079431 -53.117895) (xy 4.172308 -53.051907) (xy 4.269609 -52.992635)
			(xy 4.370848 -52.940374) (xy 4.475522 -52.895384) (xy 4.583108 -52.85789) (xy 4.693071 -52.828079)
			(xy 4.804864 -52.806098) (xy 4.917928 -52.792058) (xy 5.0317 -52.786028) (xy 5.145615 -52.788039)
			(xy 5.259104 -52.79808) (xy 5.371603 -52.816102) (xy 5.482549 -52.842014) (xy 5.591392 -52.875688)
			(xy 5.697588 -52.916955) (xy 5.800608 -52.965611) (xy 5.89994 -53.021412) (xy 5.995089 -53.084081)
			(xy 6.085579 -53.153306) (xy 6.170961 -53.228741) (xy 6.25081 -53.310012) (xy 6.324727 -53.396712)
			(xy 6.392343 -53.48841) (xy 6.453324 -53.584649) (xy 6.507363 -53.684951) (xy 6.554193 -53.788814)
			(xy 6.59358 -53.895722) (xy 6.625327 -54.005142) (xy 6.649277 -54.116528) (xy 6.665311 -54.229327)
			(xy 6.673347 -54.342976) (xy 6.67385 -54.399942) (xy 6.673347 -54.456908) (xy 6.665311 -54.570557)
			(xy 6.649277 -54.683356) (xy 6.625327 -54.794742) (xy 6.59358 -54.904162) (xy 6.554193 -55.01107)
			(xy 6.507363 -55.114933) (xy 6.453324 -55.215235) (xy 6.392343 -55.311474) (xy 6.324727 -55.403172)
			(xy 6.25081 -55.489872) (xy 6.170961 -55.571143) (xy 6.090758 -55.642002) (xy 37.371528 -55.642002)
			(xy 37.372032 -55.599654) (xy 37.380083 -55.51534) (xy 37.396112 -55.432174) (xy 37.419973 -55.350907)
			(xy 37.451452 -55.272277) (xy 37.490263 -55.196996) (xy 37.536053 -55.125744) (xy 37.588409 -55.059168)
			(xy 37.646857 -54.99787) (xy 37.710867 -54.942405) (xy 37.779859 -54.893276) (xy 37.853209 -54.850927)
			(xy 37.930252 -54.815743) (xy 38.010291 -54.788041) (xy 38.0926 -54.768073) (xy 38.176435 -54.75602)
			(xy 38.261036 -54.75199) (xy 38.345637 -54.75602) (xy 38.429472 -54.768073) (xy 38.511781 -54.788041)
			(xy 38.59182 -54.815743) (xy 38.668863 -54.850927) (xy 38.742213 -54.893276) (xy 38.811205 -54.942405)
			(xy 38.875215 -54.99787) (xy 38.933663 -55.059168) (xy 38.986019 -55.125744) (xy 39.031809 -55.196996)
			(xy 39.07062 -55.272277) (xy 39.102099 -55.350907) (xy 39.12596 -55.432174) (xy 39.141989 -55.51534)
			(xy 39.15004 -55.599654) (xy 39.150544 -55.642002) (xy 39.149888 -55.692156) (xy 39.13869 -55.791837)
			(xy 39.128192 -55.840884) (xy 39.126403 -55.851401) (xy 39.130519 -55.872305) (xy 39.142729 -55.889765)
			(xy 39.15156 -55.895748) (xy 39.188993 -55.918893) (xy 39.259542 -55.971521) (xy 39.324556 -56.030851)
			(xy 39.383399 -56.096306) (xy 39.409878 -56.13146) (xy 39.416788 -56.140033) (xy 39.436031 -56.150694)
			(xy 39.446962 -56.152034) (xy 39.488331 -56.155768) (xy 39.570195 -56.169853) (xy 39.65039 -56.191507)
			(xy 39.728218 -56.220543) (xy 39.802999 -56.256707) (xy 39.874084 -56.299685) (xy 39.940853 -56.349102)
			(xy 40.002725 -56.404528) (xy 40.05916 -56.465481) (xy 40.109668 -56.531428) (xy 40.153809 -56.601797)
			(xy 40.191198 -56.675974) (xy 40.221509 -56.753314) (xy 40.244479 -56.833142) (xy 40.259907 -56.914764)
			(xy 40.267659 -56.997468) (xy 40.268144 -57.039002) (xy 40.267664 -57.082792) (xy 40.259099 -57.169952)
			(xy 40.242002 -57.255846) (xy 40.216539 -57.339643) (xy 40.182958 -57.420528) (xy 40.162734 -57.459372)
			(xy 40.157312 -57.470837) (xy 40.157313 -57.496166) (xy 40.162734 -57.507632) (xy 40.182954 -57.546475)
			(xy 40.216507 -57.627369) (xy 40.241955 -57.711167) (xy 40.259051 -57.797058) (xy 40.267631 -57.884214)
			(xy 40.268144 -57.928002) (xy 40.267664 -57.971792) (xy 40.259099 -58.058952) (xy 40.242002 -58.144846)
			(xy 40.216539 -58.228643) (xy 40.182958 -58.309528) (xy 40.162734 -58.348372) (xy 40.157312 -58.359837)
			(xy 40.157313 -58.385166) (xy 40.162734 -58.396632) (xy 40.182954 -58.435475) (xy 40.216507 -58.516369)
			(xy 40.241955 -58.600167) (xy 40.242899 -58.604912) (xy 40.474392 -58.604912) (xy 40.474903 -58.560519)
			(xy 40.483698 -58.472169) (xy 40.50125 -58.385135) (xy 40.527387 -58.300283) (xy 40.561847 -58.218457)
			(xy 40.582596 -58.179208) (xy 40.586434 -58.171656) (xy 40.589251 -58.154957) (xy 40.586406 -58.138263)
			(xy 40.582596 -58.130694) (xy 40.561847 -58.091445) (xy 40.527387 -58.009619) (xy 40.501251 -57.924767)
			(xy 40.483698 -57.837733) (xy 40.474903 -57.749383) (xy 40.474392 -57.70499) (xy 40.474894 -57.660596)
			(xy 40.48369 -57.572247) (xy 40.501245 -57.485213) (xy 40.527384 -57.400361) (xy 40.561846 -57.318535)
			(xy 40.582596 -57.279286) (xy 40.586376 -57.271708) (xy 40.589213 -57.255026) (xy 40.586393 -57.23834)
			(xy 40.582596 -57.230772) (xy 40.561839 -57.191527) (xy 40.52738 -57.1097) (xy 40.501246 -57.024847)
			(xy 40.483694 -56.937812) (xy 40.474902 -56.849462) (xy 40.474392 -56.805068) (xy 40.474941 -56.760669)
			(xy 40.483788 -56.672313) (xy 40.501391 -56.585278) (xy 40.527575 -56.500428) (xy 40.562079 -56.418608)
			(xy 40.58285 -56.379364) (xy 40.586655 -56.371754) (xy 40.589465 -56.354982) (xy 40.586644 -56.338212)
			(xy 40.58285 -56.330596) (xy 40.56208 -56.291351) (xy 40.527568 -56.209533) (xy 40.501379 -56.124684)
			(xy 40.483774 -56.037648) (xy 40.474928 -55.949291) (xy 40.474392 -55.904892) (xy 40.474795 -55.863896)
			(xy 40.482332 -55.782251) (xy 40.497352 -55.701646) (xy 40.519727 -55.622766) (xy 40.549266 -55.546279)
			(xy 40.585719 -55.472836) (xy 40.628776 -55.40306) (xy 40.678073 -55.337542) (xy 40.73319 -55.276839)
			(xy 40.79366 -55.221467) (xy 40.85897 -55.171895) (xy 40.928564 -55.128544) (xy 41.001853 -55.091782)
			(xy 41.078215 -55.061921) (xy 41.157 -55.039215) (xy 41.237541 -55.023856) (xy 41.278302 -55.019448)
			(xy 41.294304 -55.017924) (xy 41.318434 -54.997604) (xy 41.351708 -54.874922) (xy 41.341294 -54.845204)
			(xy 41.328086 -54.835806) (xy 41.294308 -54.810762) (xy 41.231103 -54.755296) (xy 41.173413 -54.694112)
			(xy 41.121754 -54.627759) (xy 41.076587 -54.556826) (xy 41.038314 -54.481948) (xy 41.007278 -54.403793)
			(xy 40.983755 -54.323058) (xy 40.967956 -54.240463) (xy 40.960021 -54.156746) (xy 40.959532 -54.1147)
			(xy 40.95995 -54.074933) (xy 40.96699 -53.995711) (xy 40.981077 -53.917434) (xy 41.002099 -53.840728)
			(xy 41.029886 -53.766206) (xy 41.046654 -53.730144) (xy 41.050985 -53.719643) (xy 41.050985 -53.696957)
			(xy 41.046654 -53.686456) (xy 41.029913 -53.650383) (xy 41.002132 -53.57586) (xy 40.981109 -53.499157)
			(xy 40.967012 -53.420884) (xy 40.959954 -53.341666) (xy 40.959532 -53.3019) (xy 40.959952 -53.260796)
			(xy 40.967538 -53.178938) (xy 40.982644 -53.098129) (xy 41.005142 -53.019059) (xy 41.03484 -52.942402)
			(xy 41.071485 -52.868812) (xy 41.114763 -52.798917) (xy 41.164306 -52.733314) (xy 41.219691 -52.672563)
			(xy 41.280445 -52.61718) (xy 41.34605 -52.56764) (xy 41.415947 -52.524365) (xy 41.489538 -52.487724)
			(xy 41.566197 -52.458029) (xy 41.645268 -52.435535) (xy 41.726077 -52.420432) (xy 41.807936 -52.41285)
			(xy 41.84904 -52.412392) (xy 41.893805 -52.412911) (xy 41.982887 -52.421844) (xy 42.07062 -52.439686)
			(xy 42.156115 -52.466255) (xy 42.197528 -52.483258) (xy 42.207119 -52.486823) (xy 42.227561 -52.486823)
			(xy 42.237152 -52.483258) (xy 42.278569 -52.466265) (xy 42.364066 -52.439708) (xy 42.451797 -52.421867)
			(xy 42.540876 -52.412923) (xy 42.58564 -52.412392) (xy 42.626743 -52.412828) (xy 42.708598 -52.420417)
			(xy 42.789404 -52.435526) (xy 42.868472 -52.458025) (xy 42.945126 -52.487724) (xy 43.018713 -52.524369)
			(xy 43.088605 -52.567647) (xy 43.154206 -52.617189) (xy 43.214955 -52.672573) (xy 43.270336 -52.733325)
			(xy 43.319875 -52.798928) (xy 43.36315 -52.868822) (xy 43.399792 -52.942411) (xy 43.429487 -53.019066)
			(xy 43.451984 -53.098134) (xy 43.467089 -53.178941) (xy 43.474673 -53.260797) (xy 43.475148 -53.3019)
			(xy 43.474732 -53.341667) (xy 43.467691 -53.42089) (xy 43.453604 -53.499166) (xy 43.432582 -53.575872)
			(xy 43.404794 -53.650394) (xy 43.388026 -53.686456) (xy 43.383691 -53.696957) (xy 43.383691 -53.719643)
			(xy 43.388026 -53.730144) (xy 43.404773 -53.766215) (xy 43.432551 -53.840738) (xy 43.453572 -53.917442)
			(xy 43.467668 -53.995715) (xy 43.474726 -54.074934) (xy 43.475148 -54.1147) (xy 43.474633 -54.155801)
			(xy 43.467049 -54.237653) (xy 43.451945 -54.318456) (xy 43.429449 -54.397521) (xy 43.399755 -54.474173)
			(xy 43.363115 -54.547758) (xy 43.319842 -54.617649) (xy 43.270305 -54.683249) (xy 43.214927 -54.743999)
			(xy 43.15418 -54.79938) (xy 43.088582 -54.84892) (xy 43.018693 -54.892196) (xy 42.94511 -54.928839)
			(xy 42.868459 -54.958537) (xy 42.789395 -54.981036) (xy 42.708593 -54.996143) (xy 42.626741 -55.003732)
			(xy 42.58564 -55.004208) (xy 42.540875 -55.003695) (xy 42.451793 -54.994761) (xy 42.36406 -54.976917)
			(xy 42.278565 -54.950346) (xy 42.237152 -54.933342) (xy 42.227561 -54.929777) (xy 42.207119 -54.929777)
			(xy 42.197528 -54.933342) (xy 42.182542 -54.939438) (xy 42.17275 -54.944035) (xy 42.157834 -54.959663)
			(xy 42.150643 -54.980036) (xy 42.152446 -55.001564) (xy 42.162924 -55.020457) (xy 42.180232 -55.033387)
			(xy 42.19067 -55.036212) (xy 42.232544 -55.046034) (xy 42.314349 -55.072611) (xy 42.393207 -55.106959)
			(xy 42.468382 -55.148756) (xy 42.539173 -55.197614) (xy 42.604918 -55.253075) (xy 42.665004 -55.314623)
			(xy 42.718869 -55.381682) (xy 42.766012 -55.453626) (xy 42.805991 -55.529784) (xy 42.838434 -55.609444)
			(xy 42.863037 -55.691864) (xy 42.879572 -55.776274) (xy 42.887883 -55.861885) (xy 42.888408 -55.904892)
			(xy 42.887885 -55.949292) (xy 42.879032 -56.037648) (xy 42.861423 -56.124684) (xy 42.835233 -56.209533)
			(xy 42.800723 -56.291352) (xy 42.77995 -56.330596) (xy 42.776174 -56.338218) (xy 42.773354 -56.354982)
			(xy 42.776163 -56.371748) (xy 42.77995 -56.379364) (xy 42.800704 -56.418617) (xy 42.835219 -56.500433)
			(xy 42.861411 -56.585279) (xy 42.87902 -56.672314) (xy 42.88787 -56.760669) (xy 42.888408 -56.805068)
			(xy 42.887888 -56.849461) (xy 42.879096 -56.93781) (xy 42.861545 -57.024844) (xy 42.83541 -57.109696)
			(xy 42.800952 -57.191523) (xy 42.780204 -57.230772) (xy 42.774742 -57.242292) (xy 42.774755 -57.267758)
			(xy 42.780204 -57.279286) (xy 42.800945 -57.318539) (xy 42.835407 -57.400364) (xy 42.861545 -57.485215)
			(xy 42.8791 -57.572248) (xy 42.887896 -57.660597) (xy 42.888408 -57.70499) (xy 42.887898 -57.749383)
			(xy 42.879103 -57.837733) (xy 42.86155 -57.924767) (xy 42.835413 -58.009619) (xy 42.800953 -58.091445)
			(xy 42.780204 -58.130694) (xy 42.774796 -58.142234) (xy 42.774774 -58.167681) (xy 42.780204 -58.179208)
			(xy 42.800954 -58.218457) (xy 42.835413 -58.300283) (xy 42.86155 -58.385135) (xy 42.879103 -58.472169)
			(xy 42.887897 -58.560519) (xy 42.888408 -58.604912) (xy 42.887945 -58.646015) (xy 42.880359 -58.727869)
			(xy 42.865253 -58.808675) (xy 42.842755 -58.887742) (xy 42.813058 -58.964396) (xy 42.776416 -59.037983)
			(xy 42.733139 -59.107875) (xy 42.683599 -59.173476) (xy 42.628217 -59.234226) (xy 42.567466 -59.289607)
			(xy 42.501865 -59.339146) (xy 42.431972 -59.382421) (xy 42.358385 -59.419063) (xy 42.28173 -59.448759)
			(xy 42.202663 -59.471255) (xy 42.121857 -59.48636) (xy 42.040003 -59.493945) (xy 41.9989 -59.49442)
			(xy 41.960616 -59.494032) (xy 41.884327 -59.487493) (xy 41.808885 -59.474411) (xy 41.734848 -59.454885)
			(xy 41.698672 -59.44235) (xy 41.690235 -59.439699) (xy 41.672565 -59.439699) (xy 41.664128 -59.44235)
			(xy 41.62795 -59.454876) (xy 41.55391 -59.474383) (xy 41.478469 -59.487463) (xy 41.402183 -59.494018)
			(xy 41.3639 -59.49442) (xy 41.322798 -59.493933) (xy 41.240944 -59.486349) (xy 41.16014 -59.471244)
			(xy 41.081073 -59.448748) (xy 41.00442 -59.419052) (xy 40.930834 -59.382411) (xy 40.860942 -59.339136)
			(xy 40.795341 -59.289598) (xy 40.734591 -59.234217) (xy 40.67921 -59.173468) (xy 40.62967 -59.107868)
			(xy 40.586395 -59.037977) (xy 40.549753 -58.964391) (xy 40.520056 -58.887738) (xy 40.497559 -58.808672)
			(xy 40.482453 -58.727868) (xy 40.474867 -58.646014) (xy 40.474392 -58.604912) (xy 40.242899 -58.604912)
			(xy 40.259051 -58.686058) (xy 40.267631 -58.773214) (xy 40.268144 -58.817002) (xy 40.267689 -58.858109)
			(xy 40.260105 -58.939973) (xy 40.245 -59.020789) (xy 40.222505 -59.099866) (xy 40.19281 -59.17653)
			(xy 40.156169 -59.250129) (xy 40.112895 -59.320033) (xy 40.063357 -59.385647) (xy 40.007977 -59.446411)
			(xy 39.947227 -59.501807) (xy 39.881626 -59.551363) (xy 39.811733 -59.594655) (xy 39.738145 -59.631315)
			(xy 39.661488 -59.66103) (xy 39.582416 -59.683546) (xy 39.501605 -59.698672) (xy 39.419743 -59.706279)
			(xy 39.378636 -59.706764) (xy 39.336929 -59.706247) (xy 39.253882 -59.698432) (xy 39.17193 -59.682877)
			(xy 39.091796 -59.659718) (xy 39.014181 -59.629158) (xy 38.939768 -59.591467) (xy 38.86921 -59.546974)
			(xy 38.803128 -59.496072) (xy 38.742101 -59.439206) (xy 38.686666 -59.376878) (xy 38.661594 -59.343544)
			(xy 38.654652 -59.335001) (xy 38.635433 -59.324324) (xy 38.62451 -59.32297) (xy 38.583139 -59.319256)
			(xy 38.501275 -59.305169) (xy 38.42108 -59.283512) (xy 38.343252 -59.254474) (xy 38.268471 -59.218308)
			(xy 38.197386 -59.175329) (xy 38.130618 -59.12591) (xy 38.068746 -59.070482) (xy 38.012311 -59.009529)
			(xy 37.961804 -58.94358) (xy 37.917663 -58.873211) (xy 37.880275 -58.799033) (xy 37.849964 -58.721692)
			(xy 37.826994 -58.641864) (xy 37.811565 -58.560241) (xy 37.803813 -58.477536) (xy 37.803328 -58.436002)
			(xy 37.803813 -58.392212) (xy 37.812377 -58.305053) (xy 37.829473 -58.219158) (xy 37.854935 -58.135362)
			(xy 37.888515 -58.054476) (xy 37.908738 -58.015632) (xy 37.914152 -58.004165) (xy 37.914153 -57.978839)
			(xy 37.908738 -57.967372) (xy 37.888517 -57.928529) (xy 37.854964 -57.847635) (xy 37.829517 -57.763837)
			(xy 37.812421 -57.677946) (xy 37.803841 -57.59079) (xy 37.803328 -57.547002) (xy 37.803813 -57.503212)
			(xy 37.812377 -57.416053) (xy 37.829473 -57.330158) (xy 37.854935 -57.246362) (xy 37.888515 -57.165476)
			(xy 37.908738 -57.126632) (xy 37.914152 -57.115165) (xy 37.914153 -57.089839) (xy 37.908738 -57.078372)
			(xy 37.888517 -57.039529) (xy 37.854964 -56.958635) (xy 37.829517 -56.874837) (xy 37.812421 -56.788946)
			(xy 37.803841 -56.70179) (xy 37.803328 -56.658002) (xy 37.803969 -56.607847) (xy 37.815177 -56.508167)
			(xy 37.82568 -56.45912) (xy 37.827479 -56.448604) (xy 37.823362 -56.427696) (xy 37.811147 -56.410236)
			(xy 37.802312 -56.404256) (xy 37.766912 -56.382369) (xy 37.699929 -56.332962) (xy 37.637853 -56.277515)
			(xy 37.581226 -56.216513) (xy 37.530544 -56.15049) (xy 37.48625 -56.080021) (xy 37.44873 -56.005724)
			(xy 37.418313 -55.928248) (xy 37.395264 -55.84827) (xy 37.379785 -55.766488) (xy 37.372012 -55.683619)
			(xy 37.371528 -55.642002) (xy 6.090758 -55.642002) (xy 6.085579 -55.646578) (xy 5.995089 -55.715803)
			(xy 5.89994 -55.778472) (xy 5.800608 -55.834273) (xy 5.697588 -55.882929) (xy 5.591392 -55.924196)
			(xy 5.482549 -55.95787) (xy 5.371603 -55.983782) (xy 5.259104 -56.001804) (xy 5.145615 -56.011845)
			(xy 5.0317 -56.013856) (xy 4.917928 -56.007826) (xy 4.804864 -55.993786) (xy 4.693071 -55.971805)
			(xy 4.583108 -55.941994) (xy 4.475522 -55.9045) (xy 4.370848 -55.85951) (xy 4.269609 -55.807249)
			(xy 4.172308 -55.747977) (xy 4.079431 -55.681989) (xy 3.99144 -55.609614) (xy 3.908773 -55.531212)
			(xy 3.831843 -55.447175) (xy 3.761032 -55.35792) (xy 3.696693 -55.263892) (xy 3.639147 -55.165561)
			(xy 3.588681 -55.063415) (xy 3.545546 -54.957964) (xy 3.509957 -54.849732) (xy 3.482091 -54.73926)
			(xy 3.462086 -54.627098) (xy 3.450044 -54.513804) (xy 3.446023 -54.399942) (xy 0.509016 -54.399942)
			(xy 0.509016 -60.96) (xy 66.673737 -60.96) (xy 66.677742 -60.854251) (xy 66.689732 -60.749108) (xy 66.709641 -60.645173)
			(xy 66.737352 -60.543041) (xy 66.772709 -60.443297) (xy 66.815507 -60.346513) (xy 66.865503 -60.253243)
			(xy 66.92241 -60.164022) (xy 66.985901 -60.079359) (xy 67.055613 -59.999741) (xy 67.131147 -59.925623)
			(xy 67.21207 -59.85743) (xy 67.297919 -59.795552) (xy 67.388202 -59.740345) (xy 67.482401 -59.692123)
			(xy 67.579978 -59.651163) (xy 67.680373 -59.617701) (xy 67.783011 -59.591927) (xy 67.887304 -59.573989)
			(xy 67.992655 -59.56399) (xy 68.098461 -59.561987) (xy 68.204115 -59.567992) (xy 68.309012 -59.581971)
			(xy 68.412552 -59.603842) (xy 68.514141 -59.633482) (xy 68.613198 -59.67072) (xy 68.709155 -59.715342)
			(xy 68.801462 -59.767094) (xy 68.889591 -59.825679) (xy 68.973037 -59.890761) (xy 69.051321 -59.961967)
			(xy 69.123996 -60.03889) (xy 69.190646 -60.12109) (xy 69.250888 -60.208094) (xy 69.304377 -60.299405)
			(xy 69.350808 -60.3945) (xy 69.389913 -60.492834) (xy 69.42147 -60.593845) (xy 69.445297 -60.696952)
			(xy 69.461258 -60.801566) (xy 69.469262 -60.907088) (xy 69.469762 -60.96) (xy 77.976737 -60.96) (xy 77.980742 -60.854251)
			(xy 77.992732 -60.749108) (xy 78.012641 -60.645173) (xy 78.040352 -60.543041) (xy 78.075709 -60.443297)
			(xy 78.118507 -60.346513) (xy 78.168503 -60.253243) (xy 78.22541 -60.164022) (xy 78.288901 -60.079359)
			(xy 78.358613 -59.999741) (xy 78.434147 -59.925623) (xy 78.51507 -59.85743) (xy 78.600919 -59.795552)
			(xy 78.691202 -59.740345) (xy 78.785401 -59.692123) (xy 78.882978 -59.651163) (xy 78.983373 -59.617701)
			(xy 79.086011 -59.591927) (xy 79.190304 -59.573989) (xy 79.295655 -59.56399) (xy 79.401461 -59.561987)
			(xy 79.507115 -59.567992) (xy 79.612012 -59.581971) (xy 79.715552 -59.603842) (xy 79.817141 -59.633482)
			(xy 79.916198 -59.67072) (xy 80.012155 -59.715342) (xy 80.104462 -59.767094) (xy 80.192591 -59.825679)
			(xy 80.276037 -59.890761) (xy 80.354321 -59.961967) (xy 80.426996 -60.03889) (xy 80.493646 -60.12109)
			(xy 80.553888 -60.208094) (xy 80.607377 -60.299405) (xy 80.653808 -60.3945) (xy 80.692913 -60.492834)
			(xy 80.72447 -60.593845) (xy 80.748297 -60.696952) (xy 80.764258 -60.801566) (xy 80.772262 -60.907088)
			(xy 80.772762 -60.96) (xy 89.279737 -60.96) (xy 89.283742 -60.854251) (xy 89.295732 -60.749108) (xy 89.315641 -60.645173)
			(xy 89.343352 -60.543041) (xy 89.378709 -60.443297) (xy 89.421507 -60.346513) (xy 89.471503 -60.253243)
			(xy 89.52841 -60.164022) (xy 89.591901 -60.079359) (xy 89.661613 -59.999741) (xy 89.737147 -59.925623)
			(xy 89.81807 -59.85743) (xy 89.903919 -59.795552) (xy 89.994202 -59.740345) (xy 90.088401 -59.692123)
			(xy 90.185978 -59.651163) (xy 90.286373 -59.617701) (xy 90.389011 -59.591927) (xy 90.493304 -59.573989)
			(xy 90.598655 -59.56399) (xy 90.704461 -59.561987) (xy 90.810115 -59.567992) (xy 90.915012 -59.581971)
			(xy 91.018552 -59.603842) (xy 91.120141 -59.633482) (xy 91.219198 -59.67072) (xy 91.315155 -59.715342)
			(xy 91.407462 -59.767094) (xy 91.495591 -59.825679) (xy 91.579037 -59.890761) (xy 91.657321 -59.961967)
			(xy 91.729996 -60.03889) (xy 91.796646 -60.12109) (xy 91.856888 -60.208094) (xy 91.910377 -60.299405)
			(xy 91.956808 -60.3945) (xy 91.995913 -60.492834) (xy 92.02747 -60.593845) (xy 92.051297 -60.696952)
			(xy 92.067258 -60.801566) (xy 92.075262 -60.907088) (xy 92.075762 -60.96) (xy 107.440737 -60.96)
			(xy 107.444742 -60.854251) (xy 107.456732 -60.749108) (xy 107.476641 -60.645173) (xy 107.504352 -60.543041)
			(xy 107.539709 -60.443297) (xy 107.582507 -60.346513) (xy 107.632503 -60.253243) (xy 107.68941 -60.164022)
			(xy 107.752901 -60.079359) (xy 107.822613 -59.999741) (xy 107.898147 -59.925623) (xy 107.97907 -59.85743)
			(xy 108.064919 -59.795552) (xy 108.155202 -59.740345) (xy 108.249401 -59.692123) (xy 108.346978 -59.651163)
			(xy 108.447373 -59.617701) (xy 108.550011 -59.591927) (xy 108.654304 -59.573989) (xy 108.759655 -59.56399)
			(xy 108.865461 -59.561987) (xy 108.971115 -59.567992) (xy 109.076012 -59.581971) (xy 109.179552 -59.603842)
			(xy 109.281141 -59.633482) (xy 109.380198 -59.67072) (xy 109.476155 -59.715342) (xy 109.568462 -59.767094)
			(xy 109.656591 -59.825679) (xy 109.740037 -59.890761) (xy 109.818321 -59.961967) (xy 109.890996 -60.03889)
			(xy 109.957646 -60.12109) (xy 110.017888 -60.208094) (xy 110.071377 -60.299405) (xy 110.117808 -60.3945)
			(xy 110.156913 -60.492834) (xy 110.18847 -60.593845) (xy 110.212297 -60.696952) (xy 110.228258 -60.801566)
			(xy 110.236262 -60.907088) (xy 110.236762 -60.96) (xy 118.616737 -60.96) (xy 118.620742 -60.854251)
			(xy 118.632732 -60.749108) (xy 118.652641 -60.645173) (xy 118.680352 -60.543041) (xy 118.715709 -60.443297)
			(xy 118.758507 -60.346513) (xy 118.808503 -60.253243) (xy 118.86541 -60.164022) (xy 118.928901 -60.079359)
			(xy 118.998613 -59.999741) (xy 119.074147 -59.925623) (xy 119.15507 -59.85743) (xy 119.240919 -59.795552)
			(xy 119.331202 -59.740345) (xy 119.425401 -59.692123) (xy 119.522978 -59.651163) (xy 119.623373 -59.617701)
			(xy 119.726011 -59.591927) (xy 119.830304 -59.573989) (xy 119.935655 -59.56399) (xy 120.041461 -59.561987)
			(xy 120.147115 -59.567992) (xy 120.252012 -59.581971) (xy 120.355552 -59.603842) (xy 120.457141 -59.633482)
			(xy 120.556198 -59.67072) (xy 120.652155 -59.715342) (xy 120.744462 -59.767094) (xy 120.832591 -59.825679)
			(xy 120.916037 -59.890761) (xy 120.994321 -59.961967) (xy 121.066996 -60.03889) (xy 121.133646 -60.12109)
			(xy 121.193888 -60.208094) (xy 121.247377 -60.299405) (xy 121.293808 -60.3945) (xy 121.332913 -60.492834)
			(xy 121.36447 -60.593845) (xy 121.388297 -60.696952) (xy 121.404258 -60.801566) (xy 121.412262 -60.907088)
			(xy 121.412762 -60.96) (xy 129.792737 -60.96) (xy 129.796742 -60.854251) (xy 129.808732 -60.749108)
			(xy 129.828641 -60.645173) (xy 129.856352 -60.543041) (xy 129.891709 -60.443297) (xy 129.934507 -60.346513)
			(xy 129.984503 -60.253243) (xy 130.04141 -60.164022) (xy 130.104901 -60.079359) (xy 130.174613 -59.999741)
			(xy 130.250147 -59.925623) (xy 130.33107 -59.85743) (xy 130.416919 -59.795552) (xy 130.507202 -59.740345)
			(xy 130.601401 -59.692123) (xy 130.698978 -59.651163) (xy 130.799373 -59.617701) (xy 130.902011 -59.591927)
			(xy 131.006304 -59.573989) (xy 131.111655 -59.56399) (xy 131.217461 -59.561987) (xy 131.323115 -59.567992)
			(xy 131.428012 -59.581971) (xy 131.531552 -59.603842) (xy 131.633141 -59.633482) (xy 131.732198 -59.67072)
			(xy 131.828155 -59.715342) (xy 131.920462 -59.767094) (xy 132.008591 -59.825679) (xy 132.092037 -59.890761)
			(xy 132.170321 -59.961967) (xy 132.242996 -60.03889) (xy 132.309646 -60.12109) (xy 132.369888 -60.208094)
			(xy 132.423377 -60.299405) (xy 132.469808 -60.3945) (xy 132.508913 -60.492834) (xy 132.54047 -60.593845)
			(xy 132.564297 -60.696952) (xy 132.580258 -60.801566) (xy 132.588262 -60.907088) (xy 132.588762 -60.96)
			(xy 145.540737 -60.96) (xy 145.544742 -60.854251) (xy 145.556732 -60.749108) (xy 145.576641 -60.645173)
			(xy 145.604352 -60.543041) (xy 145.639709 -60.443297) (xy 145.682507 -60.346513) (xy 145.732503 -60.253243)
			(xy 145.78941 -60.164022) (xy 145.852901 -60.079359) (xy 145.922613 -59.999741) (xy 145.998147 -59.925623)
			(xy 146.07907 -59.85743) (xy 146.164919 -59.795552) (xy 146.255202 -59.740345) (xy 146.349401 -59.692123)
			(xy 146.446978 -59.651163) (xy 146.547373 -59.617701) (xy 146.650011 -59.591927) (xy 146.754304 -59.573989)
			(xy 146.859655 -59.56399) (xy 146.965461 -59.561987) (xy 147.071115 -59.567992) (xy 147.176012 -59.581971)
			(xy 147.279552 -59.603842) (xy 147.381141 -59.633482) (xy 147.480198 -59.67072) (xy 147.576155 -59.715342)
			(xy 147.668462 -59.767094) (xy 147.756591 -59.825679) (xy 147.840037 -59.890761) (xy 147.918321 -59.961967)
			(xy 147.990996 -60.03889) (xy 148.057646 -60.12109) (xy 148.117888 -60.208094) (xy 148.171377 -60.299405)
			(xy 148.217808 -60.3945) (xy 148.256913 -60.492834) (xy 148.28847 -60.593845) (xy 148.312297 -60.696952)
			(xy 148.328258 -60.801566) (xy 148.336262 -60.907088) (xy 148.336762 -60.96) (xy 156.716737 -60.96)
			(xy 156.720742 -60.854251) (xy 156.732732 -60.749108) (xy 156.752641 -60.645173) (xy 156.780352 -60.543041)
			(xy 156.815709 -60.443297) (xy 156.858507 -60.346513) (xy 156.908503 -60.253243) (xy 156.96541 -60.164022)
			(xy 157.028901 -60.079359) (xy 157.098613 -59.999741) (xy 157.174147 -59.925623) (xy 157.25507 -59.85743)
			(xy 157.340919 -59.795552) (xy 157.431202 -59.740345) (xy 157.525401 -59.692123) (xy 157.622978 -59.651163)
			(xy 157.723373 -59.617701) (xy 157.826011 -59.591927) (xy 157.930304 -59.573989) (xy 158.035655 -59.56399)
			(xy 158.141461 -59.561987) (xy 158.247115 -59.567992) (xy 158.352012 -59.581971) (xy 158.455552 -59.603842)
			(xy 158.557141 -59.633482) (xy 158.656198 -59.67072) (xy 158.752155 -59.715342) (xy 158.844462 -59.767094)
			(xy 158.932591 -59.825679) (xy 159.016037 -59.890761) (xy 159.094321 -59.961967) (xy 159.166996 -60.03889)
			(xy 159.233646 -60.12109) (xy 159.293888 -60.208094) (xy 159.347377 -60.299405) (xy 159.393808 -60.3945)
			(xy 159.432913 -60.492834) (xy 159.46447 -60.593845) (xy 159.488297 -60.696952) (xy 159.504258 -60.801566)
			(xy 159.512262 -60.907088) (xy 159.512762 -60.96) (xy 167.892737 -60.96) (xy 167.896742 -60.854251)
			(xy 167.908732 -60.749108) (xy 167.928641 -60.645173) (xy 167.956352 -60.543041) (xy 167.991709 -60.443297)
			(xy 168.034507 -60.346513) (xy 168.084503 -60.253243) (xy 168.14141 -60.164022) (xy 168.204901 -60.079359)
			(xy 168.274613 -59.999741) (xy 168.350147 -59.925623) (xy 168.43107 -59.85743) (xy 168.516919 -59.795552)
			(xy 168.607202 -59.740345) (xy 168.701401 -59.692123) (xy 168.798978 -59.651163) (xy 168.899373 -59.617701)
			(xy 169.002011 -59.591927) (xy 169.106304 -59.573989) (xy 169.211655 -59.56399) (xy 169.317461 -59.561987)
			(xy 169.423115 -59.567992) (xy 169.528012 -59.581971) (xy 169.631552 -59.603842) (xy 169.733141 -59.633482)
			(xy 169.832198 -59.67072) (xy 169.928155 -59.715342) (xy 170.020462 -59.767094) (xy 170.108591 -59.825679)
			(xy 170.192037 -59.890761) (xy 170.270321 -59.961967) (xy 170.342996 -60.03889) (xy 170.409646 -60.12109)
			(xy 170.469888 -60.208094) (xy 170.523377 -60.299405) (xy 170.569808 -60.3945) (xy 170.608913 -60.492834)
			(xy 170.64047 -60.593845) (xy 170.664297 -60.696952) (xy 170.680258 -60.801566) (xy 170.688262 -60.907088)
			(xy 170.688762 -60.96) (xy 185.540911 -60.96) (xy 185.544916 -60.854251) (xy 185.556906 -60.749108)
			(xy 185.576815 -60.645173) (xy 185.604526 -60.543041) (xy 185.639883 -60.443297) (xy 185.682681 -60.346513)
			(xy 185.732677 -60.253243) (xy 185.789584 -60.164022) (xy 185.853075 -60.079359) (xy 185.922787 -59.999741)
			(xy 185.998321 -59.925623) (xy 186.079244 -59.85743) (xy 186.165093 -59.795552) (xy 186.255376 -59.740345)
			(xy 186.349575 -59.692123) (xy 186.447152 -59.651163) (xy 186.547547 -59.617701) (xy 186.650185 -59.591927)
			(xy 186.754478 -59.573989) (xy 186.859829 -59.56399) (xy 186.965635 -59.561987) (xy 187.071289 -59.567992)
			(xy 187.176186 -59.581971) (xy 187.279726 -59.603842) (xy 187.381315 -59.633482) (xy 187.480372 -59.67072)
			(xy 187.576329 -59.715342) (xy 187.668636 -59.767094) (xy 187.756765 -59.825679) (xy 187.840211 -59.890761)
			(xy 187.918495 -59.961967) (xy 187.99117 -60.03889) (xy 188.05782 -60.12109) (xy 188.118062 -60.208094)
			(xy 188.171551 -60.299405) (xy 188.217982 -60.3945) (xy 188.257087 -60.492834) (xy 188.288644 -60.593845)
			(xy 188.312471 -60.696952) (xy 188.328432 -60.801566) (xy 188.336436 -60.907088) (xy 188.336936 -60.96)
			(xy 196.716911 -60.96) (xy 196.720916 -60.854251) (xy 196.732906 -60.749108) (xy 196.752815 -60.645173)
			(xy 196.780526 -60.543041) (xy 196.815883 -60.443297) (xy 196.858681 -60.346513) (xy 196.908677 -60.253243)
			(xy 196.965584 -60.164022) (xy 197.029075 -60.079359) (xy 197.098787 -59.999741) (xy 197.174321 -59.925623)
			(xy 197.255244 -59.85743) (xy 197.341093 -59.795552) (xy 197.431376 -59.740345) (xy 197.525575 -59.692123)
			(xy 197.623152 -59.651163) (xy 197.723547 -59.617701) (xy 197.826185 -59.591927) (xy 197.930478 -59.573989)
			(xy 198.035829 -59.56399) (xy 198.141635 -59.561987) (xy 198.247289 -59.567992) (xy 198.352186 -59.581971)
			(xy 198.455726 -59.603842) (xy 198.557315 -59.633482) (xy 198.656372 -59.67072) (xy 198.752329 -59.715342)
			(xy 198.844636 -59.767094) (xy 198.932765 -59.825679) (xy 199.016211 -59.890761) (xy 199.094495 -59.961967)
			(xy 199.16717 -60.03889) (xy 199.23382 -60.12109) (xy 199.294062 -60.208094) (xy 199.347551 -60.299405)
			(xy 199.393982 -60.3945) (xy 199.433087 -60.492834) (xy 199.464644 -60.593845) (xy 199.488471 -60.696952)
			(xy 199.504432 -60.801566) (xy 199.512436 -60.907088) (xy 199.512936 -60.96) (xy 207.892911 -60.96)
			(xy 207.896916 -60.854251) (xy 207.908906 -60.749108) (xy 207.928815 -60.645173) (xy 207.956526 -60.543041)
			(xy 207.991883 -60.443297) (xy 208.034681 -60.346513) (xy 208.084677 -60.253243) (xy 208.141584 -60.164022)
			(xy 208.205075 -60.079359) (xy 208.274787 -59.999741) (xy 208.350321 -59.925623) (xy 208.431244 -59.85743)
			(xy 208.517093 -59.795552) (xy 208.607376 -59.740345) (xy 208.701575 -59.692123) (xy 208.799152 -59.651163)
			(xy 208.899547 -59.617701) (xy 209.002185 -59.591927) (xy 209.106478 -59.573989) (xy 209.211829 -59.56399)
			(xy 209.317635 -59.561987) (xy 209.423289 -59.567992) (xy 209.528186 -59.581971) (xy 209.631726 -59.603842)
			(xy 209.733315 -59.633482) (xy 209.832372 -59.67072) (xy 209.928329 -59.715342) (xy 210.020636 -59.767094)
			(xy 210.108765 -59.825679) (xy 210.192211 -59.890761) (xy 210.270495 -59.961967) (xy 210.34317 -60.03889)
			(xy 210.40982 -60.12109) (xy 210.470062 -60.208094) (xy 210.523551 -60.299405) (xy 210.569982 -60.3945)
			(xy 210.609087 -60.492834) (xy 210.640644 -60.593845) (xy 210.664471 -60.696952) (xy 210.680432 -60.801566)
			(xy 210.688436 -60.907088) (xy 210.688936 -60.96) (xy 210.688436 -61.012912) (xy 210.680432 -61.118434)
			(xy 210.664471 -61.223048) (xy 210.640644 -61.326155) (xy 210.609087 -61.427166) (xy 210.569982 -61.5255)
			(xy 210.523551 -61.620595) (xy 210.470062 -61.711906) (xy 210.40982 -61.79891) (xy 210.34317 -61.88111)
			(xy 210.270495 -61.958033) (xy 210.192211 -62.029239) (xy 210.108765 -62.094321) (xy 210.020636 -62.152906)
			(xy 209.928329 -62.204658) (xy 209.832372 -62.24928) (xy 209.733315 -62.286518) (xy 209.631726 -62.316158)
			(xy 209.528186 -62.338029) (xy 209.423289 -62.352008) (xy 209.317635 -62.358013) (xy 209.211829 -62.35601)
			(xy 209.106478 -62.346011) (xy 209.002185 -62.328073) (xy 208.899547 -62.302299) (xy 208.799152 -62.268837)
			(xy 208.701575 -62.227877) (xy 208.607376 -62.179655) (xy 208.517093 -62.124448) (xy 208.431244 -62.06257)
			(xy 208.350321 -61.994377) (xy 208.274787 -61.920259) (xy 208.205075 -61.840641) (xy 208.141584 -61.755978)
			(xy 208.084677 -61.666757) (xy 208.034681 -61.573487) (xy 207.991883 -61.476703) (xy 207.956526 -61.376959)
			(xy 207.928815 -61.274827) (xy 207.908906 -61.170892) (xy 207.896916 -61.065749) (xy 207.892911 -60.96)
			(xy 199.512936 -60.96) (xy 199.512436 -61.012912) (xy 199.504432 -61.118434) (xy 199.488471 -61.223048)
			(xy 199.464644 -61.326155) (xy 199.433087 -61.427166) (xy 199.393982 -61.5255) (xy 199.347551 -61.620595)
			(xy 199.294062 -61.711906) (xy 199.23382 -61.79891) (xy 199.16717 -61.88111) (xy 199.094495 -61.958033)
			(xy 199.016211 -62.029239) (xy 198.932765 -62.094321) (xy 198.844636 -62.152906) (xy 198.752329 -62.204658)
			(xy 198.656372 -62.24928) (xy 198.557315 -62.286518) (xy 198.455726 -62.316158) (xy 198.352186 -62.338029)
			(xy 198.247289 -62.352008) (xy 198.141635 -62.358013) (xy 198.035829 -62.35601) (xy 197.930478 -62.346011)
			(xy 197.826185 -62.328073) (xy 197.723547 -62.302299) (xy 197.623152 -62.268837) (xy 197.525575 -62.227877)
			(xy 197.431376 -62.179655) (xy 197.341093 -62.124448) (xy 197.255244 -62.06257) (xy 197.174321 -61.994377)
			(xy 197.098787 -61.920259) (xy 197.029075 -61.840641) (xy 196.965584 -61.755978) (xy 196.908677 -61.666757)
			(xy 196.858681 -61.573487) (xy 196.815883 -61.476703) (xy 196.780526 -61.376959) (xy 196.752815 -61.274827)
			(xy 196.732906 -61.170892) (xy 196.720916 -61.065749) (xy 196.716911 -60.96) (xy 188.336936 -60.96)
			(xy 188.336436 -61.012912) (xy 188.328432 -61.118434) (xy 188.312471 -61.223048) (xy 188.288644 -61.326155)
			(xy 188.257087 -61.427166) (xy 188.217982 -61.5255) (xy 188.171551 -61.620595) (xy 188.118062 -61.711906)
			(xy 188.05782 -61.79891) (xy 187.99117 -61.88111) (xy 187.918495 -61.958033) (xy 187.840211 -62.029239)
			(xy 187.756765 -62.094321) (xy 187.668636 -62.152906) (xy 187.576329 -62.204658) (xy 187.480372 -62.24928)
			(xy 187.381315 -62.286518) (xy 187.279726 -62.316158) (xy 187.176186 -62.338029) (xy 187.071289 -62.352008)
			(xy 186.965635 -62.358013) (xy 186.859829 -62.35601) (xy 186.754478 -62.346011) (xy 186.650185 -62.328073)
			(xy 186.547547 -62.302299) (xy 186.447152 -62.268837) (xy 186.349575 -62.227877) (xy 186.255376 -62.179655)
			(xy 186.165093 -62.124448) (xy 186.079244 -62.06257) (xy 185.998321 -61.994377) (xy 185.922787 -61.920259)
			(xy 185.853075 -61.840641) (xy 185.789584 -61.755978) (xy 185.732677 -61.666757) (xy 185.682681 -61.573487)
			(xy 185.639883 -61.476703) (xy 185.604526 -61.376959) (xy 185.576815 -61.274827) (xy 185.556906 -61.170892)
			(xy 185.544916 -61.065749) (xy 185.540911 -60.96) (xy 170.688762 -60.96) (xy 170.688262 -61.012912)
			(xy 170.680258 -61.118434) (xy 170.664297 -61.223048) (xy 170.64047 -61.326155) (xy 170.608913 -61.427166)
			(xy 170.569808 -61.5255) (xy 170.523377 -61.620595) (xy 170.469888 -61.711906) (xy 170.409646 -61.79891)
			(xy 170.342996 -61.88111) (xy 170.270321 -61.958033) (xy 170.192037 -62.029239) (xy 170.108591 -62.094321)
			(xy 170.020462 -62.152906) (xy 169.928155 -62.204658) (xy 169.832198 -62.24928) (xy 169.733141 -62.286518)
			(xy 169.631552 -62.316158) (xy 169.528012 -62.338029) (xy 169.423115 -62.352008) (xy 169.317461 -62.358013)
			(xy 169.211655 -62.35601) (xy 169.106304 -62.346011) (xy 169.002011 -62.328073) (xy 168.899373 -62.302299)
			(xy 168.798978 -62.268837) (xy 168.701401 -62.227877) (xy 168.607202 -62.179655) (xy 168.516919 -62.124448)
			(xy 168.43107 -62.06257) (xy 168.350147 -61.994377) (xy 168.274613 -61.920259) (xy 168.204901 -61.840641)
			(xy 168.14141 -61.755978) (xy 168.084503 -61.666757) (xy 168.034507 -61.573487) (xy 167.991709 -61.476703)
			(xy 167.956352 -61.376959) (xy 167.928641 -61.274827) (xy 167.908732 -61.170892) (xy 167.896742 -61.065749)
			(xy 167.892737 -60.96) (xy 159.512762 -60.96) (xy 159.512262 -61.012912) (xy 159.504258 -61.118434)
			(xy 159.488297 -61.223048) (xy 159.46447 -61.326155) (xy 159.432913 -61.427166) (xy 159.393808 -61.5255)
			(xy 159.347377 -61.620595) (xy 159.293888 -61.711906) (xy 159.233646 -61.79891) (xy 159.166996 -61.88111)
			(xy 159.094321 -61.958033) (xy 159.016037 -62.029239) (xy 158.932591 -62.094321) (xy 158.844462 -62.152906)
			(xy 158.752155 -62.204658) (xy 158.656198 -62.24928) (xy 158.557141 -62.286518) (xy 158.455552 -62.316158)
			(xy 158.352012 -62.338029) (xy 158.247115 -62.352008) (xy 158.141461 -62.358013) (xy 158.035655 -62.35601)
			(xy 157.930304 -62.346011) (xy 157.826011 -62.328073) (xy 157.723373 -62.302299) (xy 157.622978 -62.268837)
			(xy 157.525401 -62.227877) (xy 157.431202 -62.179655) (xy 157.340919 -62.124448) (xy 157.25507 -62.06257)
			(xy 157.174147 -61.994377) (xy 157.098613 -61.920259) (xy 157.028901 -61.840641) (xy 156.96541 -61.755978)
			(xy 156.908503 -61.666757) (xy 156.858507 -61.573487) (xy 156.815709 -61.476703) (xy 156.780352 -61.376959)
			(xy 156.752641 -61.274827) (xy 156.732732 -61.170892) (xy 156.720742 -61.065749) (xy 156.716737 -60.96)
			(xy 148.336762 -60.96) (xy 148.336262 -61.012912) (xy 148.328258 -61.118434) (xy 148.312297 -61.223048)
			(xy 148.28847 -61.326155) (xy 148.256913 -61.427166) (xy 148.217808 -61.5255) (xy 148.171377 -61.620595)
			(xy 148.117888 -61.711906) (xy 148.057646 -61.79891) (xy 147.990996 -61.88111) (xy 147.918321 -61.958033)
			(xy 147.840037 -62.029239) (xy 147.756591 -62.094321) (xy 147.668462 -62.152906) (xy 147.576155 -62.204658)
			(xy 147.480198 -62.24928) (xy 147.381141 -62.286518) (xy 147.279552 -62.316158) (xy 147.176012 -62.338029)
			(xy 147.071115 -62.352008) (xy 146.965461 -62.358013) (xy 146.859655 -62.35601) (xy 146.754304 -62.346011)
			(xy 146.650011 -62.328073) (xy 146.547373 -62.302299) (xy 146.446978 -62.268837) (xy 146.349401 -62.227877)
			(xy 146.255202 -62.179655) (xy 146.164919 -62.124448) (xy 146.07907 -62.06257) (xy 145.998147 -61.994377)
			(xy 145.922613 -61.920259) (xy 145.852901 -61.840641) (xy 145.78941 -61.755978) (xy 145.732503 -61.666757)
			(xy 145.682507 -61.573487) (xy 145.639709 -61.476703) (xy 145.604352 -61.376959) (xy 145.576641 -61.274827)
			(xy 145.556732 -61.170892) (xy 145.544742 -61.065749) (xy 145.540737 -60.96) (xy 132.588762 -60.96)
			(xy 132.588262 -61.012912) (xy 132.580258 -61.118434) (xy 132.564297 -61.223048) (xy 132.54047 -61.326155)
			(xy 132.508913 -61.427166) (xy 132.469808 -61.5255) (xy 132.423377 -61.620595) (xy 132.369888 -61.711906)
			(xy 132.309646 -61.79891) (xy 132.242996 -61.88111) (xy 132.170321 -61.958033) (xy 132.092037 -62.029239)
			(xy 132.008591 -62.094321) (xy 131.920462 -62.152906) (xy 131.828155 -62.204658) (xy 131.732198 -62.24928)
			(xy 131.633141 -62.286518) (xy 131.531552 -62.316158) (xy 131.428012 -62.338029) (xy 131.323115 -62.352008)
			(xy 131.217461 -62.358013) (xy 131.111655 -62.35601) (xy 131.006304 -62.346011) (xy 130.902011 -62.328073)
			(xy 130.799373 -62.302299) (xy 130.698978 -62.268837) (xy 130.601401 -62.227877) (xy 130.507202 -62.179655)
			(xy 130.416919 -62.124448) (xy 130.33107 -62.06257) (xy 130.250147 -61.994377) (xy 130.174613 -61.920259)
			(xy 130.104901 -61.840641) (xy 130.04141 -61.755978) (xy 129.984503 -61.666757) (xy 129.934507 -61.573487)
			(xy 129.891709 -61.476703) (xy 129.856352 -61.376959) (xy 129.828641 -61.274827) (xy 129.808732 -61.170892)
			(xy 129.796742 -61.065749) (xy 129.792737 -60.96) (xy 121.412762 -60.96) (xy 121.412262 -61.012912)
			(xy 121.404258 -61.118434) (xy 121.388297 -61.223048) (xy 121.36447 -61.326155) (xy 121.332913 -61.427166)
			(xy 121.293808 -61.5255) (xy 121.247377 -61.620595) (xy 121.193888 -61.711906) (xy 121.133646 -61.79891)
			(xy 121.066996 -61.88111) (xy 120.994321 -61.958033) (xy 120.916037 -62.029239) (xy 120.832591 -62.094321)
			(xy 120.744462 -62.152906) (xy 120.652155 -62.204658) (xy 120.556198 -62.24928) (xy 120.457141 -62.286518)
			(xy 120.355552 -62.316158) (xy 120.252012 -62.338029) (xy 120.147115 -62.352008) (xy 120.041461 -62.358013)
			(xy 119.935655 -62.35601) (xy 119.830304 -62.346011) (xy 119.726011 -62.328073) (xy 119.623373 -62.302299)
			(xy 119.522978 -62.268837) (xy 119.425401 -62.227877) (xy 119.331202 -62.179655) (xy 119.240919 -62.124448)
			(xy 119.15507 -62.06257) (xy 119.074147 -61.994377) (xy 118.998613 -61.920259) (xy 118.928901 -61.840641)
			(xy 118.86541 -61.755978) (xy 118.808503 -61.666757) (xy 118.758507 -61.573487) (xy 118.715709 -61.476703)
			(xy 118.680352 -61.376959) (xy 118.652641 -61.274827) (xy 118.632732 -61.170892) (xy 118.620742 -61.065749)
			(xy 118.616737 -60.96) (xy 110.236762 -60.96) (xy 110.236262 -61.012912) (xy 110.228258 -61.118434)
			(xy 110.212297 -61.223048) (xy 110.18847 -61.326155) (xy 110.156913 -61.427166) (xy 110.117808 -61.5255)
			(xy 110.071377 -61.620595) (xy 110.017888 -61.711906) (xy 109.957646 -61.79891) (xy 109.890996 -61.88111)
			(xy 109.818321 -61.958033) (xy 109.740037 -62.029239) (xy 109.656591 -62.094321) (xy 109.568462 -62.152906)
			(xy 109.476155 -62.204658) (xy 109.380198 -62.24928) (xy 109.281141 -62.286518) (xy 109.179552 -62.316158)
			(xy 109.076012 -62.338029) (xy 108.971115 -62.352008) (xy 108.865461 -62.358013) (xy 108.759655 -62.35601)
			(xy 108.654304 -62.346011) (xy 108.550011 -62.328073) (xy 108.447373 -62.302299) (xy 108.346978 -62.268837)
			(xy 108.249401 -62.227877) (xy 108.155202 -62.179655) (xy 108.064919 -62.124448) (xy 107.97907 -62.06257)
			(xy 107.898147 -61.994377) (xy 107.822613 -61.920259) (xy 107.752901 -61.840641) (xy 107.68941 -61.755978)
			(xy 107.632503 -61.666757) (xy 107.582507 -61.573487) (xy 107.539709 -61.476703) (xy 107.504352 -61.376959)
			(xy 107.476641 -61.274827) (xy 107.456732 -61.170892) (xy 107.444742 -61.065749) (xy 107.440737 -60.96)
			(xy 92.075762 -60.96) (xy 92.075262 -61.012912) (xy 92.067258 -61.118434) (xy 92.051297 -61.223048)
			(xy 92.02747 -61.326155) (xy 91.995913 -61.427166) (xy 91.956808 -61.5255) (xy 91.910377 -61.620595)
			(xy 91.856888 -61.711906) (xy 91.796646 -61.79891) (xy 91.729996 -61.88111) (xy 91.657321 -61.958033)
			(xy 91.579037 -62.029239) (xy 91.495591 -62.094321) (xy 91.407462 -62.152906) (xy 91.315155 -62.204658)
			(xy 91.219198 -62.24928) (xy 91.120141 -62.286518) (xy 91.018552 -62.316158) (xy 90.915012 -62.338029)
			(xy 90.810115 -62.352008) (xy 90.704461 -62.358013) (xy 90.598655 -62.35601) (xy 90.493304 -62.346011)
			(xy 90.389011 -62.328073) (xy 90.286373 -62.302299) (xy 90.185978 -62.268837) (xy 90.088401 -62.227877)
			(xy 89.994202 -62.179655) (xy 89.903919 -62.124448) (xy 89.81807 -62.06257) (xy 89.737147 -61.994377)
			(xy 89.661613 -61.920259) (xy 89.591901 -61.840641) (xy 89.52841 -61.755978) (xy 89.471503 -61.666757)
			(xy 89.421507 -61.573487) (xy 89.378709 -61.476703) (xy 89.343352 -61.376959) (xy 89.315641 -61.274827)
			(xy 89.295732 -61.170892) (xy 89.283742 -61.065749) (xy 89.279737 -60.96) (xy 80.772762 -60.96) (xy 80.772262 -61.012912)
			(xy 80.764258 -61.118434) (xy 80.748297 -61.223048) (xy 80.72447 -61.326155) (xy 80.692913 -61.427166)
			(xy 80.653808 -61.5255) (xy 80.607377 -61.620595) (xy 80.553888 -61.711906) (xy 80.493646 -61.79891)
			(xy 80.426996 -61.88111) (xy 80.354321 -61.958033) (xy 80.276037 -62.029239) (xy 80.192591 -62.094321)
			(xy 80.104462 -62.152906) (xy 80.012155 -62.204658) (xy 79.916198 -62.24928) (xy 79.817141 -62.286518)
			(xy 79.715552 -62.316158) (xy 79.612012 -62.338029) (xy 79.507115 -62.352008) (xy 79.401461 -62.358013)
			(xy 79.295655 -62.35601) (xy 79.190304 -62.346011) (xy 79.086011 -62.328073) (xy 78.983373 -62.302299)
			(xy 78.882978 -62.268837) (xy 78.785401 -62.227877) (xy 78.691202 -62.179655) (xy 78.600919 -62.124448)
			(xy 78.51507 -62.06257) (xy 78.434147 -61.994377) (xy 78.358613 -61.920259) (xy 78.288901 -61.840641)
			(xy 78.22541 -61.755978) (xy 78.168503 -61.666757) (xy 78.118507 -61.573487) (xy 78.075709 -61.476703)
			(xy 78.040352 -61.376959) (xy 78.012641 -61.274827) (xy 77.992732 -61.170892) (xy 77.980742 -61.065749)
			(xy 77.976737 -60.96) (xy 69.469762 -60.96) (xy 69.469262 -61.012912) (xy 69.461258 -61.118434) (xy 69.445297 -61.223048)
			(xy 69.42147 -61.326155) (xy 69.389913 -61.427166) (xy 69.350808 -61.5255) (xy 69.304377 -61.620595)
			(xy 69.250888 -61.711906) (xy 69.190646 -61.79891) (xy 69.123996 -61.88111) (xy 69.051321 -61.958033)
			(xy 68.973037 -62.029239) (xy 68.889591 -62.094321) (xy 68.801462 -62.152906) (xy 68.709155 -62.204658)
			(xy 68.613198 -62.24928) (xy 68.514141 -62.286518) (xy 68.412552 -62.316158) (xy 68.309012 -62.338029)
			(xy 68.204115 -62.352008) (xy 68.098461 -62.358013) (xy 67.992655 -62.35601) (xy 67.887304 -62.346011)
			(xy 67.783011 -62.328073) (xy 67.680373 -62.302299) (xy 67.579978 -62.268837) (xy 67.482401 -62.227877)
			(xy 67.388202 -62.179655) (xy 67.297919 -62.124448) (xy 67.21207 -62.06257) (xy 67.131147 -61.994377)
			(xy 67.055613 -61.920259) (xy 66.985901 -61.840641) (xy 66.92241 -61.755978) (xy 66.865503 -61.666757)
			(xy 66.815507 -61.573487) (xy 66.772709 -61.476703) (xy 66.737352 -61.376959) (xy 66.709641 -61.274827)
			(xy 66.689732 -61.170892) (xy 66.677742 -61.065749) (xy 66.673737 -60.96) (xy 0.509016 -60.96) (xy 0.509016 -62.203781)
			(xy 38.440102 -62.203781) (xy 38.440102 -62.119059) (xy 38.448155 -62.034722) (xy 38.464189 -61.951532)
			(xy 38.488057 -61.870242) (xy 38.519545 -61.79159) (xy 38.558367 -61.716287) (xy 38.60417 -61.645015)
			(xy 38.656541 -61.578419) (xy 38.715006 -61.517104) (xy 38.779034 -61.461623) (xy 38.848046 -61.41248)
			(xy 38.921416 -61.37012) (xy 38.998481 -61.334925) (xy 39.078543 -61.307216) (xy 39.160876 -61.287242)
			(xy 39.244735 -61.275185) (xy 39.32936 -61.271154) (xy 39.413985 -61.275185) (xy 39.497844 -61.287242)
			(xy 39.580177 -61.307216) (xy 39.660239 -61.334925) (xy 39.737304 -61.37012) (xy 39.810674 -61.41248)
			(xy 39.879686 -61.461623) (xy 39.943714 -61.517104) (xy 40.002179 -61.578419) (xy 40.05455 -61.645015)
			(xy 40.100353 -61.716287) (xy 40.139175 -61.79159) (xy 40.170663 -61.870242) (xy 40.194531 -61.951532)
			(xy 40.210565 -62.034722) (xy 40.218618 -62.119059) (xy 40.219122 -62.16142) (xy 40.218618 -62.203781)
			(xy 40.210565 -62.288118) (xy 40.194531 -62.371308) (xy 40.170663 -62.452598) (xy 40.139175 -62.53125)
			(xy 40.100353 -62.606553) (xy 40.05455 -62.677825) (xy 40.002179 -62.744421) (xy 39.943714 -62.805736)
			(xy 39.879686 -62.861217) (xy 39.810674 -62.91036) (xy 39.737304 -62.95272) (xy 39.660239 -62.987915)
			(xy 39.580177 -63.015624) (xy 39.497844 -63.035598) (xy 39.413985 -63.047655) (xy 39.32936 -63.051687)
			(xy 39.244735 -63.047655) (xy 39.160876 -63.035598) (xy 39.078543 -63.015624) (xy 38.998481 -62.987915)
			(xy 38.921416 -62.95272) (xy 38.848046 -62.91036) (xy 38.779034 -62.861217) (xy 38.715006 -62.805736)
			(xy 38.656541 -62.744421) (xy 38.60417 -62.677825) (xy 38.558367 -62.606553) (xy 38.519545 -62.53125)
			(xy 38.488057 -62.452598) (xy 38.464189 -62.371308) (xy 38.448155 -62.288118) (xy 38.440102 -62.203781)
			(xy 0.509016 -62.203781) (xy 0.509016 -66.43624) (xy 26.694892 -66.43624) (xy 26.695489 -66.389845)
			(xy 26.70513 -66.297557) (xy 26.724322 -66.206773) (xy 26.752856 -66.118479) (xy 26.771092 -66.075814)
			(xy 26.774874 -66.065864) (xy 26.774889 -66.044608) (xy 26.771092 -66.034666) (xy 26.75286 -65.991998)
			(xy 26.724313 -65.903708) (xy 26.705116 -65.812925) (xy 26.695479 -65.720636) (xy 26.694892 -65.67424)
			(xy 26.695489 -65.627845) (xy 26.70513 -65.535557) (xy 26.724322 -65.444773) (xy 26.752856 -65.356479)
			(xy 26.771092 -65.313814) (xy 26.774874 -65.303864) (xy 26.774889 -65.282608) (xy 26.771092 -65.272666)
			(xy 26.75286 -65.229998) (xy 26.724313 -65.141708) (xy 26.705116 -65.050925) (xy 26.695479 -64.958636)
			(xy 26.694892 -64.91224) (xy 26.69539 -64.871137) (xy 26.702972 -64.789283) (xy 26.718074 -64.708477)
			(xy 26.740567 -64.629409) (xy 26.77026 -64.552754) (xy 26.8069 -64.479166) (xy 26.850173 -64.409273)
			(xy 26.899711 -64.343671) (xy 26.955091 -64.282919) (xy 27.01584 -64.227537) (xy 27.08144 -64.177996)
			(xy 27.151331 -64.13472) (xy 27.224918 -64.098077) (xy 27.301571 -64.06838) (xy 27.380638 -64.045883)
			(xy 27.461443 -64.030777) (xy 27.543298 -64.023192) (xy 27.5844 -64.022732) (xy 27.630796 -64.023311)
			(xy 27.723084 -64.032957) (xy 27.813868 -64.052154) (xy 27.902161 -64.080693) (xy 27.944826 -64.098932)
			(xy 27.954768 -64.102738) (xy 27.976032 -64.102738) (xy 27.985974 -64.098932) (xy 28.028637 -64.08069)
			(xy 28.116929 -64.052144) (xy 28.207714 -64.032951) (xy 28.300004 -64.023317) (xy 28.3464 -64.022732)
			(xy 28.387504 -64.023152) (xy 28.469362 -64.030738) (xy 28.550171 -64.045844) (xy 28.629241 -64.068342)
			(xy 28.705898 -64.09804) (xy 28.779488 -64.134685) (xy 28.849383 -64.177963) (xy 28.914986 -64.227506)
			(xy 28.975737 -64.282891) (xy 29.03112 -64.343645) (xy 29.08066 -64.40925) (xy 29.123935 -64.479147)
			(xy 29.160576 -64.552738) (xy 29.190271 -64.629397) (xy 29.212765 -64.708468) (xy 29.227868 -64.789277)
			(xy 29.23545 -64.871136) (xy 29.235908 -64.91224) (xy 29.235304 -64.958635) (xy 29.225665 -65.050923)
			(xy 29.206475 -65.141707) (xy 29.177943 -65.230001) (xy 29.159708 -65.272666) (xy 29.155879 -65.282601)
			(xy 29.155894 -65.303871) (xy 29.159708 -65.313814) (xy 29.177966 -65.356471) (xy 29.206507 -65.444765)
			(xy 29.224945 -65.532) (xy 268.350492 -65.532) (xy 268.351075 -65.485604) (xy 268.36072 -65.393316)
			(xy 268.379916 -65.302532) (xy 268.408454 -65.214239) (xy 268.426692 -65.171574) (xy 268.430498 -65.161632)
			(xy 268.430498 -65.140368) (xy 268.426692 -65.130426) (xy 268.408447 -65.087764) (xy 268.379903 -64.999471)
			(xy 268.36071 -64.908686) (xy 268.351077 -64.816396) (xy 268.350492 -64.77) (xy 268.351075 -64.723604)
			(xy 268.36072 -64.631316) (xy 268.379916 -64.540532) (xy 268.408454 -64.452239) (xy 268.426692 -64.409574)
			(xy 268.430498 -64.399632) (xy 268.430498 -64.378368) (xy 268.426692 -64.368426) (xy 268.408447 -64.325764)
			(xy 268.379903 -64.237471) (xy 268.36071 -64.146686) (xy 268.351077 -64.054396) (xy 268.350492 -64.008)
			(xy 268.351075 -63.961604) (xy 268.36072 -63.869316) (xy 268.379916 -63.778532) (xy 268.408454 -63.690239)
			(xy 268.426692 -63.647574) (xy 268.430498 -63.637632) (xy 268.430498 -63.616368) (xy 268.426692 -63.606426)
			(xy 268.408447 -63.563764) (xy 268.379903 -63.475471) (xy 268.36071 -63.384686) (xy 268.351077 -63.292396)
			(xy 268.350492 -63.246) (xy 268.351075 -63.199604) (xy 268.36072 -63.107316) (xy 268.379916 -63.016532)
			(xy 268.408454 -62.928239) (xy 268.426692 -62.885574) (xy 268.430498 -62.875632) (xy 268.430498 -62.854368)
			(xy 268.426692 -62.844426) (xy 268.408447 -62.801764) (xy 268.379903 -62.713471) (xy 268.36071 -62.622686)
			(xy 268.351077 -62.530396) (xy 268.350492 -62.484) (xy 268.351075 -62.437604) (xy 268.36072 -62.345316)
			(xy 268.379916 -62.254532) (xy 268.408454 -62.166239) (xy 268.426692 -62.123574) (xy 268.430498 -62.113632)
			(xy 268.430498 -62.092368) (xy 268.426692 -62.082426) (xy 268.408447 -62.039764) (xy 268.379903 -61.951471)
			(xy 268.36071 -61.860686) (xy 268.351077 -61.768396) (xy 268.350492 -61.722) (xy 268.350967 -61.680898)
			(xy 268.358552 -61.599043) (xy 268.373657 -61.518238) (xy 268.396153 -61.439171) (xy 268.425849 -61.362517)
			(xy 268.462491 -61.28893) (xy 268.505766 -61.219038) (xy 268.555306 -61.153437) (xy 268.610687 -61.092687)
			(xy 268.671437 -61.037306) (xy 268.737038 -60.987766) (xy 268.80693 -60.944491) (xy 268.880517 -60.907849)
			(xy 268.957171 -60.878153) (xy 269.036238 -60.855657) (xy 269.117043 -60.840552) (xy 269.198898 -60.832967)
			(xy 269.24 -60.832492) (xy 269.286396 -60.833075) (xy 269.378684 -60.84272) (xy 269.469468 -60.861916)
			(xy 269.557761 -60.890454) (xy 269.600426 -60.908692) (xy 269.610368 -60.912498) (xy 269.631632 -60.912498)
			(xy 269.641574 -60.908692) (xy 269.684236 -60.890447) (xy 269.772529 -60.861903) (xy 269.863314 -60.84271)
			(xy 269.955604 -60.833077) (xy 270.002 -60.832492) (xy 270.048396 -60.833075) (xy 270.140684 -60.84272)
			(xy 270.231468 -60.861916) (xy 270.319761 -60.890454) (xy 270.362426 -60.908692) (xy 270.372368 -60.912498)
			(xy 270.393632 -60.912498) (xy 270.403574 -60.908692) (xy 270.446236 -60.890447) (xy 270.534529 -60.861903)
			(xy 270.625314 -60.84271) (xy 270.717604 -60.833077) (xy 270.764 -60.832492) (xy 270.810396 -60.833075)
			(xy 270.902684 -60.84272) (xy 270.993468 -60.861916) (xy 271.081761 -60.890454) (xy 271.124426 -60.908692)
			(xy 271.134368 -60.912498) (xy 271.155632 -60.912498) (xy 271.165574 -60.908692) (xy 271.208236 -60.890447)
			(xy 271.296529 -60.861903) (xy 271.387314 -60.84271) (xy 271.479604 -60.833077) (xy 271.526 -60.832492)
			(xy 271.572396 -60.833075) (xy 271.664684 -60.84272) (xy 271.755468 -60.861916) (xy 271.843761 -60.890454)
			(xy 271.886426 -60.908692) (xy 271.896368 -60.912498) (xy 271.917632 -60.912498) (xy 271.927574 -60.908692)
			(xy 271.970236 -60.890447) (xy 272.058529 -60.861903) (xy 272.149314 -60.84271) (xy 272.241604 -60.833077)
			(xy 272.288 -60.832492) (xy 272.329102 -60.832967) (xy 272.410957 -60.840552) (xy 272.491762 -60.855657)
			(xy 272.570829 -60.878153) (xy 272.647483 -60.907849) (xy 272.72107 -60.944491) (xy 272.790962 -60.987766)
			(xy 272.856563 -61.037306) (xy 272.917313 -61.092687) (xy 272.972694 -61.153437) (xy 273.022234 -61.219038)
			(xy 273.065509 -61.28893) (xy 273.102151 -61.362517) (xy 273.131847 -61.439171) (xy 273.154343 -61.518238)
			(xy 273.169448 -61.599043) (xy 273.177033 -61.680898) (xy 273.177508 -61.722) (xy 273.176925 -61.768396)
			(xy 273.16728 -61.860684) (xy 273.148084 -61.951468) (xy 273.119546 -62.039761) (xy 273.101308 -62.082426)
			(xy 273.097502 -62.092368) (xy 273.097502 -62.113632) (xy 273.101308 -62.123574) (xy 273.119553 -62.166236)
			(xy 273.148097 -62.254529) (xy 273.16729 -62.345314) (xy 273.176923 -62.437604) (xy 273.177508 -62.484)
			(xy 273.177033 -62.525102) (xy 273.169448 -62.606957) (xy 273.154343 -62.687762) (xy 273.131847 -62.766829)
			(xy 273.102151 -62.843483) (xy 273.065509 -62.91707) (xy 273.022234 -62.986962) (xy 272.972694 -63.052563)
			(xy 272.917313 -63.113313) (xy 272.856563 -63.168694) (xy 272.790962 -63.218234) (xy 272.72107 -63.261509)
			(xy 272.647483 -63.298151) (xy 272.570829 -63.327847) (xy 272.491762 -63.350343) (xy 272.410957 -63.365448)
			(xy 272.329102 -63.373033) (xy 272.288 -63.373508) (xy 272.241604 -63.372925) (xy 272.149316 -63.36328)
			(xy 272.058532 -63.344084) (xy 271.970239 -63.315546) (xy 271.927574 -63.297308) (xy 271.917632 -63.293502)
			(xy 271.896368 -63.293502) (xy 271.886426 -63.297308) (xy 271.853507 -63.311537) (xy 271.785822 -63.335257)
			(xy 271.716442 -63.353437) (xy 271.681194 -63.360046) (xy 271.67107 -63.362344) (xy 271.653749 -63.373749)
			(xy 271.642344 -63.39107) (xy 271.640046 -63.401194) (xy 271.633416 -63.436437) (xy 271.61522 -63.50581)
			(xy 271.591513 -63.573498) (xy 271.577308 -63.606426) (xy 271.573502 -63.616368) (xy 271.573502 -63.637632)
			(xy 271.577308 -63.647574) (xy 271.591537 -63.680493) (xy 271.615257 -63.748178) (xy 271.633437 -63.817558)
			(xy 271.640046 -63.852806) (xy 271.642344 -63.86293) (xy 271.653749 -63.880251) (xy 271.67107 -63.891656)
			(xy 271.681194 -63.893954) (xy 271.716437 -63.900584) (xy 271.78581 -63.91878) (xy 271.853498 -63.942487)
			(xy 271.886426 -63.956692) (xy 271.896368 -63.960498) (xy 271.917632 -63.960498) (xy 271.927574 -63.956692)
			(xy 271.970236 -63.938447) (xy 272.058529 -63.909903) (xy 272.149314 -63.89071) (xy 272.241604 -63.881077)
			(xy 272.288 -63.880492) (xy 272.329102 -63.880967) (xy 272.410957 -63.888552) (xy 272.491762 -63.903657)
			(xy 272.570829 -63.926153) (xy 272.647483 -63.955849) (xy 272.72107 -63.992491) (xy 272.790962 -64.035766)
			(xy 272.856563 -64.085306) (xy 272.917313 -64.140687) (xy 272.972694 -64.201437) (xy 273.022234 -64.267038)
			(xy 273.065509 -64.33693) (xy 273.102151 -64.410517) (xy 273.131847 -64.487171) (xy 273.154343 -64.566238)
			(xy 273.169448 -64.647043) (xy 273.177033 -64.728898) (xy 273.177508 -64.77) (xy 273.176925 -64.816396)
			(xy 273.16728 -64.908684) (xy 273.148084 -64.999468) (xy 273.119546 -65.087761) (xy 273.101308 -65.130426)
			(xy 273.097502 -65.140368) (xy 273.097502 -65.161632) (xy 273.101308 -65.171574) (xy 273.119553 -65.214236)
			(xy 273.148097 -65.302529) (xy 273.16729 -65.393314) (xy 273.176923 -65.485604) (xy 273.177508 -65.532)
			(xy 273.177033 -65.573102) (xy 273.169448 -65.654957) (xy 273.154343 -65.735762) (xy 273.131847 -65.814829)
			(xy 273.102151 -65.891483) (xy 273.065509 -65.96507) (xy 273.022234 -66.034962) (xy 272.972694 -66.100563)
			(xy 272.917313 -66.161313) (xy 272.856563 -66.216694) (xy 272.790962 -66.266234) (xy 272.72107 -66.309509)
			(xy 272.647483 -66.346151) (xy 272.570829 -66.375847) (xy 272.491762 -66.398343) (xy 272.410957 -66.413448)
			(xy 272.329102 -66.421033) (xy 272.288 -66.421508) (xy 272.241604 -66.420925) (xy 272.149316 -66.41128)
			(xy 272.058532 -66.392084) (xy 271.970239 -66.363546) (xy 271.927574 -66.345308) (xy 271.917632 -66.341502)
			(xy 271.896368 -66.341502) (xy 271.886426 -66.345308) (xy 271.843764 -66.363553) (xy 271.755471 -66.392097)
			(xy 271.664686 -66.41129) (xy 271.572396 -66.420923) (xy 271.526 -66.421508) (xy 271.479604 -66.420925)
			(xy 271.387316 -66.41128) (xy 271.296532 -66.392084) (xy 271.208239 -66.363546) (xy 271.165574 -66.345308)
			(xy 271.155632 -66.341502) (xy 271.134368 -66.341502) (xy 271.124426 -66.345308) (xy 271.081764 -66.363553)
			(xy 270.993471 -66.392097) (xy 270.902686 -66.41129) (xy 270.810396 -66.420923) (xy 270.764 -66.421508)
			(xy 270.717604 -66.420925) (xy 270.625316 -66.41128) (xy 270.534532 -66.392084) (xy 270.446239 -66.363546)
			(xy 270.403574 -66.345308) (xy 270.393632 -66.341502) (xy 270.372368 -66.341502) (xy 270.362426 -66.345308)
			(xy 270.319764 -66.363553) (xy 270.231471 -66.392097) (xy 270.140686 -66.41129) (xy 270.048396 -66.420923)
			(xy 270.002 -66.421508) (xy 269.955604 -66.420925) (xy 269.863316 -66.41128) (xy 269.772532 -66.392084)
			(xy 269.684239 -66.363546) (xy 269.641574 -66.345308) (xy 269.631632 -66.341502) (xy 269.610368 -66.341502)
			(xy 269.600426 -66.345308) (xy 269.557764 -66.363553) (xy 269.469471 -66.392097) (xy 269.378686 -66.41129)
			(xy 269.286396 -66.420923) (xy 269.24 -66.421508) (xy 269.198898 -66.421033) (xy 269.117043 -66.413448)
			(xy 269.036238 -66.398343) (xy 268.957171 -66.375847) (xy 268.880517 -66.346151) (xy 268.80693 -66.309509)
			(xy 268.737038 -66.266234) (xy 268.671437 -66.216694) (xy 268.610687 -66.161313) (xy 268.555306 -66.100563)
			(xy 268.505766 -66.034962) (xy 268.462491 -65.96507) (xy 268.425849 -65.891483) (xy 268.396153 -65.814829)
			(xy 268.373657 -65.735762) (xy 268.358552 -65.654957) (xy 268.350967 -65.573102) (xy 268.350492 -65.532)
			(xy 29.224945 -65.532) (xy 29.225696 -65.535552) (xy 29.235325 -65.627843) (xy 29.235908 -65.67424)
			(xy 29.235304 -65.720635) (xy 29.225665 -65.812923) (xy 29.206475 -65.903707) (xy 29.177943 -65.992001)
			(xy 29.159708 -66.034666) (xy 29.155879 -66.044601) (xy 29.155894 -66.065871) (xy 29.159708 -66.075814)
			(xy 29.177966 -66.118471) (xy 29.206507 -66.206765) (xy 29.225696 -66.297552) (xy 29.235325 -66.389843)
			(xy 29.235908 -66.43624) (xy 29.235472 -66.477343) (xy 29.227883 -66.559198) (xy 29.212774 -66.640004)
			(xy 29.190275 -66.719072) (xy 29.160576 -66.795726) (xy 29.123931 -66.869313) (xy 29.080653 -66.939205)
			(xy 29.031111 -67.004806) (xy 28.975727 -67.065555) (xy 28.914975 -67.120936) (xy 28.849372 -67.170475)
			(xy 28.779478 -67.21375) (xy 28.705889 -67.250392) (xy 28.629234 -67.280087) (xy 28.550166 -67.302584)
			(xy 28.469359 -67.317689) (xy 28.387503 -67.325273) (xy 28.3464 -67.325748) (xy 28.300004 -67.32517)
			(xy 28.207716 -67.315524) (xy 28.116932 -67.296327) (xy 28.028638 -67.267787) (xy 27.985974 -67.249548)
			(xy 27.976032 -67.245742) (xy 27.954768 -67.245742) (xy 27.944826 -67.249548) (xy 27.902165 -67.267795)
			(xy 27.813872 -67.296338) (xy 27.723087 -67.31553) (xy 27.630796 -67.325163) (xy 27.5844 -67.325748)
			(xy 27.543299 -67.325233) (xy 27.461447 -67.317649) (xy 27.380644 -67.302545) (xy 27.301579 -67.280049)
			(xy 27.224927 -67.250355) (xy 27.151342 -67.213715) (xy 27.081451 -67.170442) (xy 27.015851 -67.120905)
			(xy 26.955101 -67.065527) (xy 26.89972 -67.00478) (xy 26.85018 -66.939182) (xy 26.806904 -66.869293)
			(xy 26.770261 -66.79571) (xy 26.740563 -66.719059) (xy 26.718064 -66.639995) (xy 26.702957 -66.559193)
			(xy 26.695368 -66.477341) (xy 26.694892 -66.43624) (xy 0.509016 -66.43624) (xy 0.509016 -70.939914)
			(xy 8.478012 -70.939914) (xy 8.478545 -70.885007) (xy 8.487299 -70.775543) (xy 8.504775 -70.667129)
			(xy 8.530863 -70.56046) (xy 8.565395 -70.456217) (xy 8.608149 -70.355068) (xy 8.658854 -70.257662)
			(xy 8.717182 -70.16462) (xy 8.749538 -70.120256) (xy 8.755682 -70.111222) (xy 8.760349 -70.089902)
			(xy 8.755684 -70.068582) (xy 8.749538 -70.05955) (xy 8.717186 -70.015184) (xy 8.65886 -69.922141)
			(xy 8.608158 -69.824733) (xy 8.565404 -69.723585) (xy 8.530872 -69.619343) (xy 8.504782 -69.512674)
			(xy 8.487302 -69.404262) (xy 8.478544 -69.294799) (xy 8.478012 -69.239892) (xy 8.478453 -69.188568)
			(xy 8.486124 -69.086208) (xy 8.501424 -68.984707) (xy 8.524266 -68.884633) (xy 8.554522 -68.786547)
			(xy 8.592024 -68.690995) (xy 8.636562 -68.598513) (xy 8.687887 -68.509618) (xy 8.745711 -68.424808)
			(xy 8.809711 -68.344555) (xy 8.87953 -68.26931) (xy 8.954776 -68.199493) (xy 9.03503 -68.135494)
			(xy 9.119842 -68.077672) (xy 9.208738 -68.026349) (xy 9.301221 -67.981813) (xy 9.396773 -67.944313)
			(xy 9.49486 -67.914058) (xy 9.594935 -67.891218) (xy 9.696436 -67.875921) (xy 9.798796 -67.868252)
			(xy 9.85012 -67.867784) (xy 9.901023 -67.868245) (xy 10.00255 -67.875789) (xy 10.103239 -67.890838)
			(xy 10.202535 -67.913308) (xy 10.299893 -67.943077) (xy 10.394776 -67.97998) (xy 10.486663 -68.023815)
			(xy 10.575047 -68.074339) (xy 10.659444 -68.131276) (xy 10.739389 -68.194313) (xy 10.814441 -68.263101)
			(xy 10.884187 -68.337263) (xy 10.948245 -68.416391) (xy 11.006262 -68.500049) (xy 11.03249 -68.543678)
			(xy 11.039348 -68.555362) (xy 11.062716 -68.56857) (xy 11.177524 -68.56857) (xy 11.200892 -68.555362)
			(xy 11.20775 -68.543678) (xy 11.233971 -68.500045) (xy 11.291989 -68.416388) (xy 11.356048 -68.337261)
			(xy 11.425796 -68.2631) (xy 11.500849 -68.194313) (xy 11.580794 -68.131277) (xy 11.665192 -68.074341)
			(xy 11.753577 -68.023817) (xy 11.845464 -67.979983) (xy 11.940347 -67.94308) (xy 12.037705 -67.913311)
			(xy 12.137001 -67.890841) (xy 12.23769 -67.875792) (xy 12.339217 -67.868247) (xy 12.39012 -67.867784)
			(xy 12.441443 -67.868253) (xy 12.462296 -67.869816) (xy 61.553852 -67.869816) (xy 61.554352 -67.818909)
			(xy 61.56234 -67.71741) (xy 61.578267 -67.61685) (xy 61.602035 -67.517849) (xy 61.633497 -67.421019)
			(xy 61.672459 -67.326956) (xy 61.718682 -67.236239) (xy 61.771879 -67.149429) (xy 61.831723 -67.06706)
			(xy 61.897846 -66.989641) (xy 61.969839 -66.917648) (xy 62.047258 -66.851525) (xy 62.129627 -66.791681)
			(xy 62.216437 -66.738484) (xy 62.307154 -66.692261) (xy 62.401217 -66.653299) (xy 62.498047 -66.621837)
			(xy 62.597048 -66.598069) (xy 62.697608 -66.582142) (xy 62.799107 -66.574154) (xy 62.900921 -66.574154)
			(xy 63.00242 -66.582142) (xy 63.10298 -66.598069) (xy 63.201981 -66.621837) (xy 63.298811 -66.653299)
			(xy 63.392874 -66.692261) (xy 63.483591 -66.738484) (xy 63.570401 -66.791681) (xy 63.65277 -66.851525)
			(xy 63.730189 -66.917648) (xy 63.802182 -66.989641) (xy 63.868305 -67.06706) (xy 63.928149 -67.149429)
			(xy 63.981346 -67.236239) (xy 64.027569 -67.326956) (xy 64.066531 -67.421019) (xy 64.097993 -67.517849)
			(xy 64.121761 -67.61685) (xy 64.137688 -67.71741) (xy 64.145676 -67.818909) (xy 64.146176 -67.869816)
			(xy 101.553772 -67.869816) (xy 101.554272 -67.818909) (xy 101.56226 -67.71741) (xy 101.578187 -67.61685)
			(xy 101.601955 -67.517849) (xy 101.633417 -67.421019) (xy 101.672379 -67.326956) (xy 101.718602 -67.236239)
			(xy 101.771799 -67.149429) (xy 101.831643 -67.06706) (xy 101.897766 -66.989641) (xy 101.969759 -66.917648)
			(xy 102.047178 -66.851525) (xy 102.129547 -66.791681) (xy 102.216357 -66.738484) (xy 102.307074 -66.692261)
			(xy 102.401137 -66.653299) (xy 102.497967 -66.621837) (xy 102.596968 -66.598069) (xy 102.697528 -66.582142)
			(xy 102.799027 -66.574154) (xy 102.900841 -66.574154) (xy 103.00234 -66.582142) (xy 103.1029 -66.598069)
			(xy 103.201901 -66.621837) (xy 103.298731 -66.653299) (xy 103.392794 -66.692261) (xy 103.483511 -66.738484)
			(xy 103.570321 -66.791681) (xy 103.65269 -66.851525) (xy 103.730109 -66.917648) (xy 103.802102 -66.989641)
			(xy 103.868225 -67.06706) (xy 103.928069 -67.149429) (xy 103.981266 -67.236239) (xy 104.027489 -67.326956)
			(xy 104.066451 -67.421019) (xy 104.097913 -67.517849) (xy 104.121681 -67.61685) (xy 104.137608 -67.71741)
			(xy 104.145596 -67.818909) (xy 104.146096 -67.869816) (xy 141.5542 -67.869816) (xy 141.554699 -67.818919)
			(xy 141.562686 -67.71744) (xy 141.57861 -67.616899) (xy 141.602373 -67.517918) (xy 141.633829 -67.421107)
			(xy 141.672784 -67.327062) (xy 141.718997 -67.236364) (xy 141.772184 -67.14957) (xy 141.832017 -67.067218)
			(xy 141.898126 -66.989813) (xy 141.970105 -66.917834) (xy 142.04751 -66.851725) (xy 142.129862 -66.791892)
			(xy 142.216656 -66.738705) (xy 142.307354 -66.692492) (xy 142.401399 -66.653537) (xy 142.49821 -66.622081)
			(xy 142.597191 -66.598318) (xy 142.697732 -66.582394) (xy 142.799211 -66.574407) (xy 142.901005 -66.574407)
			(xy 143.002484 -66.582394) (xy 143.103025 -66.598318) (xy 143.202006 -66.622081) (xy 143.298817 -66.653537)
			(xy 143.392862 -66.692492) (xy 143.48356 -66.738705) (xy 143.570354 -66.791892) (xy 143.652706 -66.851725)
			(xy 143.730111 -66.917834) (xy 143.80209 -66.989813) (xy 143.868199 -67.067218) (xy 143.928032 -67.14957)
			(xy 143.981219 -67.236364) (xy 144.027432 -67.327062) (xy 144.066387 -67.421107) (xy 144.097843 -67.517918)
			(xy 144.121606 -67.616899) (xy 144.13753 -67.71744) (xy 144.145517 -67.818919) (xy 144.146016 -67.869816)
			(xy 181.55412 -67.869816) (xy 181.55462 -67.818909) (xy 181.562608 -67.71741) (xy 181.578535 -67.61685)
			(xy 181.602303 -67.517849) (xy 181.633765 -67.421019) (xy 181.672727 -67.326956) (xy 181.71895 -67.236239)
			(xy 181.772147 -67.149429) (xy 181.831991 -67.06706) (xy 181.898114 -66.989641) (xy 181.970107 -66.917648)
			(xy 182.047526 -66.851525) (xy 182.129895 -66.791681) (xy 182.216705 -66.738484) (xy 182.307422 -66.692261)
			(xy 182.401485 -66.653299) (xy 182.498315 -66.621837) (xy 182.597316 -66.598069) (xy 182.697876 -66.582142)
			(xy 182.799375 -66.574154) (xy 182.901189 -66.574154) (xy 183.002688 -66.582142) (xy 183.103248 -66.598069)
			(xy 183.202249 -66.621837) (xy 183.299079 -66.653299) (xy 183.393142 -66.692261) (xy 183.483859 -66.738484)
			(xy 183.570669 -66.791681) (xy 183.653038 -66.851525) (xy 183.730457 -66.917648) (xy 183.80245 -66.989641)
			(xy 183.868573 -67.06706) (xy 183.928417 -67.149429) (xy 183.981614 -67.236239) (xy 184.027837 -67.326956)
			(xy 184.066799 -67.421019) (xy 184.098261 -67.517849) (xy 184.122029 -67.61685) (xy 184.137956 -67.71741)
			(xy 184.145944 -67.818909) (xy 184.146444 -67.869816) (xy 184.145789 -67.929021) (xy 184.134974 -68.046936)
			(xy 184.124854 -68.105274) (xy 184.122568 -68.117212) (xy 184.129172 -68.140072) (xy 184.201308 -68.217796)
			(xy 184.223406 -68.225924) (xy 184.235598 -68.224654) (xy 184.294095 -68.218798) (xy 184.411506 -68.212572)
			(xy 184.470294 -68.212208) (xy 184.537362 -68.212707) (xy 184.671248 -68.220881) (xy 184.804386 -68.237206)
			(xy 184.936281 -68.26162) (xy 185.066442 -68.294033) (xy 185.194383 -68.334324) (xy 185.319629 -68.382343)
			(xy 185.441713 -68.437912) (xy 185.56018 -68.500822) (xy 185.674591 -68.570841) (xy 185.784518 -68.647707)
			(xy 185.889552 -68.731135) (xy 185.989302 -68.820813) (xy 186.083398 -68.916407) (xy 186.171488 -69.017563)
			(xy 186.253245 -69.123903) (xy 186.29122 -69.179186) (xy 186.298332 -69.1896) (xy 186.32043 -69.201538)
			(xy 186.430158 -69.201538) (xy 186.452256 -69.1896) (xy 186.459368 -69.179186) (xy 186.497355 -69.12391)
			(xy 186.579103 -69.017561) (xy 186.667186 -68.916397) (xy 186.761276 -68.820795) (xy 186.861022 -68.731111)
			(xy 186.966054 -68.647678) (xy 187.07598 -68.570807) (xy 187.19039 -68.500785) (xy 187.308858 -68.437873)
			(xy 187.430944 -68.382304) (xy 187.556192 -68.334287) (xy 187.684136 -68.293999) (xy 187.814299 -68.26159)
			(xy 187.946196 -68.237182) (xy 188.079337 -68.220866) (xy 188.213225 -68.212701) (xy 188.280294 -68.212208)
			(xy 188.346684 -68.212667) (xy 188.479223 -68.220684) (xy 188.611036 -68.236689) (xy 188.741642 -68.260623)
			(xy 188.870565 -68.292399) (xy 188.997333 -68.331901) (xy 189.121486 -68.378986) (xy 189.242569 -68.433481)
			(xy 189.360141 -68.495187) (xy 189.473772 -68.563879) (xy 189.583049 -68.639307) (xy 189.687572 -68.721195)
			(xy 189.702736 -68.734629) (xy 270.306796 -68.734629) (xy 270.306796 -68.649907) (xy 270.314849 -68.56557)
			(xy 270.330883 -68.48238) (xy 270.354751 -68.40109) (xy 270.386239 -68.322438) (xy 270.425061 -68.247135)
			(xy 270.470864 -68.175863) (xy 270.523235 -68.109267) (xy 270.5817 -68.047952) (xy 270.645728 -67.992471)
			(xy 270.71474 -67.943328) (xy 270.78811 -67.900968) (xy 270.865175 -67.865773) (xy 270.945237 -67.838064)
			(xy 271.02757 -67.81809) (xy 271.111429 -67.806033) (xy 271.196054 -67.802002) (xy 271.280679 -67.806033)
			(xy 271.364538 -67.81809) (xy 271.446871 -67.838064) (xy 271.526933 -67.865773) (xy 271.603998 -67.900968)
			(xy 271.677368 -67.943328) (xy 271.74638 -67.992471) (xy 271.810408 -68.047952) (xy 271.868873 -68.109267)
			(xy 271.921244 -68.175863) (xy 271.967047 -68.247135) (xy 272.005869 -68.322438) (xy 272.037357 -68.40109)
			(xy 272.061225 -68.48238) (xy 272.077259 -68.56557) (xy 272.085312 -68.649907) (xy 272.085816 -68.692268)
			(xy 272.085312 -68.734629) (xy 272.077259 -68.818966) (xy 272.061225 -68.902156) (xy 272.037357 -68.983446)
			(xy 272.005869 -69.062098) (xy 271.967047 -69.137401) (xy 271.921244 -69.208673) (xy 271.868873 -69.275269)
			(xy 271.810408 -69.336584) (xy 271.74638 -69.392065) (xy 271.677368 -69.441208) (xy 271.603998 -69.483568)
			(xy 271.526933 -69.518763) (xy 271.446871 -69.546472) (xy 271.364538 -69.566446) (xy 271.280679 -69.578503)
			(xy 271.196054 -69.582535) (xy 271.111429 -69.578503) (xy 271.02757 -69.566446) (xy 270.945237 -69.546472)
			(xy 270.865175 -69.518763) (xy 270.78811 -69.483568) (xy 270.71474 -69.441208) (xy 270.645728 -69.392065)
			(xy 270.5817 -69.336584) (xy 270.523235 -69.275269) (xy 270.470864 -69.208673) (xy 270.425061 -69.137401)
			(xy 270.386239 -69.062098) (xy 270.354751 -68.983446) (xy 270.330883 -68.902156) (xy 270.314849 -68.818966)
			(xy 270.306796 -68.734629) (xy 189.702736 -68.734629) (xy 189.78696 -68.809245) (xy 189.880851 -68.903136)
			(xy 189.968901 -69.002523) (xy 190.050789 -69.107046) (xy 190.126218 -69.216323) (xy 190.19491 -69.329954)
			(xy 190.256617 -69.447526) (xy 190.311112 -69.568609) (xy 190.358197 -69.692761) (xy 190.397699 -69.81953)
			(xy 190.429476 -69.948452) (xy 190.453411 -70.079058) (xy 190.469047 -70.207829) (xy 268.757142 -70.207829)
			(xy 268.757142 -70.123107) (xy 268.765195 -70.03877) (xy 268.781229 -69.95558) (xy 268.805097 -69.87429)
			(xy 268.836585 -69.795638) (xy 268.875407 -69.720335) (xy 268.92121 -69.649063) (xy 268.973581 -69.582467)
			(xy 269.032046 -69.521152) (xy 269.096074 -69.465671) (xy 269.165086 -69.416528) (xy 269.238456 -69.374168)
			(xy 269.315521 -69.338973) (xy 269.395583 -69.311264) (xy 269.477916 -69.29129) (xy 269.561775 -69.279233)
			(xy 269.6464 -69.275202) (xy 269.731025 -69.279233) (xy 269.814884 -69.29129) (xy 269.897217 -69.311264)
			(xy 269.977279 -69.338973) (xy 270.054344 -69.374168) (xy 270.127714 -69.416528) (xy 270.196726 -69.465671)
			(xy 270.260754 -69.521152) (xy 270.319219 -69.582467) (xy 270.37159 -69.649063) (xy 270.417393 -69.720335)
			(xy 270.456215 -69.795638) (xy 270.487703 -69.87429) (xy 270.511571 -69.95558) (xy 270.527605 -70.03877)
			(xy 270.535658 -70.123107) (xy 270.536162 -70.165468) (xy 270.535658 -70.207829) (xy 270.527605 -70.292166)
			(xy 270.511571 -70.375356) (xy 270.487703 -70.456646) (xy 270.456215 -70.535298) (xy 270.417393 -70.610601)
			(xy 270.37159 -70.681873) (xy 270.319219 -70.748469) (xy 270.260754 -70.809784) (xy 270.196726 -70.865265)
			(xy 270.127714 -70.914408) (xy 270.054344 -70.956768) (xy 269.977279 -70.991963) (xy 269.897217 -71.019672)
			(xy 269.814884 -71.039646) (xy 269.731025 -71.051703) (xy 269.6464 -71.055735) (xy 269.561775 -71.051703)
			(xy 269.477916 -71.039646) (xy 269.395583 -71.019672) (xy 269.315521 -70.991963) (xy 269.238456 -70.956768)
			(xy 269.165086 -70.914408) (xy 269.096074 -70.865265) (xy 269.032046 -70.809784) (xy 268.973581 -70.748469)
			(xy 268.92121 -70.681873) (xy 268.875407 -70.610601) (xy 268.836585 -70.535298) (xy 268.805097 -70.456646)
			(xy 268.781229 -70.375356) (xy 268.765195 -70.292166) (xy 268.757142 -70.207829) (xy 190.469047 -70.207829)
			(xy 190.469416 -70.210871) (xy 190.477433 -70.34341) (xy 190.477433 -70.47619) (xy 190.469416 -70.608729)
			(xy 190.453411 -70.740542) (xy 190.429476 -70.871148) (xy 190.397699 -71.00007) (xy 190.358197 -71.126839)
			(xy 190.311112 -71.250991) (xy 190.256617 -71.372074) (xy 190.19491 -71.489646) (xy 190.126218 -71.603277)
			(xy 190.050789 -71.712554) (xy 189.968901 -71.817077) (xy 189.880851 -71.916464) (xy 189.78696 -72.010355)
			(xy 189.687572 -72.098405) (xy 189.583049 -72.180293) (xy 189.473772 -72.255721) (xy 189.360141 -72.324413)
			(xy 189.242569 -72.386119) (xy 189.121486 -72.440614) (xy 188.997333 -72.487699) (xy 188.870565 -72.527201)
			(xy 188.741642 -72.558977) (xy 188.611036 -72.582911) (xy 188.479223 -72.598916) (xy 188.346684 -72.606933)
			(xy 188.280294 -72.607424) (xy 188.213225 -72.606965) (xy 188.079338 -72.598789) (xy 187.946198 -72.582463)
			(xy 187.814302 -72.558047) (xy 187.684141 -72.525633) (xy 187.556198 -72.485339) (xy 187.430952 -72.437318)
			(xy 187.308867 -72.381747) (xy 187.1904 -72.318834) (xy 187.075989 -72.248812) (xy 186.966063 -72.171943)
			(xy 186.861029 -72.088513) (xy 186.76128 -71.998831) (xy 186.667185 -71.903233) (xy 186.579097 -71.802074)
			(xy 186.497342 -71.695731) (xy 186.459368 -71.640446) (xy 186.452256 -71.630032) (xy 186.430158 -71.618094)
			(xy 186.32043 -71.618094) (xy 186.298332 -71.630032) (xy 186.29122 -71.640446) (xy 186.253252 -71.695735)
			(xy 186.171502 -71.802083) (xy 186.083417 -71.903246) (xy 185.989326 -71.998848) (xy 185.889577 -72.088531)
			(xy 185.784544 -72.171964) (xy 185.674617 -72.248833) (xy 185.560206 -72.318854) (xy 185.441736 -72.381766)
			(xy 185.319649 -72.437333) (xy 185.194401 -72.48535) (xy 185.066456 -72.525637) (xy 184.936292 -72.558045)
			(xy 184.804393 -72.582452) (xy 184.671252 -72.598768) (xy 184.537363 -72.606931) (xy 184.470294 -72.607424)
			(xy 184.403901 -72.606967) (xy 184.271357 -72.598949) (xy 184.139539 -72.582944) (xy 184.008927 -72.55901)
			(xy 183.879999 -72.527234) (xy 183.753224 -72.487732) (xy 183.629066 -72.440648) (xy 183.507977 -72.386153)
			(xy 183.390399 -72.324448) (xy 183.276761 -72.255756) (xy 183.167477 -72.180329) (xy 183.062946 -72.098441)
			(xy 182.963551 -72.010392) (xy 182.869652 -71.916502) (xy 182.781593 -71.817115) (xy 182.699696 -71.712592)
			(xy 182.624258 -71.603316) (xy 182.555555 -71.489684) (xy 182.493839 -71.372112) (xy 182.439333 -71.251028)
			(xy 182.392237 -71.126874) (xy 182.352723 -71.000103) (xy 182.320934 -70.871178) (xy 182.296987 -70.740569)
			(xy 182.28097 -70.608752) (xy 182.27294 -70.476209) (xy 182.272432 -70.409816) (xy 182.27291 -70.34359)
			(xy 182.280893 -70.211378) (xy 182.296826 -70.079888) (xy 182.32065 -69.949596) (xy 182.35228 -69.820975)
			(xy 182.391599 -69.694494) (xy 182.438466 -69.57061) (xy 182.49271 -69.449775) (xy 182.554135 -69.332426)
			(xy 182.5879 -69.275452) (xy 182.59425 -69.265038) (xy 182.596028 -69.241416) (xy 182.555896 -69.143372)
			(xy 182.538116 -69.127878) (xy 182.526178 -69.124576) (xy 182.477646 -69.111541) (xy 182.382574 -69.078966)
			(xy 182.290311 -69.039123) (xy 182.201411 -68.992253) (xy 182.116409 -68.938637) (xy 182.035816 -68.878598)
			(xy 181.960117 -68.812496) (xy 181.889765 -68.740729) (xy 181.825184 -68.663727) (xy 181.766762 -68.581954)
			(xy 181.71485 -68.495901) (xy 181.66976 -68.406086) (xy 181.631763 -68.313047) (xy 181.601088 -68.217345)
			(xy 181.577918 -68.119554) (xy 181.562394 -68.020262) (xy 181.554607 -67.920065) (xy 181.55412 -67.869816)
			(xy 144.146016 -67.869816) (xy 144.145413 -67.929016) (xy 144.134729 -68.04693) (xy 144.12468 -68.105274)
			(xy 144.122394 -68.117212) (xy 144.128998 -68.140072) (xy 144.201134 -68.217796) (xy 144.223232 -68.225924)
			(xy 144.235424 -68.224654) (xy 144.293921 -68.218796) (xy 144.411332 -68.212571) (xy 144.47012 -68.212208)
			(xy 144.537188 -68.212686) (xy 144.671075 -68.220862) (xy 144.804214 -68.237188) (xy 144.936109 -68.261604)
			(xy 145.066269 -68.294019) (xy 145.194211 -68.334311) (xy 145.319457 -68.382332) (xy 145.441541 -68.437901)
			(xy 145.560008 -68.500813) (xy 145.674419 -68.570833) (xy 145.784345 -68.647701) (xy 145.889379 -68.73113)
			(xy 145.98913 -68.820809) (xy 146.083225 -68.916405) (xy 146.171315 -69.017562) (xy 146.253071 -69.123902)
			(xy 146.291046 -69.179186) (xy 146.298158 -69.1896) (xy 146.320256 -69.201538) (xy 146.429984 -69.201538)
			(xy 146.452082 -69.1896) (xy 146.459194 -69.179186) (xy 146.497163 -69.123898) (xy 146.578913 -69.017549)
			(xy 146.666997 -68.916385) (xy 146.761088 -68.820783) (xy 146.860836 -68.731099) (xy 146.965869 -68.647667)
			(xy 147.075796 -68.570797) (xy 147.190207 -68.500775) (xy 147.308677 -68.437864) (xy 147.430764 -68.382296)
			(xy 147.556013 -68.334279) (xy 147.683957 -68.293992) (xy 147.814122 -68.261585) (xy 147.94602 -68.237179)
			(xy 148.079162 -68.220863) (xy 148.213051 -68.2127) (xy 148.28012 -68.212208) (xy 148.34651 -68.212678)
			(xy 148.479047 -68.220696) (xy 148.610858 -68.236702) (xy 148.741462 -68.260637) (xy 148.870383 -68.292414)
			(xy 148.99715 -68.331918) (xy 149.1213 -68.379003) (xy 149.242381 -68.433498) (xy 149.359951 -68.495204)
			(xy 149.473581 -68.563897) (xy 149.582855 -68.639324) (xy 149.687377 -68.721212) (xy 149.786763 -68.809262)
			(xy 149.880652 -68.903152) (xy 149.9687 -69.002539) (xy 150.050587 -69.107061) (xy 150.126014 -69.216336)
			(xy 150.194706 -69.329966) (xy 150.256411 -69.447537) (xy 150.310905 -69.568618) (xy 150.357989 -69.692769)
			(xy 150.397491 -69.819537) (xy 150.429267 -69.948458) (xy 150.453201 -70.079062) (xy 150.469206 -70.210873)
			(xy 150.477223 -70.34341) (xy 150.477223 -70.47619) (xy 150.469206 -70.608727) (xy 150.453201 -70.740538)
			(xy 150.429267 -70.871142) (xy 150.397491 -71.000063) (xy 150.357989 -71.126831) (xy 150.310905 -71.250982)
			(xy 150.256411 -71.372063) (xy 150.194706 -71.489634) (xy 150.126014 -71.603264) (xy 150.050587 -71.712539)
			(xy 149.9687 -71.817061) (xy 149.880652 -71.916448) (xy 149.786763 -72.010338) (xy 149.687377 -72.098388)
			(xy 149.582855 -72.180276) (xy 149.473581 -72.255703) (xy 149.359951 -72.324396) (xy 149.242381 -72.386102)
			(xy 149.1213 -72.440597) (xy 148.99715 -72.487682) (xy 148.870383 -72.527186) (xy 148.741462 -72.558963)
			(xy 148.610858 -72.582898) (xy 148.479047 -72.598904) (xy 148.34651 -72.606922) (xy 148.28012 -72.607424)
			(xy 148.213052 -72.606944) (xy 148.079165 -72.59877) (xy 147.946025 -72.582446) (xy 147.81413 -72.558031)
			(xy 147.683968 -72.525618) (xy 147.556026 -72.485326) (xy 147.43078 -72.437306) (xy 147.308695 -72.381737)
			(xy 147.190228 -72.318825) (xy 147.075817 -72.248805) (xy 146.96589 -72.171937) (xy 146.860857 -72.088508)
			(xy 146.761107 -71.998827) (xy 146.667012 -71.90323) (xy 146.578923 -71.802072) (xy 146.497168 -71.69573)
			(xy 146.459194 -71.640446) (xy 146.452082 -71.630032) (xy 146.429984 -71.618094) (xy 146.320256 -71.618094)
			(xy 146.298158 -71.630032) (xy 146.291046 -71.640446) (xy 146.253061 -71.695723) (xy 146.171312 -71.802071)
			(xy 146.083229 -71.903234) (xy 145.989138 -71.998836) (xy 145.889391 -72.08852) (xy 145.784359 -72.171952)
			(xy 145.674433 -72.248823) (xy 145.560023 -72.318844) (xy 145.441555 -72.381756) (xy 145.319469 -72.437325)
			(xy 145.194221 -72.485343) (xy 145.066278 -72.525631) (xy 144.936115 -72.55804) (xy 144.804217 -72.582448)
			(xy 144.671077 -72.598765) (xy 144.537189 -72.606931) (xy 144.47012 -72.607424) (xy 144.403731 -72.606897)
			(xy 144.271194 -72.598882) (xy 144.139383 -72.582878) (xy 144.008779 -72.558945) (xy 143.879859 -72.52717)
			(xy 143.753092 -72.487669) (xy 143.628941 -72.440586) (xy 143.50786 -72.386093) (xy 143.39029 -72.324389)
			(xy 143.27666 -72.255699) (xy 143.167384 -72.180273) (xy 143.062862 -72.098386) (xy 142.963475 -72.010339)
			(xy 142.869586 -71.916451) (xy 142.781537 -71.817065) (xy 142.699649 -71.712545) (xy 142.624221 -71.603271)
			(xy 142.555529 -71.489642) (xy 142.493822 -71.372072) (xy 142.439327 -71.250992) (xy 142.392242 -71.126842)
			(xy 142.352739 -71.000076) (xy 142.320962 -70.871156) (xy 142.297027 -70.740552) (xy 142.281022 -70.608742)
			(xy 142.273004 -70.476205) (xy 142.272512 -70.409816) (xy 142.272989 -70.343594) (xy 142.280942 -70.211388)
			(xy 142.296845 -70.079902) (xy 142.320639 -69.949613) (xy 142.352238 -69.820993) (xy 142.391527 -69.694511)
			(xy 142.438365 -69.570624) (xy 142.492579 -69.449784) (xy 142.553975 -69.33243) (xy 142.587726 -69.275452)
			(xy 142.594076 -69.265038) (xy 142.595854 -69.241416) (xy 142.555722 -69.143372) (xy 142.537942 -69.127878)
			(xy 142.526004 -69.124576) (xy 142.477475 -69.111555) (xy 142.382423 -69.078958) (xy 142.29018 -69.039098)
			(xy 142.201302 -68.992213) (xy 142.116322 -68.938586) (xy 142.03575 -68.878538) (xy 141.960071 -68.81243)
			(xy 141.88974 -68.740659) (xy 141.825178 -68.663658) (xy 141.766774 -68.581887) (xy 141.714878 -68.495838)
			(xy 141.669802 -68.406029) (xy 141.631818 -68.312998) (xy 141.601152 -68.217305) (xy 141.57799 -68.119525)
			(xy 141.562471 -68.020244) (xy 141.554687 -67.920059) (xy 141.5542 -67.869816) (xy 104.146096 -67.869816)
			(xy 104.14544 -67.929021) (xy 104.134626 -68.046936) (xy 104.124506 -68.105274) (xy 104.12222 -68.117212)
			(xy 104.128824 -68.140072) (xy 104.20096 -68.217796) (xy 104.223058 -68.225924) (xy 104.23525 -68.224654)
			(xy 104.293747 -68.218802) (xy 104.411158 -68.212573) (xy 104.469946 -68.212208) (xy 104.537013 -68.212745)
			(xy 104.670898 -68.220917) (xy 104.804036 -68.237238) (xy 104.93593 -68.26165) (xy 105.06609 -68.29406)
			(xy 105.194031 -68.334348) (xy 105.319277 -68.382365) (xy 105.441361 -68.43793) (xy 105.559829 -68.500839)
			(xy 105.674239 -68.570855) (xy 105.784166 -68.647719) (xy 105.889201 -68.731144) (xy 105.988952 -68.82082)
			(xy 106.083048 -68.916412) (xy 106.171139 -69.017566) (xy 106.252896 -69.123904) (xy 106.290872 -69.179186)
			(xy 106.297984 -69.1896) (xy 106.320082 -69.201538) (xy 106.42981 -69.201538) (xy 106.451908 -69.1896)
			(xy 106.45902 -69.179186) (xy 106.496972 -69.123886) (xy 106.578722 -69.017537) (xy 106.666808 -68.916373)
			(xy 106.7609 -68.820772) (xy 106.86065 -68.731088) (xy 106.965684 -68.647656) (xy 107.075612 -68.570786)
			(xy 107.190025 -68.500765) (xy 107.308495 -68.437855) (xy 107.430583 -68.382288) (xy 107.555833 -68.334272)
			(xy 107.683779 -68.293986) (xy 107.813945 -68.26158) (xy 107.945844 -68.237175) (xy 108.078987 -68.220861)
			(xy 108.212877 -68.212699) (xy 108.279946 -68.212208) (xy 108.346561 -68.21269) (xy 108.479549 -68.220738)
			(xy 108.611805 -68.236826) (xy 108.742843 -68.260895) (xy 108.872183 -68.292856) (xy 108.99935 -68.332592)
			(xy 109.123877 -68.379958) (xy 109.245307 -68.434779) (xy 109.363193 -68.496853) (xy 109.420406 -68.530978)
			(xy 109.42955 -68.536566) (xy 109.450632 -68.53936) (xy 109.543088 -68.512436) (xy 109.559598 -68.49872)
			(xy 109.56417 -68.489068) (xy 109.58283 -68.45221) (xy 109.625989 -68.381762) (xy 109.675492 -68.315617)
			(xy 109.730913 -68.254346) (xy 109.791775 -68.198475) (xy 109.857554 -68.148486) (xy 109.927683 -68.10481)
			(xy 110.001559 -68.067822) (xy 110.078545 -68.037842) (xy 110.157978 -68.015126) (xy 110.239175 -67.999871)
			(xy 110.321437 -67.992208) (xy 110.362746 -67.991736) (xy 110.405055 -67.992204) (xy 110.489292 -68.000211)
			(xy 110.572388 -68.016178) (xy 110.653594 -68.039959) (xy 110.732177 -68.071342) (xy 110.807426 -68.110041)
			(xy 110.843314 -68.132452) (xy 110.851703 -68.137335) (xy 110.870746 -68.141006) (xy 110.889789 -68.137335)
			(xy 110.898178 -68.132452) (xy 110.934072 -68.110048) (xy 111.009313 -68.071332) (xy 111.087892 -68.039941)
			(xy 111.169099 -68.01616) (xy 111.252198 -68.000202) (xy 111.336437 -67.992213) (xy 111.378746 -67.991736)
			(xy 111.421055 -67.992204) (xy 111.505292 -68.000211) (xy 111.588388 -68.016178) (xy 111.669594 -68.039959)
			(xy 111.748177 -68.071342) (xy 111.823426 -68.110041) (xy 111.859314 -68.132452) (xy 111.867703 -68.137335)
			(xy 111.886746 -68.141006) (xy 111.905789 -68.137335) (xy 111.914178 -68.132452) (xy 111.950072 -68.110048)
			(xy 112.025313 -68.071332) (xy 112.103892 -68.039941) (xy 112.185099 -68.01616) (xy 112.268198 -68.000202)
			(xy 112.352437 -67.992213) (xy 112.394746 -67.991736) (xy 112.435853 -67.992169) (xy 112.517717 -67.999757)
			(xy 112.598532 -68.014865) (xy 112.677609 -68.037364) (xy 112.754273 -68.067061) (xy 112.827871 -68.103704)
			(xy 112.897774 -68.146979) (xy 112.963387 -68.196519) (xy 113.024151 -68.251901) (xy 113.079547 -68.312651)
			(xy 113.129102 -68.378253) (xy 113.172394 -68.448146) (xy 113.209054 -68.521735) (xy 113.23877 -68.598392)
			(xy 113.261287 -68.677463) (xy 113.276414 -68.758274) (xy 113.284022 -68.840137) (xy 113.284508 -68.881244)
			(xy 113.284026 -68.923559) (xy 113.275992 -69.007808) (xy 113.25999 -69.090912) (xy 113.236165 -69.17212)
			(xy 113.204733 -69.250697) (xy 113.165978 -69.325933) (xy 113.143538 -69.361812) (xy 113.138619 -69.370183)
			(xy 113.134959 -69.389237) (xy 113.138646 -69.408287) (xy 113.143538 -69.416676) (xy 113.166016 -69.452532)
			(xy 113.204764 -69.527773) (xy 113.236192 -69.606354) (xy 113.260013 -69.687564) (xy 113.276014 -69.770671)
			(xy 113.284049 -69.854921) (xy 113.284045 -69.939553) (xy 113.276003 -70.023803) (xy 113.259996 -70.106908)
			(xy 113.236167 -70.188116) (xy 113.204734 -70.266695) (xy 113.165979 -70.341932) (xy 113.143538 -70.377812)
			(xy 113.138619 -70.386183) (xy 113.134959 -70.405237) (xy 113.138646 -70.424287) (xy 113.143538 -70.432676)
			(xy 113.166016 -70.468532) (xy 113.204764 -70.543773) (xy 113.236192 -70.622354) (xy 113.260013 -70.703564)
			(xy 113.276014 -70.786671) (xy 113.284049 -70.870921) (xy 113.284045 -70.955553) (xy 113.276003 -71.039803)
			(xy 113.259996 -71.122908) (xy 113.236167 -71.204116) (xy 113.204734 -71.282695) (xy 113.165979 -71.357932)
			(xy 113.143538 -71.393812) (xy 113.138619 -71.402183) (xy 113.134959 -71.421237) (xy 113.138646 -71.440287)
			(xy 113.143538 -71.448676) (xy 113.165961 -71.484564) (xy 113.204707 -71.559802) (xy 113.236134 -71.638378)
			(xy 113.259957 -71.719584) (xy 113.275962 -71.802685) (xy 113.284004 -71.88693) (xy 113.284508 -71.929244)
			(xy 113.28409 -71.970355) (xy 113.276498 -72.052227) (xy 113.261383 -72.133048) (xy 113.238875 -72.21213)
			(xy 113.209164 -72.288798) (xy 113.172506 -72.362396) (xy 113.129212 -72.432297) (xy 113.079652 -72.497905)
			(xy 113.024249 -72.55866) (xy 112.963476 -72.614042) (xy 112.897851 -72.66358) (xy 112.827936 -72.706851)
			(xy 112.754325 -72.743485) (xy 112.677648 -72.773169) (xy 112.598558 -72.795651) (xy 112.517732 -72.810739)
			(xy 112.435857 -72.818303) (xy 112.394746 -72.818752) (xy 112.352437 -72.81829) (xy 112.2682 -72.810282)
			(xy 112.185103 -72.794314) (xy 112.103897 -72.770532) (xy 112.025315 -72.739148) (xy 111.950066 -72.700448)
			(xy 111.914178 -72.678036) (xy 111.905789 -72.673153) (xy 111.886746 -72.669482) (xy 111.867703 -72.673153)
			(xy 111.859314 -72.678036) (xy 111.823421 -72.700442) (xy 111.74818 -72.739158) (xy 111.669601 -72.770548)
			(xy 111.588394 -72.79433) (xy 111.505295 -72.810287) (xy 111.421055 -72.818276) (xy 111.378746 -72.818752)
			(xy 111.336437 -72.81829) (xy 111.2522 -72.810282) (xy 111.169103 -72.794314) (xy 111.087897 -72.770532)
			(xy 111.009315 -72.739148) (xy 110.934066 -72.700448) (xy 110.898178 -72.678036) (xy 110.889789 -72.673153)
			(xy 110.870746 -72.669482) (xy 110.851703 -72.673153) (xy 110.843314 -72.678036) (xy 110.807421 -72.700442)
			(xy 110.73218 -72.739158) (xy 110.653601 -72.770548) (xy 110.572394 -72.79433) (xy 110.489295 -72.810287)
			(xy 110.405055 -72.818276) (xy 110.362746 -72.818752) (xy 110.321736 -72.818307) (xy 110.240064 -72.81076)
			(xy 110.159434 -72.795726) (xy 110.08053 -72.773333) (xy 110.004023 -72.74377) (xy 109.930563 -72.70729)
			(xy 109.860773 -72.664201) (xy 109.795246 -72.614871) (xy 109.734539 -72.559717) (xy 109.679168 -72.499208)
			(xy 109.629603 -72.433859) (xy 109.586264 -72.364224) (xy 109.567472 -72.32777) (xy 109.562392 -72.318118)
			(xy 109.54639 -72.304656) (xy 109.45368 -72.277986) (xy 109.432852 -72.28078) (xy 109.423708 -72.286622)
			(xy 109.366375 -72.320967) (xy 109.24821 -72.383438) (xy 109.126467 -72.438611) (xy 109.001595 -72.486281)
			(xy 108.874056 -72.526273) (xy 108.744322 -72.558439) (xy 108.612872 -72.58266) (xy 108.480194 -72.598845)
			(xy 108.346777 -72.606936) (xy 108.279946 -72.607424) (xy 108.212878 -72.606923) (xy 108.078991 -72.598751)
			(xy 107.945853 -72.582428) (xy 107.813957 -72.558015) (xy 107.683796 -72.525603) (xy 107.555854 -72.485313)
			(xy 107.430608 -72.437295) (xy 107.308524 -72.381727) (xy 107.190056 -72.318816) (xy 107.075645 -72.248797)
			(xy 106.965718 -72.171931) (xy 106.860684 -72.088503) (xy 106.760934 -71.998824) (xy 106.666839 -71.903228)
			(xy 106.57875 -71.802071) (xy 106.496994 -71.69573) (xy 106.45902 -71.640446) (xy 106.451908 -71.630032)
			(xy 106.42981 -71.618094) (xy 106.320082 -71.618094) (xy 106.297984 -71.630032) (xy 106.290872 -71.640446)
			(xy 106.25287 -71.695711) (xy 106.171122 -71.802059) (xy 106.08304 -71.903222) (xy 105.98895 -71.998824)
			(xy 105.889205 -72.088508) (xy 105.784174 -72.171941) (xy 105.674249 -72.248812) (xy 105.55984 -72.318834)
			(xy 105.441373 -72.381747) (xy 105.319289 -72.437317) (xy 105.194042 -72.485335) (xy 105.0661 -72.525625)
			(xy 104.935938 -72.558035) (xy 104.804041 -72.582444) (xy 104.670901 -72.598763) (xy 104.537014 -72.60693)
			(xy 104.469946 -72.607424) (xy 104.403553 -72.606916) (xy 104.27101 -72.598902) (xy 104.139193 -72.5829)
			(xy 104.008582 -72.558969) (xy 103.879654 -72.527195) (xy 103.75288 -72.487696) (xy 103.628722 -72.440614)
			(xy 103.507633 -72.386123) (xy 103.390055 -72.32442) (xy 103.276417 -72.25573) (xy 103.167133 -72.180305)
			(xy 103.062602 -72.09842) (xy 102.963206 -72.010373) (xy 102.869307 -71.916485) (xy 102.781248 -71.817099)
			(xy 102.69935 -71.712578) (xy 102.623912 -71.603304) (xy 102.555209 -71.489673) (xy 102.493492 -71.372103)
			(xy 102.438986 -71.25102) (xy 102.39189 -71.126868) (xy 102.352375 -71.000098) (xy 102.320586 -70.871174)
			(xy 102.296639 -70.740566) (xy 102.280622 -70.608751) (xy 102.272592 -70.476209) (xy 102.272084 -70.409816)
			(xy 102.272569 -70.34359) (xy 102.280552 -70.211379) (xy 102.296484 -70.079888) (xy 102.320308 -69.949596)
			(xy 102.351937 -69.820976) (xy 102.391256 -69.694495) (xy 102.438121 -69.570611) (xy 102.492364 -69.449775)
			(xy 102.553787 -69.332426) (xy 102.587552 -69.275452) (xy 102.593902 -69.265038) (xy 102.59568 -69.241416)
			(xy 102.555548 -69.143372) (xy 102.537768 -69.127878) (xy 102.52583 -69.124576) (xy 102.477308 -69.111506)
			(xy 102.382235 -69.078934) (xy 102.289972 -69.039095) (xy 102.201072 -68.992228) (xy 102.116069 -68.938615)
			(xy 102.035476 -68.878579) (xy 101.959775 -68.81248) (xy 101.889422 -68.740715) (xy 101.82484 -68.663715)
			(xy 101.766417 -68.581944) (xy 101.714505 -68.495893) (xy 101.669414 -68.406079) (xy 101.631417 -68.313042)
			(xy 101.600741 -68.217341) (xy 101.577571 -68.119551) (xy 101.562046 -68.02026) (xy 101.554259 -67.920065)
			(xy 101.553772 -67.869816) (xy 64.146176 -67.869816) (xy 64.14552 -67.929021) (xy 64.134706 -68.046936)
			(xy 64.124586 -68.105274) (xy 64.1223 -68.117212) (xy 64.128904 -68.140072) (xy 64.20104 -68.217796)
			(xy 64.223138 -68.225924) (xy 64.23533 -68.224654) (xy 64.293827 -68.218795) (xy 64.411238 -68.212571)
			(xy 64.470026 -68.212208) (xy 64.537093 -68.212761) (xy 64.670978 -68.220931) (xy 64.804115 -68.237252)
			(xy 64.936009 -68.261662) (xy 65.066169 -68.294071) (xy 65.19411 -68.334358) (xy 65.319355 -68.382374)
			(xy 65.441439 -68.437938) (xy 65.559907 -68.500845) (xy 65.674318 -68.570861) (xy 65.784245 -68.647723)
			(xy 65.88928 -68.731148) (xy 65.989031 -68.820822) (xy 66.083128 -68.916414) (xy 66.171219 -69.017567)
			(xy 66.252976 -69.123904) (xy 66.290952 -69.179186) (xy 66.298064 -69.1896) (xy 66.320162 -69.201538)
			(xy 66.42989 -69.201538) (xy 66.451988 -69.1896) (xy 66.4591 -69.179186) (xy 66.497065 -69.123895)
			(xy 66.578815 -69.017546) (xy 66.666899 -68.916383) (xy 66.760991 -68.820781) (xy 66.860739 -68.731096)
			(xy 66.965772 -68.647664) (xy 67.0757 -68.570794) (xy 67.190111 -68.500773) (xy 67.308581 -68.437862)
			(xy 67.430668 -68.382294) (xy 67.555917 -68.334278) (xy 67.683863 -68.293991) (xy 67.814027 -68.261584)
			(xy 67.945926 -68.237178) (xy 68.079068 -68.220863) (xy 68.212957 -68.2127) (xy 68.280026 -68.212208)
			(xy 68.348503 -68.212702) (xy 68.485191 -68.22123) (xy 68.621084 -68.238252) (xy 68.755653 -68.263701)
			(xy 68.888376 -68.29748) (xy 69.018739 -68.339456) (xy 69.146235 -68.389467) (xy 69.270371 -68.447318)
			(xy 69.390664 -68.512787) (xy 69.448934 -68.548758) (xy 69.458332 -68.5546) (xy 69.480176 -68.557394)
			(xy 69.575426 -68.52793) (xy 69.591682 -68.512944) (xy 69.596254 -68.502784) (xy 69.613781 -68.463304)
			(xy 69.655415 -68.387612) (xy 69.704189 -68.316312) (xy 69.759644 -68.250076) (xy 69.821258 -68.189526)
			(xy 69.88845 -68.135232) (xy 69.960589 -68.087708) (xy 70.036994 -68.047398) (xy 70.116946 -68.014684)
			(xy 70.199693 -67.989873) (xy 70.284454 -67.9732) (xy 70.370433 -67.96482) (xy 70.413626 -67.964304)
			(xy 70.455934 -67.964787) (xy 70.540171 -67.972792) (xy 70.623267 -67.988756) (xy 70.704473 -68.012535)
			(xy 70.783056 -68.043914) (xy 70.858305 -68.08261) (xy 70.894194 -68.10502) (xy 70.902583 -68.109903)
			(xy 70.921626 -68.113574) (xy 70.940669 -68.109903) (xy 70.949058 -68.10502) (xy 70.984929 -68.082579)
			(xy 71.060175 -68.043869) (xy 71.13876 -68.012484) (xy 71.219971 -67.988709) (xy 71.303073 -67.972759)
			(xy 71.387316 -67.964777) (xy 71.429626 -67.964304) (xy 71.471934 -67.964787) (xy 71.556171 -67.972792)
			(xy 71.639267 -67.988756) (xy 71.720473 -68.012535) (xy 71.799056 -68.043914) (xy 71.874305 -68.08261)
			(xy 71.910194 -68.10502) (xy 71.918583 -68.109903) (xy 71.937626 -68.113574) (xy 71.956669 -68.109903)
			(xy 71.965058 -68.10502) (xy 72.000929 -68.082579) (xy 72.076175 -68.043869) (xy 72.15476 -68.012484)
			(xy 72.235971 -67.988709) (xy 72.319073 -67.972759) (xy 72.403316 -67.964777) (xy 72.445626 -67.964304)
			(xy 72.486732 -67.964788) (xy 72.568594 -67.972374) (xy 72.649407 -67.987479) (xy 72.728481 -68.009975)
			(xy 72.805144 -68.03967) (xy 72.87874 -68.076309) (xy 72.948642 -68.119582) (xy 73.014255 -68.169118)
			(xy 73.075018 -68.224496) (xy 73.130414 -68.285243) (xy 73.17997 -68.350841) (xy 73.223263 -68.420731)
			(xy 73.259924 -68.494317) (xy 73.289641 -68.57097) (xy 73.312161 -68.650038) (xy 73.32729 -68.730847)
			(xy 73.3349 -68.812706) (xy 73.335388 -68.853812) (xy 73.334894 -68.896127) (xy 73.326862 -68.980375)
			(xy 73.310862 -69.063479) (xy 73.28704 -69.144687) (xy 73.25561 -69.223265) (xy 73.216858 -69.298501)
			(xy 73.194418 -69.33438) (xy 73.189526 -69.342764) (xy 73.185859 -69.36181) (xy 73.189534 -69.380855)
			(xy 73.194418 -69.389244) (xy 73.216868 -69.425117) (xy 73.255619 -69.500355) (xy 73.287048 -69.578933)
			(xy 73.310873 -69.660142) (xy 73.326876 -69.743246) (xy 73.334913 -69.827495) (xy 73.334912 -69.912126)
			(xy 73.326873 -69.996374) (xy 73.310868 -70.079478) (xy 73.287042 -70.160686) (xy 73.25561 -70.239264)
			(xy 73.216857 -70.314501) (xy 73.194418 -70.35038) (xy 73.189526 -70.358764) (xy 73.185859 -70.37781)
			(xy 73.189534 -70.396855) (xy 73.194418 -70.405244) (xy 73.216868 -70.441117) (xy 73.255619 -70.516355)
			(xy 73.287048 -70.594933) (xy 73.310873 -70.676142) (xy 73.326876 -70.759246) (xy 73.334913 -70.843495)
			(xy 73.334912 -70.928126) (xy 73.326873 -71.012374) (xy 73.310868 -71.095478) (xy 73.287042 -71.176686)
			(xy 73.25561 -71.255264) (xy 73.216857 -71.330501) (xy 73.194418 -71.36638) (xy 73.189526 -71.374764)
			(xy 73.185859 -71.39381) (xy 73.189534 -71.412855) (xy 73.194418 -71.421244) (xy 73.216867 -71.457116)
			(xy 73.25561 -71.532357) (xy 73.287033 -71.610937) (xy 73.310852 -71.692146) (xy 73.326851 -71.77525)
			(xy 73.334887 -71.859497) (xy 73.335388 -71.901812) (xy 73.334959 -71.942923) (xy 73.32737 -72.024795)
			(xy 73.312258 -72.105617) (xy 73.289751 -72.1847) (xy 73.260042 -72.261368) (xy 73.223385 -72.334967)
			(xy 73.180092 -72.404869) (xy 73.130533 -72.470478) (xy 73.075131 -72.531233) (xy 73.014358 -72.586616)
			(xy 72.948733 -72.636154) (xy 72.878817 -72.679424) (xy 72.805206 -72.716058) (xy 72.728529 -72.745742)
			(xy 72.649439 -72.768223) (xy 72.568612 -72.783309) (xy 72.486738 -72.790872) (xy 72.445626 -72.79132)
			(xy 72.403319 -72.790808) (xy 72.319083 -72.782808) (xy 72.235987 -72.766849) (xy 72.154781 -72.743076)
			(xy 72.076198 -72.711702) (xy 72.000948 -72.673011) (xy 71.965058 -72.650604) (xy 71.956669 -72.645721)
			(xy 71.937626 -72.64205) (xy 71.918583 -72.645721) (xy 71.910194 -72.650604) (xy 71.874311 -72.673026)
			(xy 71.799067 -72.711738) (xy 71.720486 -72.743126) (xy 71.639277 -72.766904) (xy 71.556176 -72.782859)
			(xy 71.471936 -72.790845) (xy 71.429626 -72.79132) (xy 71.387319 -72.790808) (xy 71.303083 -72.782808)
			(xy 71.219987 -72.766849) (xy 71.138781 -72.743076) (xy 71.060198 -72.711702) (xy 70.984948 -72.673011)
			(xy 70.949058 -72.650604) (xy 70.940669 -72.645721) (xy 70.921626 -72.64205) (xy 70.902583 -72.645721)
			(xy 70.894194 -72.650604) (xy 70.858311 -72.673026) (xy 70.783067 -72.711738) (xy 70.704486 -72.743126)
			(xy 70.623277 -72.766904) (xy 70.540176 -72.782859) (xy 70.455936 -72.790845) (xy 70.413626 -72.79132)
			(xy 70.372474 -72.790836) (xy 70.290522 -72.783244) (xy 70.209621 -72.768112) (xy 70.130464 -72.745571)
			(xy 70.053729 -72.715814) (xy 69.980071 -72.679093) (xy 69.91012 -72.635725) (xy 69.844476 -72.58608)
			(xy 69.783699 -72.530582) (xy 69.728309 -72.469706) (xy 69.678781 -72.403973) (xy 69.635537 -72.333946)
			(xy 69.616828 -72.29729) (xy 69.611748 -72.287384) (xy 69.595492 -72.273922) (xy 69.501004 -72.24776)
			(xy 69.479922 -72.251062) (xy 69.470778 -72.257158) (xy 69.411715 -72.294571) (xy 69.2896 -72.362684)
			(xy 69.163401 -72.422894) (xy 69.033629 -72.474957) (xy 68.900809 -72.518663) (xy 68.765478 -72.553834)
			(xy 68.628185 -72.580329) (xy 68.489485 -72.59804) (xy 68.349939 -72.606894) (xy 68.280026 -72.607424)
			(xy 68.212958 -72.606939) (xy 68.079071 -72.598766) (xy 67.945932 -72.582442) (xy 67.814036 -72.558028)
			(xy 67.683875 -72.525615) (xy 67.555933 -72.485323) (xy 67.430686 -72.437304) (xy 67.308602 -72.381735)
			(xy 67.190134 -72.318823) (xy 67.075724 -72.248803) (xy 66.965797 -72.171935) (xy 66.860763 -72.088506)
			(xy 66.761013 -71.998827) (xy 66.666918 -71.90323) (xy 66.57883 -71.802072) (xy 66.497074 -71.69573)
			(xy 66.4591 -71.640446) (xy 66.451988 -71.630032) (xy 66.42989 -71.618094) (xy 66.320162 -71.618094)
			(xy 66.298064 -71.630032) (xy 66.290952 -71.640446) (xy 66.252963 -71.695721) (xy 66.171215 -71.802068)
			(xy 66.083131 -71.903231) (xy 65.989041 -71.998833) (xy 65.889294 -72.088517) (xy 65.784262 -72.17195)
			(xy 65.674337 -72.24882) (xy 65.559927 -72.318842) (xy 65.441459 -72.381754) (xy 65.319374 -72.437323)
			(xy 65.194126 -72.485341) (xy 65.066183 -72.525629) (xy 64.93602 -72.558038) (xy 64.804123 -72.582447)
			(xy 64.670982 -72.598765) (xy 64.537094 -72.60693) (xy 64.470026 -72.607424) (xy 64.403633 -72.606935)
			(xy 64.27109 -72.59892) (xy 64.139272 -72.582917) (xy 64.008661 -72.558985) (xy 63.879733 -72.52721)
			(xy 63.752959 -72.48771) (xy 63.628801 -72.440627) (xy 63.507712 -72.386135) (xy 63.390133 -72.32443)
			(xy 63.276495 -72.25574) (xy 63.167211 -72.180314) (xy 63.062681 -72.098428) (xy 62.963285 -72.01038)
			(xy 62.869386 -71.916492) (xy 62.781327 -71.817105) (xy 62.699429 -71.712584) (xy 62.623991 -71.603308)
			(xy 62.555288 -71.489678) (xy 62.493571 -71.372106) (xy 62.439065 -71.251023) (xy 62.391969 -71.12687)
			(xy 62.352455 -71.0001) (xy 62.320666 -70.871176) (xy 62.296719 -70.740567) (xy 62.280702 -70.608751)
			(xy 62.272672 -70.476209) (xy 62.272164 -70.409816) (xy 62.272637 -70.34359) (xy 62.280621 -70.211378)
			(xy 62.296554 -70.079887) (xy 62.320379 -69.949595) (xy 62.352008 -69.820975) (xy 62.391329 -69.694493)
			(xy 62.438196 -69.57061) (xy 62.492441 -69.449774) (xy 62.553866 -69.332426) (xy 62.587632 -69.275452)
			(xy 62.593982 -69.265038) (xy 62.59576 -69.241416) (xy 62.555628 -69.143372) (xy 62.537848 -69.127878)
			(xy 62.52591 -69.124576) (xy 62.477384 -69.111519) (xy 62.382312 -69.078946) (xy 62.290048 -69.039106)
			(xy 62.201148 -68.992238) (xy 62.116146 -68.938624) (xy 62.035553 -68.878586) (xy 61.959852 -68.812486)
			(xy 61.8895 -68.74072) (xy 61.824919 -68.66372) (xy 61.766496 -68.581948) (xy 61.714584 -68.495896)
			(xy 61.669493 -68.406082) (xy 61.631496 -68.313044) (xy 61.60082 -68.217342) (xy 61.577651 -68.119552)
			(xy 61.562126 -68.020261) (xy 61.554339 -67.920065) (xy 61.553852 -67.869816) (xy 12.462296 -67.869816)
			(xy 12.543801 -67.875925) (xy 12.6453 -67.891224) (xy 12.745372 -67.914066) (xy 12.843457 -67.944323)
			(xy 12.939007 -67.981824) (xy 13.031487 -68.026361) (xy 13.12038 -68.077685) (xy 13.205189 -68.135508)
			(xy 13.28544 -68.199507) (xy 13.360685 -68.269324) (xy 13.430501 -68.344569) (xy 13.494499 -68.42482)
			(xy 13.552321 -68.50963) (xy 13.603644 -68.598524) (xy 13.64818 -68.691004) (xy 13.685681 -68.786554)
			(xy 13.715937 -68.88464) (xy 13.738778 -68.984712) (xy 13.754077 -69.086211) (xy 13.761748 -69.188569)
			(xy 13.762228 -69.239892) (xy 13.761691 -69.294799) (xy 13.752937 -69.404262) (xy 13.73546 -69.512676)
			(xy 13.709373 -69.619345) (xy 13.674841 -69.723588) (xy 13.632088 -69.824737) (xy 13.581385 -69.922144)
			(xy 13.523057 -70.015186) (xy 13.490702 -70.05955) (xy 13.484624 -70.068604) (xy 13.480031 -70.089902)
			(xy 13.484626 -70.1112) (xy 13.490702 -70.120256) (xy 13.523049 -70.164626) (xy 13.581374 -70.257669)
			(xy 13.632076 -70.355076) (xy 13.67483 -70.456223) (xy 13.709363 -70.560465) (xy 13.735454 -70.667133)
			(xy 13.752935 -70.775545) (xy 13.761695 -70.885008) (xy 13.762228 -70.939914) (xy 13.761756 -70.99124)
			(xy 13.754085 -71.093606) (xy 13.738787 -71.195112) (xy 13.715947 -71.295192) (xy 13.685693 -71.393285)
			(xy 13.648194 -71.488843) (xy 13.603659 -71.581332) (xy 13.552338 -71.670235) (xy 13.494518 -71.755054)
			(xy 13.430521 -71.835316) (xy 13.360706 -71.910572) (xy 13.285463 -71.9804) (xy 13.205212 -72.044411)
			(xy 13.120403 -72.102247) (xy 13.031509 -72.153584) (xy 12.939028 -72.198135) (xy 12.843477 -72.235652)
			(xy 12.745389 -72.265924) (xy 12.645314 -72.288782) (xy 12.54381 -72.304098) (xy 12.441446 -72.311787)
			(xy 12.39012 -72.312276) (xy 12.339213 -72.311802) (xy 12.23768 -72.304233) (xy 12.136987 -72.28916)
			(xy 12.037688 -72.266667) (xy 11.940329 -72.236876) (xy 11.845446 -72.199952) (xy 11.75356 -72.156098)
			(xy 11.665176 -72.105555) (xy 11.580782 -72.048601) (xy 11.50084 -71.98555) (xy 11.42579 -71.916747)
			(xy 11.356046 -71.842572) (xy 11.291991 -71.763431) (xy 11.233977 -71.679762) (xy 11.20775 -71.636128)
			(xy 11.200892 -71.624444) (xy 11.177524 -71.611236) (xy 11.062716 -71.611236) (xy 11.039348 -71.624444)
			(xy 11.03249 -71.636128) (xy 11.006274 -71.679769) (xy 10.948263 -71.763443) (xy 10.88421 -71.842586)
			(xy 10.814467 -71.916765) (xy 10.739418 -71.98557) (xy 10.659476 -72.048624) (xy 10.57508 -72.105579)
			(xy 10.486695 -72.156122) (xy 10.394806 -72.199975) (xy 10.299921 -72.236897) (xy 10.202559 -72.266684)
			(xy 10.103258 -72.289173) (xy 10.002563 -72.304241) (xy 9.901028 -72.311804) (xy 9.85012 -72.312276)
			(xy 9.798791 -72.311809) (xy 9.696419 -72.304137) (xy 9.594908 -72.288835) (xy 9.494824 -72.265988)
			(xy 9.396727 -72.235726) (xy 9.301167 -72.198216) (xy 9.208677 -72.153669) (xy 9.119776 -72.102335)
			(xy 9.034959 -72.044499) (xy 8.954703 -71.980486) (xy 8.879455 -71.910654) (xy 8.809637 -71.835393)
			(xy 8.745639 -71.755125) (xy 8.687819 -71.670298) (xy 8.636501 -71.581386) (xy 8.591972 -71.488888)
			(xy 8.55448 -71.393321) (xy 8.524235 -71.295219) (xy 8.501408 -71.195131) (xy 8.486124 -71.093616)
			(xy 8.478471 -70.991243) (xy 8.478012 -70.939914) (xy 0.509016 -70.939914) (xy 0.509016 -76.019914)
			(xy 8.478012 -76.019914) (xy 8.478545 -75.965007) (xy 8.487299 -75.855543) (xy 8.504775 -75.747129)
			(xy 8.530863 -75.64046) (xy 8.565395 -75.536217) (xy 8.608149 -75.435068) (xy 8.658854 -75.337662)
			(xy 8.717182 -75.24462) (xy 8.749538 -75.200256) (xy 8.755682 -75.191222) (xy 8.760349 -75.169902)
			(xy 8.755684 -75.148582) (xy 8.749538 -75.13955) (xy 8.717186 -75.095184) (xy 8.65886 -75.002141)
			(xy 8.608158 -74.904733) (xy 8.565404 -74.803585) (xy 8.530872 -74.699343) (xy 8.504782 -74.592674)
			(xy 8.487302 -74.484262) (xy 8.478544 -74.374799) (xy 8.478012 -74.319892) (xy 8.478453 -74.268568)
			(xy 8.486124 -74.166208) (xy 8.501424 -74.064707) (xy 8.524266 -73.964633) (xy 8.554522 -73.866547)
			(xy 8.592024 -73.770995) (xy 8.636562 -73.678513) (xy 8.687887 -73.589618) (xy 8.745711 -73.504808)
			(xy 8.809711 -73.424555) (xy 8.87953 -73.34931) (xy 8.954776 -73.279493) (xy 9.03503 -73.215494)
			(xy 9.119842 -73.157672) (xy 9.208738 -73.106349) (xy 9.301221 -73.061813) (xy 9.396773 -73.024313)
			(xy 9.49486 -72.994058) (xy 9.594935 -72.971218) (xy 9.696436 -72.955921) (xy 9.798796 -72.948252)
			(xy 9.85012 -72.947784) (xy 9.903561 -72.948292) (xy 10.01012 -72.956601) (xy 10.115709 -72.973175)
			(xy 10.219689 -72.997913) (xy 10.321429 -73.030665) (xy 10.420313 -73.071233) (xy 10.51574 -73.119371)
			(xy 10.607134 -73.174787) (xy 10.69394 -73.237146) (xy 10.775631 -73.306068) (xy 10.851713 -73.381137)
			(xy 10.921723 -73.461898) (xy 10.985239 -73.54786) (xy 11.041875 -73.638503) (xy 11.067034 -73.685654)
			(xy 11.071571 -73.693583) (xy 11.085137 -73.705801) (xy 11.102111 -73.712523) (xy 11.11123 -73.713086)
			(xy 11.126724 -73.71334) (xy 11.136193 -73.713098) (xy 11.153961 -73.706579) (xy 11.168185 -73.694094)
			(xy 11.172952 -73.685908) (xy 11.198138 -73.638754) (xy 11.254762 -73.548068) (xy 11.318272 -73.462065)
			(xy 11.388284 -73.381266) (xy 11.464372 -73.306161) (xy 11.546075 -73.237206) (xy 11.632897 -73.17482)
			(xy 11.724311 -73.119381) (xy 11.819764 -73.071225) (xy 11.918675 -73.030644) (xy 12.020444 -72.997886)
			(xy 12.124454 -72.973148) (xy 12.230075 -72.95658) (xy 12.336664 -72.948283) (xy 12.39012 -72.947784)
			(xy 12.441443 -72.948253) (xy 12.543801 -72.955925) (xy 12.6453 -72.971224) (xy 12.745372 -72.994066)
			(xy 12.843457 -73.024323) (xy 12.939007 -73.061824) (xy 13.031487 -73.106361) (xy 13.12038 -73.157685)
			(xy 13.205189 -73.215508) (xy 13.28544 -73.279507) (xy 13.360685 -73.349324) (xy 13.430501 -73.424569)
			(xy 13.494499 -73.50482) (xy 13.552321 -73.58963) (xy 13.603644 -73.678524) (xy 13.64818 -73.771004)
			(xy 13.685681 -73.866554) (xy 13.715937 -73.96464) (xy 13.738778 -74.064712) (xy 13.754077 -74.166211)
			(xy 13.761748 -74.268569) (xy 13.762228 -74.319892) (xy 13.761691 -74.374799) (xy 13.752937 -74.484262)
			(xy 13.73546 -74.592676) (xy 13.709373 -74.699345) (xy 13.674841 -74.803588) (xy 13.632088 -74.904737)
			(xy 13.581385 -75.002144) (xy 13.523057 -75.095186) (xy 13.490702 -75.13955) (xy 13.484624 -75.148604)
			(xy 13.480031 -75.169902) (xy 13.484626 -75.1912) (xy 13.490702 -75.200256) (xy 13.523049 -75.244626)
			(xy 13.581374 -75.337669) (xy 13.632076 -75.435076) (xy 13.67483 -75.536223) (xy 13.709363 -75.640465)
			(xy 13.735454 -75.747133) (xy 13.752935 -75.855545) (xy 13.761695 -75.965008) (xy 13.762228 -76.019914)
			(xy 13.761756 -76.07124) (xy 13.754085 -76.173606) (xy 13.738787 -76.275112) (xy 13.715947 -76.375192)
			(xy 13.685693 -76.473285) (xy 13.648194 -76.568843) (xy 13.603659 -76.661332) (xy 13.552338 -76.750235)
			(xy 13.494518 -76.835054) (xy 13.430521 -76.915316) (xy 13.360706 -76.990572) (xy 13.285463 -77.0604)
			(xy 13.205212 -77.124411) (xy 13.120403 -77.182247) (xy 13.031509 -77.233584) (xy 12.939028 -77.278135)
			(xy 12.843477 -77.315652) (xy 12.745389 -77.345924) (xy 12.645314 -77.368782) (xy 12.54381 -77.384098)
			(xy 12.441446 -77.391787) (xy 12.39012 -77.392276) (xy 12.339213 -77.391802) (xy 12.23768 -77.384233)
			(xy 12.136987 -77.36916) (xy 12.037688 -77.346667) (xy 11.940329 -77.316876) (xy 11.845446 -77.279952)
			(xy 11.75356 -77.236098) (xy 11.665176 -77.185555) (xy 11.580782 -77.128601) (xy 11.50084 -77.06555)
			(xy 11.42579 -76.996747) (xy 11.356046 -76.922572) (xy 11.291991 -76.843431) (xy 11.233977 -76.759762)
			(xy 11.20775 -76.716128) (xy 11.200892 -76.704444) (xy 11.177524 -76.691236) (xy 11.062716 -76.691236)
			(xy 11.039348 -76.704444) (xy 11.03249 -76.716128) (xy 11.006274 -76.759769) (xy 10.948263 -76.843443)
			(xy 10.88421 -76.922586) (xy 10.814467 -76.996765) (xy 10.739418 -77.06557) (xy 10.659476 -77.128624)
			(xy 10.57508 -77.185579) (xy 10.486695 -77.236122) (xy 10.394806 -77.279975) (xy 10.299921 -77.316897)
			(xy 10.202559 -77.346684) (xy 10.103258 -77.369173) (xy 10.002563 -77.384241) (xy 9.901028 -77.391804)
			(xy 9.85012 -77.392276) (xy 9.798791 -77.391809) (xy 9.696419 -77.384137) (xy 9.594908 -77.368835)
			(xy 9.494824 -77.345988) (xy 9.396727 -77.315726) (xy 9.301167 -77.278216) (xy 9.208677 -77.233669)
			(xy 9.119776 -77.182335) (xy 9.034959 -77.124499) (xy 8.954703 -77.060486) (xy 8.879455 -76.990654)
			(xy 8.809637 -76.915393) (xy 8.745639 -76.835125) (xy 8.687819 -76.750298) (xy 8.636501 -76.661386)
			(xy 8.591972 -76.568888) (xy 8.55448 -76.473321) (xy 8.524235 -76.375219) (xy 8.501408 -76.275131)
			(xy 8.486124 -76.173616) (xy 8.478471 -76.071243) (xy 8.478012 -76.019914) (xy 0.509016 -76.019914)
			(xy 0.509016 -77.760011) (xy 61.960756 -77.760011) (xy 61.960756 -77.675289) (xy 61.968809 -77.590952)
			(xy 61.984843 -77.507762) (xy 62.008711 -77.426472) (xy 62.040199 -77.34782) (xy 62.079021 -77.272517)
			(xy 62.124824 -77.201245) (xy 62.177195 -77.134649) (xy 62.23566 -77.073334) (xy 62.299688 -77.017853)
			(xy 62.3687 -76.96871) (xy 62.44207 -76.92635) (xy 62.519135 -76.891155) (xy 62.599197 -76.863446)
			(xy 62.68153 -76.843472) (xy 62.765389 -76.831415) (xy 62.850014 -76.827384) (xy 62.934639 -76.831415)
			(xy 63.018498 -76.843472) (xy 63.100831 -76.863446) (xy 63.180893 -76.891155) (xy 63.257958 -76.92635)
			(xy 63.331328 -76.96871) (xy 63.40034 -77.017853) (xy 63.464368 -77.073334) (xy 63.522833 -77.134649)
			(xy 63.575204 -77.201245) (xy 63.621007 -77.272517) (xy 63.659829 -77.34782) (xy 63.691317 -77.426472)
			(xy 63.715185 -77.507762) (xy 63.731219 -77.590952) (xy 63.739272 -77.675289) (xy 63.739776 -77.71765)
			(xy 63.739272 -77.760011) (xy 101.960676 -77.760011) (xy 101.960676 -77.675289) (xy 101.968729 -77.590952)
			(xy 101.984763 -77.507762) (xy 102.008631 -77.426472) (xy 102.040119 -77.34782) (xy 102.078941 -77.272517)
			(xy 102.124744 -77.201245) (xy 102.177115 -77.134649) (xy 102.23558 -77.073334) (xy 102.299608 -77.017853)
			(xy 102.36862 -76.96871) (xy 102.44199 -76.92635) (xy 102.519055 -76.891155) (xy 102.599117 -76.863446)
			(xy 102.68145 -76.843472) (xy 102.765309 -76.831415) (xy 102.849934 -76.827384) (xy 102.934559 -76.831415)
			(xy 103.018418 -76.843472) (xy 103.100751 -76.863446) (xy 103.180813 -76.891155) (xy 103.257878 -76.92635)
			(xy 103.331248 -76.96871) (xy 103.40026 -77.017853) (xy 103.464288 -77.073334) (xy 103.522753 -77.134649)
			(xy 103.575124 -77.201245) (xy 103.620927 -77.272517) (xy 103.659749 -77.34782) (xy 103.691237 -77.426472)
			(xy 103.715105 -77.507762) (xy 103.731139 -77.590952) (xy 103.739192 -77.675289) (xy 103.739696 -77.71765)
			(xy 103.739192 -77.760011) (xy 141.96085 -77.760011) (xy 141.96085 -77.675289) (xy 141.968903 -77.590952)
			(xy 141.984937 -77.507762) (xy 142.008805 -77.426472) (xy 142.040293 -77.34782) (xy 142.079115 -77.272517)
			(xy 142.124918 -77.201245) (xy 142.177289 -77.134649) (xy 142.235754 -77.073334) (xy 142.299782 -77.017853)
			(xy 142.368794 -76.96871) (xy 142.442164 -76.92635) (xy 142.519229 -76.891155) (xy 142.599291 -76.863446)
			(xy 142.681624 -76.843472) (xy 142.765483 -76.831415) (xy 142.850108 -76.827384) (xy 142.934733 -76.831415)
			(xy 143.018592 -76.843472) (xy 143.100925 -76.863446) (xy 143.180987 -76.891155) (xy 143.258052 -76.92635)
			(xy 143.331422 -76.96871) (xy 143.400434 -77.017853) (xy 143.464462 -77.073334) (xy 143.522927 -77.134649)
			(xy 143.575298 -77.201245) (xy 143.621101 -77.272517) (xy 143.659923 -77.34782) (xy 143.691411 -77.426472)
			(xy 143.715279 -77.507762) (xy 143.731313 -77.590952) (xy 143.739366 -77.675289) (xy 143.73987 -77.71765)
			(xy 143.739366 -77.760011) (xy 181.961024 -77.760011) (xy 181.961024 -77.675289) (xy 181.969077 -77.590952)
			(xy 181.985111 -77.507762) (xy 182.008979 -77.426472) (xy 182.040467 -77.34782) (xy 182.079289 -77.272517)
			(xy 182.125092 -77.201245) (xy 182.177463 -77.134649) (xy 182.235928 -77.073334) (xy 182.299956 -77.017853)
			(xy 182.368968 -76.96871) (xy 182.442338 -76.92635) (xy 182.519403 -76.891155) (xy 182.599465 -76.863446)
			(xy 182.681798 -76.843472) (xy 182.765657 -76.831415) (xy 182.850282 -76.827384) (xy 182.934907 -76.831415)
			(xy 183.018766 -76.843472) (xy 183.101099 -76.863446) (xy 183.181161 -76.891155) (xy 183.258226 -76.92635)
			(xy 183.331596 -76.96871) (xy 183.400608 -77.017853) (xy 183.464636 -77.073334) (xy 183.523101 -77.134649)
			(xy 183.575472 -77.201245) (xy 183.621275 -77.272517) (xy 183.660097 -77.34782) (xy 183.691585 -77.426472)
			(xy 183.715453 -77.507762) (xy 183.731487 -77.590952) (xy 183.732064 -77.597) (xy 268.350492 -77.597)
			(xy 268.351075 -77.550604) (xy 268.36072 -77.458316) (xy 268.379916 -77.367532) (xy 268.408454 -77.279239)
			(xy 268.426692 -77.236574) (xy 268.430498 -77.226632) (xy 268.430498 -77.205368) (xy 268.426692 -77.195426)
			(xy 268.408447 -77.152764) (xy 268.379903 -77.064471) (xy 268.36071 -76.973686) (xy 268.351077 -76.881396)
			(xy 268.350492 -76.835) (xy 268.351075 -76.788604) (xy 268.36072 -76.696316) (xy 268.379916 -76.605532)
			(xy 268.408454 -76.517239) (xy 268.426692 -76.474574) (xy 268.430498 -76.464632) (xy 268.430498 -76.443368)
			(xy 268.426692 -76.433426) (xy 268.408447 -76.390764) (xy 268.379903 -76.302471) (xy 268.36071 -76.211686)
			(xy 268.351077 -76.119396) (xy 268.350492 -76.073) (xy 268.351075 -76.026604) (xy 268.36072 -75.934316)
			(xy 268.379916 -75.843532) (xy 268.408454 -75.755239) (xy 268.426692 -75.712574) (xy 268.430498 -75.702632)
			(xy 268.430498 -75.681368) (xy 268.426692 -75.671426) (xy 268.408447 -75.628764) (xy 268.379903 -75.540471)
			(xy 268.36071 -75.449686) (xy 268.351077 -75.357396) (xy 268.350492 -75.311) (xy 268.351075 -75.264604)
			(xy 268.36072 -75.172316) (xy 268.379916 -75.081532) (xy 268.408454 -74.993239) (xy 268.426692 -74.950574)
			(xy 268.430498 -74.940632) (xy 268.430498 -74.919368) (xy 268.426692 -74.909426) (xy 268.408447 -74.866764)
			(xy 268.379903 -74.778471) (xy 268.36071 -74.687686) (xy 268.351077 -74.595396) (xy 268.350492 -74.549)
			(xy 268.351075 -74.502604) (xy 268.36072 -74.410316) (xy 268.379916 -74.319532) (xy 268.408454 -74.231239)
			(xy 268.426692 -74.188574) (xy 268.430498 -74.178632) (xy 268.430498 -74.157368) (xy 268.426692 -74.147426)
			(xy 268.408447 -74.104764) (xy 268.379903 -74.016471) (xy 268.36071 -73.925686) (xy 268.351077 -73.833396)
			(xy 268.350492 -73.787) (xy 268.350967 -73.745898) (xy 268.358552 -73.664043) (xy 268.373657 -73.583238)
			(xy 268.396153 -73.504171) (xy 268.425849 -73.427517) (xy 268.462491 -73.35393) (xy 268.505766 -73.284038)
			(xy 268.555306 -73.218437) (xy 268.610687 -73.157687) (xy 268.671437 -73.102306) (xy 268.737038 -73.052766)
			(xy 268.80693 -73.009491) (xy 268.880517 -72.972849) (xy 268.957171 -72.943153) (xy 269.036238 -72.920657)
			(xy 269.117043 -72.905552) (xy 269.198898 -72.897967) (xy 269.24 -72.897492) (xy 269.286396 -72.898075)
			(xy 269.378684 -72.90772) (xy 269.469468 -72.926916) (xy 269.557761 -72.955454) (xy 269.600426 -72.973692)
			(xy 269.610368 -72.977498) (xy 269.631632 -72.977498) (xy 269.641574 -72.973692) (xy 269.684236 -72.955447)
			(xy 269.772529 -72.926903) (xy 269.863314 -72.90771) (xy 269.955604 -72.898077) (xy 270.002 -72.897492)
			(xy 270.048396 -72.898075) (xy 270.140684 -72.90772) (xy 270.231468 -72.926916) (xy 270.319761 -72.955454)
			(xy 270.362426 -72.973692) (xy 270.372368 -72.977498) (xy 270.393632 -72.977498) (xy 270.403574 -72.973692)
			(xy 270.446236 -72.955447) (xy 270.534529 -72.926903) (xy 270.625314 -72.90771) (xy 270.717604 -72.898077)
			(xy 270.764 -72.897492) (xy 270.810396 -72.898075) (xy 270.902684 -72.90772) (xy 270.993468 -72.926916)
			(xy 271.081761 -72.955454) (xy 271.124426 -72.973692) (xy 271.134368 -72.977498) (xy 271.155632 -72.977498)
			(xy 271.165574 -72.973692) (xy 271.208236 -72.955447) (xy 271.296529 -72.926903) (xy 271.387314 -72.90771)
			(xy 271.479604 -72.898077) (xy 271.526 -72.897492) (xy 271.572396 -72.898075) (xy 271.664684 -72.90772)
			(xy 271.755468 -72.926916) (xy 271.843761 -72.955454) (xy 271.886426 -72.973692) (xy 271.896368 -72.977498)
			(xy 271.917632 -72.977498) (xy 271.927574 -72.973692) (xy 271.970236 -72.955447) (xy 272.058529 -72.926903)
			(xy 272.149314 -72.90771) (xy 272.241604 -72.898077) (xy 272.288 -72.897492) (xy 272.329102 -72.897967)
			(xy 272.410957 -72.905552) (xy 272.491762 -72.920657) (xy 272.570829 -72.943153) (xy 272.647483 -72.972849)
			(xy 272.72107 -73.009491) (xy 272.790962 -73.052766) (xy 272.856563 -73.102306) (xy 272.917313 -73.157687)
			(xy 272.972694 -73.218437) (xy 273.022234 -73.284038) (xy 273.065509 -73.35393) (xy 273.102151 -73.427517)
			(xy 273.131847 -73.504171) (xy 273.154343 -73.583238) (xy 273.169448 -73.664043) (xy 273.177033 -73.745898)
			(xy 273.177508 -73.787) (xy 273.176925 -73.833396) (xy 273.16728 -73.925684) (xy 273.148084 -74.016468)
			(xy 273.119546 -74.104761) (xy 273.101308 -74.147426) (xy 273.097502 -74.157368) (xy 273.097502 -74.178632)
			(xy 273.101308 -74.188574) (xy 273.119553 -74.231236) (xy 273.148097 -74.319529) (xy 273.16729 -74.410314)
			(xy 273.176923 -74.502604) (xy 273.177508 -74.549) (xy 273.177033 -74.590102) (xy 273.169448 -74.671957)
			(xy 273.154343 -74.752762) (xy 273.131847 -74.831829) (xy 273.102151 -74.908483) (xy 273.065509 -74.98207)
			(xy 273.022234 -75.051962) (xy 272.972694 -75.117563) (xy 272.917313 -75.178313) (xy 272.856563 -75.233694)
			(xy 272.790962 -75.283234) (xy 272.72107 -75.326509) (xy 272.647483 -75.363151) (xy 272.570829 -75.392847)
			(xy 272.491762 -75.415343) (xy 272.410957 -75.430448) (xy 272.329102 -75.438033) (xy 272.288 -75.438508)
			(xy 272.241604 -75.437925) (xy 272.149316 -75.42828) (xy 272.058532 -75.409084) (xy 271.970239 -75.380546)
			(xy 271.927574 -75.362308) (xy 271.917632 -75.358502) (xy 271.896368 -75.358502) (xy 271.886426 -75.362308)
			(xy 271.853507 -75.376537) (xy 271.785822 -75.400257) (xy 271.716442 -75.418437) (xy 271.681194 -75.425046)
			(xy 271.67107 -75.427344) (xy 271.653749 -75.438749) (xy 271.642344 -75.45607) (xy 271.640046 -75.466194)
			(xy 271.633416 -75.501437) (xy 271.61522 -75.57081) (xy 271.591513 -75.638498) (xy 271.577308 -75.671426)
			(xy 271.573502 -75.681368) (xy 271.573502 -75.702632) (xy 271.577308 -75.712574) (xy 271.591537 -75.745493)
			(xy 271.615257 -75.813178) (xy 271.633437 -75.882558) (xy 271.640046 -75.917806) (xy 271.642344 -75.92793)
			(xy 271.653749 -75.945251) (xy 271.67107 -75.956656) (xy 271.681194 -75.958954) (xy 271.716437 -75.965584)
			(xy 271.78581 -75.98378) (xy 271.853498 -76.007487) (xy 271.886426 -76.021692) (xy 271.896368 -76.025498)
			(xy 271.917632 -76.025498) (xy 271.927574 -76.021692) (xy 271.970236 -76.003447) (xy 272.058529 -75.974903)
			(xy 272.149314 -75.95571) (xy 272.241604 -75.946077) (xy 272.288 -75.945492) (xy 272.329102 -75.945967)
			(xy 272.410957 -75.953552) (xy 272.491762 -75.968657) (xy 272.570829 -75.991153) (xy 272.647483 -76.020849)
			(xy 272.72107 -76.057491) (xy 272.790962 -76.100766) (xy 272.856563 -76.150306) (xy 272.917313 -76.205687)
			(xy 272.972694 -76.266437) (xy 273.022234 -76.332038) (xy 273.065509 -76.40193) (xy 273.102151 -76.475517)
			(xy 273.131847 -76.552171) (xy 273.154343 -76.631238) (xy 273.169448 -76.712043) (xy 273.177033 -76.793898)
			(xy 273.177508 -76.835) (xy 273.176925 -76.881396) (xy 273.16728 -76.973684) (xy 273.148084 -77.064468)
			(xy 273.119546 -77.152761) (xy 273.101308 -77.195426) (xy 273.097502 -77.205368) (xy 273.097502 -77.226632)
			(xy 273.101308 -77.236574) (xy 273.119553 -77.279236) (xy 273.148097 -77.367529) (xy 273.16729 -77.458314)
			(xy 273.176923 -77.550604) (xy 273.177508 -77.597) (xy 273.177033 -77.638102) (xy 273.169448 -77.719957)
			(xy 273.154343 -77.800762) (xy 273.131847 -77.879829) (xy 273.102151 -77.956483) (xy 273.065509 -78.03007)
			(xy 273.022234 -78.099962) (xy 272.972694 -78.165563) (xy 272.917313 -78.226313) (xy 272.856563 -78.281694)
			(xy 272.790962 -78.331234) (xy 272.72107 -78.374509) (xy 272.647483 -78.411151) (xy 272.570829 -78.440847)
			(xy 272.491762 -78.463343) (xy 272.410957 -78.478448) (xy 272.329102 -78.486033) (xy 272.288 -78.486508)
			(xy 272.241604 -78.485925) (xy 272.149316 -78.47628) (xy 272.058532 -78.457084) (xy 271.970239 -78.428546)
			(xy 271.927574 -78.410308) (xy 271.917632 -78.406502) (xy 271.896368 -78.406502) (xy 271.886426 -78.410308)
			(xy 271.843764 -78.428553) (xy 271.755471 -78.457097) (xy 271.664686 -78.47629) (xy 271.572396 -78.485923)
			(xy 271.526 -78.486508) (xy 271.479604 -78.485925) (xy 271.387316 -78.47628) (xy 271.296532 -78.457084)
			(xy 271.208239 -78.428546) (xy 271.165574 -78.410308) (xy 271.155632 -78.406502) (xy 271.134368 -78.406502)
			(xy 271.124426 -78.410308) (xy 271.081764 -78.428553) (xy 270.993471 -78.457097) (xy 270.902686 -78.47629)
			(xy 270.810396 -78.485923) (xy 270.764 -78.486508) (xy 270.717604 -78.485925) (xy 270.625316 -78.47628)
			(xy 270.534532 -78.457084) (xy 270.446239 -78.428546) (xy 270.403574 -78.410308) (xy 270.393632 -78.406502)
			(xy 270.372368 -78.406502) (xy 270.362426 -78.410308) (xy 270.319764 -78.428553) (xy 270.231471 -78.457097)
			(xy 270.140686 -78.47629) (xy 270.048396 -78.485923) (xy 270.002 -78.486508) (xy 269.955604 -78.485925)
			(xy 269.863316 -78.47628) (xy 269.772532 -78.457084) (xy 269.684239 -78.428546) (xy 269.641574 -78.410308)
			(xy 269.631632 -78.406502) (xy 269.610368 -78.406502) (xy 269.600426 -78.410308) (xy 269.557764 -78.428553)
			(xy 269.469471 -78.457097) (xy 269.378686 -78.47629) (xy 269.286396 -78.485923) (xy 269.24 -78.486508)
			(xy 269.198898 -78.486033) (xy 269.117043 -78.478448) (xy 269.036238 -78.463343) (xy 268.957171 -78.440847)
			(xy 268.880517 -78.411151) (xy 268.80693 -78.374509) (xy 268.737038 -78.331234) (xy 268.671437 -78.281694)
			(xy 268.610687 -78.226313) (xy 268.555306 -78.165563) (xy 268.505766 -78.099962) (xy 268.462491 -78.03007)
			(xy 268.425849 -77.956483) (xy 268.396153 -77.879829) (xy 268.373657 -77.800762) (xy 268.358552 -77.719957)
			(xy 268.350967 -77.638102) (xy 268.350492 -77.597) (xy 183.732064 -77.597) (xy 183.73954 -77.675289)
			(xy 183.740044 -77.71765) (xy 183.73954 -77.760011) (xy 183.731487 -77.844348) (xy 183.715453 -77.927538)
			(xy 183.691585 -78.008828) (xy 183.660097 -78.08748) (xy 183.621275 -78.162783) (xy 183.575472 -78.234055)
			(xy 183.523101 -78.300651) (xy 183.464636 -78.361966) (xy 183.400608 -78.417447) (xy 183.331596 -78.46659)
			(xy 183.258226 -78.50895) (xy 183.181161 -78.544145) (xy 183.101099 -78.571854) (xy 183.018766 -78.591828)
			(xy 182.934907 -78.603885) (xy 182.850282 -78.607917) (xy 182.765657 -78.603885) (xy 182.681798 -78.591828)
			(xy 182.599465 -78.571854) (xy 182.519403 -78.544145) (xy 182.442338 -78.50895) (xy 182.368968 -78.46659)
			(xy 182.299956 -78.417447) (xy 182.235928 -78.361966) (xy 182.177463 -78.300651) (xy 182.125092 -78.234055)
			(xy 182.079289 -78.162783) (xy 182.040467 -78.08748) (xy 182.008979 -78.008828) (xy 181.985111 -77.927538)
			(xy 181.969077 -77.844348) (xy 181.961024 -77.760011) (xy 143.739366 -77.760011) (xy 143.731313 -77.844348)
			(xy 143.715279 -77.927538) (xy 143.691411 -78.008828) (xy 143.659923 -78.08748) (xy 143.621101 -78.162783)
			(xy 143.575298 -78.234055) (xy 143.522927 -78.300651) (xy 143.464462 -78.361966) (xy 143.400434 -78.417447)
			(xy 143.331422 -78.46659) (xy 143.258052 -78.50895) (xy 143.180987 -78.544145) (xy 143.100925 -78.571854)
			(xy 143.018592 -78.591828) (xy 142.934733 -78.603885) (xy 142.850108 -78.607917) (xy 142.765483 -78.603885)
			(xy 142.681624 -78.591828) (xy 142.599291 -78.571854) (xy 142.519229 -78.544145) (xy 142.442164 -78.50895)
			(xy 142.368794 -78.46659) (xy 142.299782 -78.417447) (xy 142.235754 -78.361966) (xy 142.177289 -78.300651)
			(xy 142.124918 -78.234055) (xy 142.079115 -78.162783) (xy 142.040293 -78.08748) (xy 142.008805 -78.008828)
			(xy 141.984937 -77.927538) (xy 141.968903 -77.844348) (xy 141.96085 -77.760011) (xy 103.739192 -77.760011)
			(xy 103.731139 -77.844348) (xy 103.715105 -77.927538) (xy 103.691237 -78.008828) (xy 103.659749 -78.08748)
			(xy 103.620927 -78.162783) (xy 103.575124 -78.234055) (xy 103.522753 -78.300651) (xy 103.464288 -78.361966)
			(xy 103.40026 -78.417447) (xy 103.331248 -78.46659) (xy 103.257878 -78.50895) (xy 103.180813 -78.544145)
			(xy 103.100751 -78.571854) (xy 103.018418 -78.591828) (xy 102.934559 -78.603885) (xy 102.849934 -78.607917)
			(xy 102.765309 -78.603885) (xy 102.68145 -78.591828) (xy 102.599117 -78.571854) (xy 102.519055 -78.544145)
			(xy 102.44199 -78.50895) (xy 102.36862 -78.46659) (xy 102.299608 -78.417447) (xy 102.23558 -78.361966)
			(xy 102.177115 -78.300651) (xy 102.124744 -78.234055) (xy 102.078941 -78.162783) (xy 102.040119 -78.08748)
			(xy 102.008631 -78.008828) (xy 101.984763 -77.927538) (xy 101.968729 -77.844348) (xy 101.960676 -77.760011)
			(xy 63.739272 -77.760011) (xy 63.731219 -77.844348) (xy 63.715185 -77.927538) (xy 63.691317 -78.008828)
			(xy 63.659829 -78.08748) (xy 63.621007 -78.162783) (xy 63.575204 -78.234055) (xy 63.522833 -78.300651)
			(xy 63.464368 -78.361966) (xy 63.40034 -78.417447) (xy 63.331328 -78.46659) (xy 63.257958 -78.50895)
			(xy 63.180893 -78.544145) (xy 63.100831 -78.571854) (xy 63.018498 -78.591828) (xy 62.934639 -78.603885)
			(xy 62.850014 -78.607917) (xy 62.765389 -78.603885) (xy 62.68153 -78.591828) (xy 62.599197 -78.571854)
			(xy 62.519135 -78.544145) (xy 62.44207 -78.50895) (xy 62.3687 -78.46659) (xy 62.299688 -78.417447)
			(xy 62.23566 -78.361966) (xy 62.177195 -78.300651) (xy 62.124824 -78.234055) (xy 62.079021 -78.162783)
			(xy 62.040199 -78.08748) (xy 62.008711 -78.008828) (xy 61.984843 -77.927538) (xy 61.968809 -77.844348)
			(xy 61.960756 -77.760011) (xy 0.509016 -77.760011) (xy 0.509016 -80.799629) (xy 270.301208 -80.799629)
			(xy 270.301208 -80.714907) (xy 270.309261 -80.63057) (xy 270.325295 -80.54738) (xy 270.349163 -80.46609)
			(xy 270.380651 -80.387438) (xy 270.419473 -80.312135) (xy 270.465276 -80.240863) (xy 270.517647 -80.174267)
			(xy 270.576112 -80.112952) (xy 270.64014 -80.057471) (xy 270.709152 -80.008328) (xy 270.782522 -79.965968)
			(xy 270.859587 -79.930773) (xy 270.939649 -79.903064) (xy 271.021982 -79.88309) (xy 271.105841 -79.871033)
			(xy 271.190466 -79.867002) (xy 271.275091 -79.871033) (xy 271.35895 -79.88309) (xy 271.441283 -79.903064)
			(xy 271.521345 -79.930773) (xy 271.59841 -79.965968) (xy 271.67178 -80.008328) (xy 271.740792 -80.057471)
			(xy 271.80482 -80.112952) (xy 271.863285 -80.174267) (xy 271.915656 -80.240863) (xy 271.961459 -80.312135)
			(xy 272.000281 -80.387438) (xy 272.031769 -80.46609) (xy 272.055637 -80.54738) (xy 272.071671 -80.63057)
			(xy 272.079724 -80.714907) (xy 272.080228 -80.757268) (xy 272.079724 -80.799629) (xy 272.071671 -80.883966)
			(xy 272.055637 -80.967156) (xy 272.031769 -81.048446) (xy 272.000281 -81.127098) (xy 271.961459 -81.202401)
			(xy 271.915656 -81.273673) (xy 271.863285 -81.340269) (xy 271.80482 -81.401584) (xy 271.740792 -81.457065)
			(xy 271.67178 -81.506208) (xy 271.59841 -81.548568) (xy 271.521345 -81.583763) (xy 271.441283 -81.611472)
			(xy 271.35895 -81.631446) (xy 271.275091 -81.643503) (xy 271.190466 -81.647535) (xy 271.105841 -81.643503)
			(xy 271.021982 -81.631446) (xy 270.939649 -81.611472) (xy 270.859587 -81.583763) (xy 270.782522 -81.548568)
			(xy 270.709152 -81.506208) (xy 270.64014 -81.457065) (xy 270.576112 -81.401584) (xy 270.517647 -81.340269)
			(xy 270.465276 -81.273673) (xy 270.419473 -81.202401) (xy 270.380651 -81.127098) (xy 270.349163 -81.048446)
			(xy 270.325295 -80.967156) (xy 270.309261 -80.883966) (xy 270.301208 -80.799629) (xy 0.509016 -80.799629)
			(xy 0.509016 -82.272829) (xy 268.757142 -82.272829) (xy 268.757142 -82.188107) (xy 268.765195 -82.10377)
			(xy 268.781229 -82.02058) (xy 268.805097 -81.93929) (xy 268.836585 -81.860638) (xy 268.875407 -81.785335)
			(xy 268.92121 -81.714063) (xy 268.973581 -81.647467) (xy 269.032046 -81.586152) (xy 269.096074 -81.530671)
			(xy 269.165086 -81.481528) (xy 269.238456 -81.439168) (xy 269.315521 -81.403973) (xy 269.395583 -81.376264)
			(xy 269.477916 -81.35629) (xy 269.561775 -81.344233) (xy 269.6464 -81.340202) (xy 269.731025 -81.344233)
			(xy 269.814884 -81.35629) (xy 269.897217 -81.376264) (xy 269.977279 -81.403973) (xy 270.054344 -81.439168)
			(xy 270.127714 -81.481528) (xy 270.196726 -81.530671) (xy 270.260754 -81.586152) (xy 270.319219 -81.647467)
			(xy 270.37159 -81.714063) (xy 270.417393 -81.785335) (xy 270.456215 -81.860638) (xy 270.487703 -81.93929)
			(xy 270.511571 -82.02058) (xy 270.527605 -82.10377) (xy 270.535658 -82.188107) (xy 270.536162 -82.230468)
			(xy 270.535658 -82.272829) (xy 270.527605 -82.357166) (xy 270.511571 -82.440356) (xy 270.487703 -82.521646)
			(xy 270.456215 -82.600298) (xy 270.417393 -82.675601) (xy 270.37159 -82.746873) (xy 270.319219 -82.813469)
			(xy 270.260754 -82.874784) (xy 270.196726 -82.930265) (xy 270.127714 -82.979408) (xy 270.054344 -83.021768)
			(xy 269.977279 -83.056963) (xy 269.897217 -83.084672) (xy 269.814884 -83.104646) (xy 269.731025 -83.116703)
			(xy 269.6464 -83.120735) (xy 269.561775 -83.116703) (xy 269.477916 -83.104646) (xy 269.395583 -83.084672)
			(xy 269.315521 -83.056963) (xy 269.238456 -83.021768) (xy 269.165086 -82.979408) (xy 269.096074 -82.930265)
			(xy 269.032046 -82.874784) (xy 268.973581 -82.813469) (xy 268.92121 -82.746873) (xy 268.875407 -82.675601)
			(xy 268.836585 -82.600298) (xy 268.805097 -82.521646) (xy 268.781229 -82.440356) (xy 268.765195 -82.357166)
			(xy 268.757142 -82.272829) (xy 0.509016 -82.272829) (xy 0.509016 -83.749896) (xy 11.118856 -83.749896)
			(xy 11.122874 -83.648894) (xy 11.134905 -83.54853) (xy 11.154871 -83.44944) (xy 11.182647 -83.352249)
			(xy 11.218058 -83.257572) (xy 11.260878 -83.166008) (xy 11.310838 -83.078135) (xy 11.367621 -82.994509)
			(xy 11.430869 -82.91566) (xy 11.500181 -82.842084) (xy 11.57512 -82.774248) (xy 11.655212 -82.71258)
			(xy 11.73995 -82.657471) (xy 11.828799 -82.609268) (xy 11.921196 -82.568277) (xy 12.016559 -82.534756)
			(xy 12.114283 -82.508918) (xy 12.21375 -82.490925) (xy 12.314333 -82.480893) (xy 12.415396 -82.478883)
			(xy 12.516298 -82.484909) (xy 12.616402 -82.498932) (xy 12.715076 -82.520865) (xy 12.811696 -82.550568)
			(xy 12.90565 -82.587854) (xy 12.996345 -82.632486) (xy 13.083207 -82.684183) (xy 13.165687 -82.742618)
			(xy 13.243264 -82.807421) (xy 13.315446 -82.878183) (xy 13.381779 -82.954456) (xy 13.441842 -83.035758)
			(xy 13.495256 -83.121575) (xy 13.541683 -83.211364) (xy 13.580829 -83.304558) (xy 13.612447 -83.400568)
			(xy 13.636337 -83.498786) (xy 13.652348 -83.598592) (xy 13.660379 -83.699355) (xy 13.660882 -83.749896)
			(xy 13.660379 -83.800437) (xy 13.652348 -83.9012) (xy 13.636337 -84.001006) (xy 13.612447 -84.099224)
			(xy 13.580829 -84.195234) (xy 13.541683 -84.288428) (xy 13.495256 -84.378217) (xy 13.441842 -84.464034)
			(xy 13.381779 -84.545336) (xy 13.315446 -84.621609) (xy 13.243264 -84.692371) (xy 13.165687 -84.757174)
			(xy 13.083207 -84.815609) (xy 12.996345 -84.867306) (xy 12.90565 -84.911938) (xy 12.811696 -84.949224)
			(xy 12.715076 -84.978927) (xy 12.616402 -85.00086) (xy 12.516298 -85.014883) (xy 12.415396 -85.020909)
			(xy 12.314333 -85.018899) (xy 12.21375 -85.008867) (xy 12.114283 -84.990874) (xy 12.016559 -84.965036)
			(xy 11.921196 -84.931515) (xy 11.828799 -84.890524) (xy 11.73995 -84.842321) (xy 11.655212 -84.787212)
			(xy 11.57512 -84.725544) (xy 11.500181 -84.657708) (xy 11.430869 -84.584132) (xy 11.367621 -84.505283)
			(xy 11.310838 -84.421657) (xy 11.260878 -84.333784) (xy 11.218058 -84.24222) (xy 11.182647 -84.147543)
			(xy 11.154871 -84.050352) (xy 11.134905 -83.951262) (xy 11.122874 -83.850898) (xy 11.118856 -83.749896)
			(xy 0.509016 -83.749896) (xy 0.509016 -87.559896) (xy 9.849612 -87.559896) (xy 9.850066 -87.509996)
			(xy 9.857896 -87.410503) (xy 9.873509 -87.311931) (xy 9.896807 -87.214889) (xy 9.927648 -87.119973)
			(xy 9.96584 -87.02777) (xy 10.011149 -86.938847) (xy 10.063296 -86.853754) (xy 10.121957 -86.773014)
			(xy 10.186773 -86.697126) (xy 10.257344 -86.626557) (xy 10.333233 -86.561743) (xy 10.413974 -86.503082)
			(xy 10.499068 -86.450938) (xy 10.587992 -86.40563) (xy 10.680196 -86.36744) (xy 10.775112 -86.336601)
			(xy 10.872155 -86.313304) (xy 10.970727 -86.297693) (xy 11.07022 -86.289865) (xy 11.12012 -86.289388)
			(xy 11.17137 -86.289896) (xy 11.273537 -86.298164) (xy 11.374705 -86.314636) (xy 11.474217 -86.339204)
			(xy 11.571427 -86.371709) (xy 11.665703 -86.411939) (xy 11.756431 -86.459633) (xy 11.843023 -86.514481)
			(xy 11.924914 -86.576126) (xy 12.001573 -86.644168) (xy 12.072502 -86.718164) (xy 12.13724 -86.797634)
			(xy 12.195365 -86.88206) (xy 12.2465 -86.970895) (xy 12.290312 -87.06356) (xy 12.326518 -87.159453)
			(xy 12.35488 -87.257951) (xy 12.375216 -87.358414) (xy 12.387393 -87.460189) (xy 12.389866 -87.511382)
			(xy 12.390707 -87.520861) (xy 12.398315 -87.538282) (xy 12.411745 -87.551735) (xy 12.429153 -87.559373)
			(xy 12.438634 -87.56015) (xy 12.489829 -87.562618) (xy 12.59161 -87.574781) (xy 12.692079 -87.595106)
			(xy 12.790584 -87.623459) (xy 12.886484 -87.659657) (xy 12.979156 -87.703465) (xy 13.067997 -87.754597)
			(xy 13.152429 -87.812721) (xy 13.231903 -87.877459) (xy 13.305903 -87.94839) (xy 13.373947 -88.025052)
			(xy 13.435592 -88.106949) (xy 13.490439 -88.193546) (xy 13.53813 -88.28428) (xy 13.578355 -88.378562)
			(xy 13.610852 -88.475779) (xy 13.635411 -88.575298) (xy 13.651871 -88.676472) (xy 13.660126 -88.778644)
			(xy 13.660628 -88.829896) (xy 13.660114 -88.879795) (xy 13.652285 -88.979284) (xy 13.636673 -89.077853)
			(xy 13.613377 -89.174893) (xy 13.582538 -89.269806) (xy 13.544348 -89.362006) (xy 13.499042 -89.450927)
			(xy 13.446898 -89.536018) (xy 13.38824 -89.616756) (xy 13.349598 -89.662) (xy 268.350492 -89.662)
			(xy 268.351075 -89.615604) (xy 268.36072 -89.523316) (xy 268.379916 -89.432532) (xy 268.408454 -89.344239)
			(xy 268.426692 -89.301574) (xy 268.430498 -89.291632) (xy 268.430498 -89.270368) (xy 268.426692 -89.260426)
			(xy 268.408447 -89.217764) (xy 268.379903 -89.129471) (xy 268.36071 -89.038686) (xy 268.351077 -88.946396)
			(xy 268.350492 -88.9) (xy 268.351075 -88.853604) (xy 268.36072 -88.761316) (xy 268.379916 -88.670532)
			(xy 268.408454 -88.582239) (xy 268.426692 -88.539574) (xy 268.430498 -88.529632) (xy 268.430498 -88.508368)
			(xy 268.426692 -88.498426) (xy 268.408447 -88.455764) (xy 268.379903 -88.367471) (xy 268.36071 -88.276686)
			(xy 268.351077 -88.184396) (xy 268.350492 -88.138) (xy 268.351075 -88.091604) (xy 268.36072 -87.999316)
			(xy 268.379916 -87.908532) (xy 268.408454 -87.820239) (xy 268.426692 -87.777574) (xy 268.430498 -87.767632)
			(xy 268.430498 -87.746368) (xy 268.426692 -87.736426) (xy 268.408447 -87.693764) (xy 268.379903 -87.605471)
			(xy 268.36071 -87.514686) (xy 268.351077 -87.422396) (xy 268.350492 -87.376) (xy 268.351075 -87.329604)
			(xy 268.36072 -87.237316) (xy 268.379916 -87.146532) (xy 268.408454 -87.058239) (xy 268.426692 -87.015574)
			(xy 268.430498 -87.005632) (xy 268.430498 -86.984368) (xy 268.426692 -86.974426) (xy 268.408447 -86.931764)
			(xy 268.379903 -86.843471) (xy 268.36071 -86.752686) (xy 268.351077 -86.660396) (xy 268.350492 -86.614)
			(xy 268.351075 -86.567604) (xy 268.36072 -86.475316) (xy 268.379916 -86.384532) (xy 268.408454 -86.296239)
			(xy 268.426692 -86.253574) (xy 268.430498 -86.243632) (xy 268.430498 -86.222368) (xy 268.426692 -86.212426)
			(xy 268.408447 -86.169764) (xy 268.379903 -86.081471) (xy 268.36071 -85.990686) (xy 268.351077 -85.898396)
			(xy 268.350492 -85.852) (xy 268.350967 -85.810898) (xy 268.358552 -85.729043) (xy 268.373657 -85.648238)
			(xy 268.396153 -85.569171) (xy 268.425849 -85.492517) (xy 268.462491 -85.41893) (xy 268.505766 -85.349038)
			(xy 268.555306 -85.283437) (xy 268.610687 -85.222687) (xy 268.671437 -85.167306) (xy 268.737038 -85.117766)
			(xy 268.80693 -85.074491) (xy 268.880517 -85.037849) (xy 268.957171 -85.008153) (xy 269.036238 -84.985657)
			(xy 269.117043 -84.970552) (xy 269.198898 -84.962967) (xy 269.24 -84.962492) (xy 269.286396 -84.963075)
			(xy 269.378684 -84.97272) (xy 269.469468 -84.991916) (xy 269.557761 -85.020454) (xy 269.600426 -85.038692)
			(xy 269.610368 -85.042498) (xy 269.631632 -85.042498) (xy 269.641574 -85.038692) (xy 269.684236 -85.020447)
			(xy 269.772529 -84.991903) (xy 269.863314 -84.97271) (xy 269.955604 -84.963077) (xy 270.002 -84.962492)
			(xy 270.048396 -84.963075) (xy 270.140684 -84.97272) (xy 270.231468 -84.991916) (xy 270.319761 -85.020454)
			(xy 270.362426 -85.038692) (xy 270.372368 -85.042498) (xy 270.393632 -85.042498) (xy 270.403574 -85.038692)
			(xy 270.446236 -85.020447) (xy 270.534529 -84.991903) (xy 270.625314 -84.97271) (xy 270.717604 -84.963077)
			(xy 270.764 -84.962492) (xy 270.810396 -84.963075) (xy 270.902684 -84.97272) (xy 270.993468 -84.991916)
			(xy 271.081761 -85.020454) (xy 271.124426 -85.038692) (xy 271.134368 -85.042498) (xy 271.155632 -85.042498)
			(xy 271.165574 -85.038692) (xy 271.208236 -85.020447) (xy 271.296529 -84.991903) (xy 271.387314 -84.97271)
			(xy 271.479604 -84.963077) (xy 271.526 -84.962492) (xy 271.572396 -84.963075) (xy 271.664684 -84.97272)
			(xy 271.755468 -84.991916) (xy 271.843761 -85.020454) (xy 271.886426 -85.038692) (xy 271.896368 -85.042498)
			(xy 271.917632 -85.042498) (xy 271.927574 -85.038692) (xy 271.970236 -85.020447) (xy 272.058529 -84.991903)
			(xy 272.149314 -84.97271) (xy 272.241604 -84.963077) (xy 272.288 -84.962492) (xy 272.329102 -84.962967)
			(xy 272.410957 -84.970552) (xy 272.491762 -84.985657) (xy 272.570829 -85.008153) (xy 272.647483 -85.037849)
			(xy 272.72107 -85.074491) (xy 272.790962 -85.117766) (xy 272.856563 -85.167306) (xy 272.917313 -85.222687)
			(xy 272.972694 -85.283437) (xy 273.022234 -85.349038) (xy 273.065509 -85.41893) (xy 273.102151 -85.492517)
			(xy 273.131847 -85.569171) (xy 273.154343 -85.648238) (xy 273.169448 -85.729043) (xy 273.177033 -85.810898)
			(xy 273.177508 -85.852) (xy 273.176925 -85.898396) (xy 273.16728 -85.990684) (xy 273.148084 -86.081468)
			(xy 273.119546 -86.169761) (xy 273.101308 -86.212426) (xy 273.097502 -86.222368) (xy 273.097502 -86.243632)
			(xy 273.101308 -86.253574) (xy 273.119553 -86.296236) (xy 273.148097 -86.384529) (xy 273.16729 -86.475314)
			(xy 273.176923 -86.567604) (xy 273.177508 -86.614) (xy 273.177033 -86.655102) (xy 273.169448 -86.736957)
			(xy 273.154343 -86.817762) (xy 273.131847 -86.896829) (xy 273.102151 -86.973483) (xy 273.065509 -87.04707)
			(xy 273.022234 -87.116962) (xy 272.972694 -87.182563) (xy 272.917313 -87.243313) (xy 272.856563 -87.298694)
			(xy 272.790962 -87.348234) (xy 272.72107 -87.391509) (xy 272.647483 -87.428151) (xy 272.570829 -87.457847)
			(xy 272.491762 -87.480343) (xy 272.410957 -87.495448) (xy 272.329102 -87.503033) (xy 272.288 -87.503508)
			(xy 272.241604 -87.502925) (xy 272.149316 -87.49328) (xy 272.058532 -87.474084) (xy 271.970239 -87.445546)
			(xy 271.927574 -87.427308) (xy 271.917632 -87.423502) (xy 271.896368 -87.423502) (xy 271.886426 -87.427308)
			(xy 271.853507 -87.441537) (xy 271.785822 -87.465257) (xy 271.716442 -87.483437) (xy 271.681194 -87.490046)
			(xy 271.67107 -87.492344) (xy 271.653749 -87.503749) (xy 271.642344 -87.52107) (xy 271.640046 -87.531194)
			(xy 271.633416 -87.566437) (xy 271.61522 -87.63581) (xy 271.591513 -87.703498) (xy 271.577308 -87.736426)
			(xy 271.573502 -87.746368) (xy 271.573502 -87.767632) (xy 271.577308 -87.777574) (xy 271.591537 -87.810493)
			(xy 271.615257 -87.878178) (xy 271.633437 -87.947558) (xy 271.640046 -87.982806) (xy 271.642344 -87.99293)
			(xy 271.653749 -88.010251) (xy 271.67107 -88.021656) (xy 271.681194 -88.023954) (xy 271.716437 -88.030584)
			(xy 271.78581 -88.04878) (xy 271.853498 -88.072487) (xy 271.886426 -88.086692) (xy 271.896368 -88.090498)
			(xy 271.917632 -88.090498) (xy 271.927574 -88.086692) (xy 271.970236 -88.068447) (xy 272.058529 -88.039903)
			(xy 272.149314 -88.02071) (xy 272.241604 -88.011077) (xy 272.288 -88.010492) (xy 272.329102 -88.010967)
			(xy 272.410957 -88.018552) (xy 272.491762 -88.033657) (xy 272.570829 -88.056153) (xy 272.647483 -88.085849)
			(xy 272.72107 -88.122491) (xy 272.790962 -88.165766) (xy 272.856563 -88.215306) (xy 272.917313 -88.270687)
			(xy 272.972694 -88.331437) (xy 273.022234 -88.397038) (xy 273.065509 -88.46693) (xy 273.102151 -88.540517)
			(xy 273.131847 -88.617171) (xy 273.154343 -88.696238) (xy 273.169448 -88.777043) (xy 273.177033 -88.858898)
			(xy 273.177508 -88.9) (xy 273.176925 -88.946396) (xy 273.16728 -89.038684) (xy 273.148084 -89.129468)
			(xy 273.119546 -89.217761) (xy 273.101308 -89.260426) (xy 273.097502 -89.270368) (xy 273.097502 -89.291632)
			(xy 273.101308 -89.301574) (xy 273.119553 -89.344236) (xy 273.148097 -89.432529) (xy 273.16729 -89.523314)
			(xy 273.176923 -89.615604) (xy 273.177508 -89.662) (xy 273.177033 -89.703102) (xy 273.169448 -89.784957)
			(xy 273.154343 -89.865762) (xy 273.131847 -89.944829) (xy 273.102151 -90.021483) (xy 273.065509 -90.09507)
			(xy 273.022234 -90.164962) (xy 272.972694 -90.230563) (xy 272.917313 -90.291313) (xy 272.856563 -90.346694)
			(xy 272.790962 -90.396234) (xy 272.72107 -90.439509) (xy 272.667144 -90.466361) (xy 275.081742 -90.466361)
			(xy 275.081742 -90.381639) (xy 275.089795 -90.297302) (xy 275.105829 -90.214112) (xy 275.129697 -90.132822)
			(xy 275.161185 -90.05417) (xy 275.200007 -89.978867) (xy 275.24581 -89.907595) (xy 275.298181 -89.840999)
			(xy 275.356646 -89.779684) (xy 275.420674 -89.724203) (xy 275.489686 -89.67506) (xy 275.563056 -89.6327)
			(xy 275.640121 -89.597505) (xy 275.720183 -89.569796) (xy 275.802516 -89.549822) (xy 275.886375 -89.537765)
			(xy 275.971 -89.533734) (xy 276.055625 -89.537765) (xy 276.139484 -89.549822) (xy 276.221817 -89.569796)
			(xy 276.301879 -89.597505) (xy 276.378944 -89.6327) (xy 276.452314 -89.67506) (xy 276.521326 -89.724203)
			(xy 276.585354 -89.779684) (xy 276.643819 -89.840999) (xy 276.69619 -89.907595) (xy 276.741993 -89.978867)
			(xy 276.780815 -90.05417) (xy 276.812303 -90.132822) (xy 276.836171 -90.214112) (xy 276.852205 -90.297302)
			(xy 276.860258 -90.381639) (xy 276.860762 -90.424) (xy 276.860258 -90.466361) (xy 276.852205 -90.550698)
			(xy 276.836171 -90.633888) (xy 276.812303 -90.715178) (xy 276.780815 -90.79383) (xy 276.741993 -90.869133)
			(xy 276.69619 -90.940405) (xy 276.643819 -91.007001) (xy 276.585354 -91.068316) (xy 276.521326 -91.123797)
			(xy 276.452314 -91.17294) (xy 276.378944 -91.2153) (xy 276.301879 -91.250495) (xy 276.221817 -91.278204)
			(xy 276.139484 -91.298178) (xy 276.055625 -91.310235) (xy 275.971 -91.314267) (xy 275.886375 -91.310235)
			(xy 275.802516 -91.298178) (xy 275.720183 -91.278204) (xy 275.640121 -91.250495) (xy 275.563056 -91.2153)
			(xy 275.489686 -91.17294) (xy 275.420674 -91.123797) (xy 275.356646 -91.068316) (xy 275.298181 -91.007001)
			(xy 275.24581 -90.940405) (xy 275.200007 -90.869133) (xy 275.161185 -90.79383) (xy 275.129697 -90.715178)
			(xy 275.105829 -90.633888) (xy 275.089795 -90.550698) (xy 275.081742 -90.466361) (xy 272.667144 -90.466361)
			(xy 272.647483 -90.476151) (xy 272.570829 -90.505847) (xy 272.491762 -90.528343) (xy 272.410957 -90.543448)
			(xy 272.329102 -90.551033) (xy 272.288 -90.551508) (xy 272.241604 -90.550925) (xy 272.149316 -90.54128)
			(xy 272.058532 -90.522084) (xy 271.970239 -90.493546) (xy 271.927574 -90.475308) (xy 271.917632 -90.471502)
			(xy 271.896368 -90.471502) (xy 271.886426 -90.475308) (xy 271.843764 -90.493553) (xy 271.755471 -90.522097)
			(xy 271.664686 -90.54129) (xy 271.572396 -90.550923) (xy 271.526 -90.551508) (xy 271.479604 -90.550925)
			(xy 271.387316 -90.54128) (xy 271.296532 -90.522084) (xy 271.208239 -90.493546) (xy 271.165574 -90.475308)
			(xy 271.155632 -90.471502) (xy 271.134368 -90.471502) (xy 271.124426 -90.475308) (xy 271.081764 -90.493553)
			(xy 270.993471 -90.522097) (xy 270.902686 -90.54129) (xy 270.810396 -90.550923) (xy 270.764 -90.551508)
			(xy 270.717604 -90.550925) (xy 270.625316 -90.54128) (xy 270.534532 -90.522084) (xy 270.446239 -90.493546)
			(xy 270.403574 -90.475308) (xy 270.393632 -90.471502) (xy 270.372368 -90.471502) (xy 270.362426 -90.475308)
			(xy 270.340242 -90.484956) (xy 270.295004 -90.502108) (xy 270.272002 -90.509598) (xy 270.258794 -90.513916)
			(xy 270.24076 -90.533982) (xy 270.21663 -90.64752) (xy 270.225266 -90.673428) (xy 270.23568 -90.682572)
			(xy 270.266746 -90.710632) (xy 270.323976 -90.771738) (xy 270.375209 -90.837953) (xy 270.419991 -90.90869)
			(xy 270.457926 -90.983323) (xy 270.488678 -91.061192) (xy 270.511974 -91.141606) (xy 270.527609 -91.223854)
			(xy 270.535444 -91.307207) (xy 270.535908 -91.349068) (xy 270.535404 -91.391416) (xy 270.527353 -91.47573)
			(xy 270.511324 -91.558896) (xy 270.487463 -91.640163) (xy 270.455984 -91.718793) (xy 270.417173 -91.794074)
			(xy 270.371383 -91.865326) (xy 270.319027 -91.931902) (xy 270.260579 -91.9932) (xy 270.196569 -92.048665)
			(xy 270.127577 -92.097794) (xy 270.054227 -92.140143) (xy 269.977184 -92.175327) (xy 269.897145 -92.203029)
			(xy 269.814836 -92.222997) (xy 269.731001 -92.23505) (xy 269.6464 -92.239081) (xy 269.561799 -92.23505)
			(xy 269.477964 -92.222997) (xy 269.395655 -92.203029) (xy 269.315616 -92.175327) (xy 269.238573 -92.140143)
			(xy 269.165223 -92.097794) (xy 269.096231 -92.048665) (xy 269.032221 -91.9932) (xy 268.973773 -91.931902)
			(xy 268.921417 -91.865326) (xy 268.875627 -91.794074) (xy 268.836816 -91.718793) (xy 268.805337 -91.640163)
			(xy 268.781476 -91.558896) (xy 268.765447 -91.47573) (xy 268.757396 -91.391416) (xy 268.756892 -91.349068)
			(xy 268.757344 -91.308052) (xy 268.764906 -91.226369) (xy 268.779953 -91.145729) (xy 268.802357 -91.066816)
			(xy 268.831929 -90.990299) (xy 268.868417 -90.916829) (xy 268.911512 -90.847029) (xy 268.960847 -90.781491)
			(xy 269.016005 -90.720771) (xy 269.045944 -90.692732) (xy 269.056104 -90.683334) (xy 269.064232 -90.656918)
			(xy 269.0368 -90.54338) (xy 269.01775 -90.523568) (xy 269.004288 -90.519758) (xy 268.964497 -90.508355)
			(xy 268.88706 -90.47909) (xy 268.812678 -90.442758) (xy 268.741992 -90.399673) (xy 268.675615 -90.350208)
			(xy 268.61412 -90.29479) (xy 268.55804 -90.233898) (xy 268.507859 -90.16806) (xy 268.464012 -90.097845)
			(xy 268.426877 -90.02386) (xy 268.396777 -89.946745) (xy 268.373971 -89.867167) (xy 268.358656 -89.785814)
			(xy 268.350965 -89.703391) (xy 268.350492 -89.662) (xy 13.349598 -89.662) (xy 13.323427 -89.692643)
			(xy 13.252861 -89.763211) (xy 13.176975 -89.828025) (xy 13.096238 -89.886685) (xy 13.011148 -89.93883)
			(xy 12.922228 -89.984138) (xy 12.830028 -90.02233) (xy 12.735116 -90.05317) (xy 12.638076 -90.076469)
			(xy 12.539508 -90.092082) (xy 12.440019 -90.099913) (xy 12.39012 -90.100404) (xy 12.33887 -90.099894)
			(xy 12.236704 -90.091626) (xy 12.135535 -90.075154) (xy 12.036023 -90.050586) (xy 11.938813 -90.018081)
			(xy 11.844537 -89.977851) (xy 11.753809 -89.930157) (xy 11.667218 -89.875309) (xy 11.585327 -89.813664)
			(xy 11.508667 -89.745623) (xy 11.437738 -89.671626) (xy 11.373001 -89.592157) (xy 11.314876 -89.507731)
			(xy 11.263741 -89.418896) (xy 11.219928 -89.326232) (xy 11.183723 -89.230338) (xy 11.15536 -89.13184)
			(xy 11.135024 -89.031377) (xy 11.122847 -88.929603) (xy 11.120374 -88.87841) (xy 11.119594 -88.868921)
			(xy 11.111973 -88.851491) (xy 11.098523 -88.838037) (xy 11.081095 -88.830409) (xy 11.071606 -88.829642)
			(xy 11.020411 -88.827172) (xy 10.918631 -88.815009) (xy 10.818161 -88.794684) (xy 10.719656 -88.766331)
			(xy 10.623756 -88.730133) (xy 10.531084 -88.686326) (xy 10.442244 -88.635194) (xy 10.357812 -88.57707)
			(xy 10.278337 -88.512332) (xy 10.204338 -88.441401) (xy 10.136294 -88.364738) (xy 10.074648 -88.282842)
			(xy 10.019802 -88.196246) (xy 9.972111 -88.105511) (xy 9.931886 -88.011229) (xy 9.899388 -87.914013)
			(xy 9.87483 -87.814494) (xy 9.858369 -87.71332) (xy 9.850114 -87.611148) (xy 9.849612 -87.559896)
			(xy 0.509016 -87.559896) (xy 0.509016 -93.399864) (xy 3.446023 -93.399864) (xy 3.450044 -93.286002)
			(xy 3.462086 -93.172708) (xy 3.482091 -93.060546) (xy 3.509957 -92.950074) (xy 3.545546 -92.841842)
			(xy 3.588681 -92.736391) (xy 3.639147 -92.634245) (xy 3.696693 -92.535914) (xy 3.761032 -92.441886)
			(xy 3.831843 -92.352631) (xy 3.908773 -92.268594) (xy 3.99144 -92.190192) (xy 4.079431 -92.117817)
			(xy 4.172308 -92.051829) (xy 4.269609 -91.992557) (xy 4.370848 -91.940296) (xy 4.475522 -91.895306)
			(xy 4.583108 -91.857812) (xy 4.693071 -91.828001) (xy 4.804864 -91.80602) (xy 4.917928 -91.79198)
			(xy 5.0317 -91.78595) (xy 5.145615 -91.787961) (xy 5.259104 -91.798002) (xy 5.371603 -91.816024)
			(xy 5.482549 -91.841936) (xy 5.591392 -91.87561) (xy 5.697588 -91.916877) (xy 5.800608 -91.965533)
			(xy 5.89994 -92.021334) (xy 5.995089 -92.084003) (xy 6.085579 -92.153228) (xy 6.170961 -92.228663)
			(xy 6.25081 -92.309934) (xy 6.324727 -92.396634) (xy 6.392343 -92.488332) (xy 6.453324 -92.584571)
			(xy 6.507363 -92.684873) (xy 6.554193 -92.788736) (xy 6.582153 -92.864629) (xy 270.30832 -92.864629)
			(xy 270.30832 -92.779907) (xy 270.316373 -92.69557) (xy 270.332407 -92.61238) (xy 270.356275 -92.53109)
			(xy 270.387763 -92.452438) (xy 270.426585 -92.377135) (xy 270.472388 -92.305863) (xy 270.524759 -92.239267)
			(xy 270.583224 -92.177952) (xy 270.647252 -92.122471) (xy 270.716264 -92.073328) (xy 270.789634 -92.030968)
			(xy 270.866699 -91.995773) (xy 270.946761 -91.968064) (xy 271.029094 -91.94809) (xy 271.112953 -91.936033)
			(xy 271.197578 -91.932002) (xy 271.282203 -91.936033) (xy 271.366062 -91.94809) (xy 271.448395 -91.968064)
			(xy 271.528457 -91.995773) (xy 271.605522 -92.030968) (xy 271.678892 -92.073328) (xy 271.747904 -92.122471)
			(xy 271.811932 -92.177952) (xy 271.870397 -92.239267) (xy 271.922768 -92.305863) (xy 271.968571 -92.377135)
			(xy 272.007393 -92.452438) (xy 272.038881 -92.53109) (xy 272.062749 -92.61238) (xy 272.078783 -92.69557)
			(xy 272.086836 -92.779907) (xy 272.08734 -92.822268) (xy 272.086836 -92.864629) (xy 272.078783 -92.948966)
			(xy 272.062749 -93.032156) (xy 272.038881 -93.113446) (xy 272.007393 -93.192098) (xy 271.968571 -93.267401)
			(xy 271.922768 -93.338673) (xy 271.870397 -93.405269) (xy 271.811932 -93.466584) (xy 271.747904 -93.522065)
			(xy 271.678892 -93.571208) (xy 271.605522 -93.613568) (xy 271.528457 -93.648763) (xy 271.448395 -93.676472)
			(xy 271.366062 -93.696446) (xy 271.282203 -93.708503) (xy 271.197578 -93.712535) (xy 271.112953 -93.708503)
			(xy 271.029094 -93.696446) (xy 270.946761 -93.676472) (xy 270.866699 -93.648763) (xy 270.789634 -93.613568)
			(xy 270.716264 -93.571208) (xy 270.647252 -93.522065) (xy 270.583224 -93.466584) (xy 270.524759 -93.405269)
			(xy 270.472388 -93.338673) (xy 270.426585 -93.267401) (xy 270.387763 -93.192098) (xy 270.356275 -93.113446)
			(xy 270.332407 -93.032156) (xy 270.316373 -92.948966) (xy 270.30832 -92.864629) (xy 6.582153 -92.864629)
			(xy 6.59358 -92.895644) (xy 6.625327 -93.005064) (xy 6.649277 -93.11645) (xy 6.665311 -93.229249)
			(xy 6.673347 -93.342898) (xy 6.67385 -93.399864) (xy 6.673347 -93.45683) (xy 6.665311 -93.570479)
			(xy 6.649277 -93.683278) (xy 6.625327 -93.794664) (xy 6.59358 -93.904084) (xy 6.554193 -94.010992)
			(xy 6.507363 -94.114855) (xy 6.453324 -94.215157) (xy 6.392343 -94.311396) (xy 6.324727 -94.403094)
			(xy 6.25081 -94.489794) (xy 6.170961 -94.571065) (xy 6.085579 -94.6465) (xy 5.995089 -94.715725)
			(xy 5.89994 -94.778394) (xy 5.800608 -94.834195) (xy 5.697588 -94.882851) (xy 5.591392 -94.924118)
			(xy 5.550527 -94.936761) (xy 273.536914 -94.936761) (xy 273.536914 -94.852039) (xy 273.544967 -94.767702)
			(xy 273.561001 -94.684512) (xy 273.584869 -94.603222) (xy 273.616357 -94.52457) (xy 273.655179 -94.449267)
			(xy 273.700982 -94.377995) (xy 273.753353 -94.311399) (xy 273.811818 -94.250084) (xy 273.875846 -94.194603)
			(xy 273.944858 -94.14546) (xy 274.018228 -94.1031) (xy 274.095293 -94.067905) (xy 274.175355 -94.040196)
			(xy 274.257688 -94.020222) (xy 274.341547 -94.008165) (xy 274.426172 -94.004134) (xy 274.510797 -94.008165)
			(xy 274.594656 -94.020222) (xy 274.676989 -94.040196) (xy 274.757051 -94.067905) (xy 274.834116 -94.1031)
			(xy 274.907486 -94.14546) (xy 274.976498 -94.194603) (xy 275.040526 -94.250084) (xy 275.098991 -94.311399)
			(xy 275.151362 -94.377995) (xy 275.197165 -94.449267) (xy 275.235987 -94.52457) (xy 275.267475 -94.603222)
			(xy 275.291343 -94.684512) (xy 275.307377 -94.767702) (xy 275.31543 -94.852039) (xy 275.315934 -94.8944)
			(xy 275.31543 -94.936761) (xy 275.307377 -95.021098) (xy 275.291343 -95.104288) (xy 275.267475 -95.185578)
			(xy 275.235987 -95.26423) (xy 275.197165 -95.339533) (xy 275.151362 -95.410805) (xy 275.098991 -95.477401)
			(xy 275.040526 -95.538716) (xy 274.976498 -95.594197) (xy 274.907486 -95.64334) (xy 274.834116 -95.6857)
			(xy 274.757051 -95.720895) (xy 274.676989 -95.748604) (xy 274.594656 -95.768578) (xy 274.510797 -95.780635)
			(xy 274.426172 -95.784667) (xy 274.341547 -95.780635) (xy 274.257688 -95.768578) (xy 274.175355 -95.748604)
			(xy 274.095293 -95.720895) (xy 274.018228 -95.6857) (xy 273.944858 -95.64334) (xy 273.875846 -95.594197)
			(xy 273.811818 -95.538716) (xy 273.753353 -95.477401) (xy 273.700982 -95.410805) (xy 273.655179 -95.339533)
			(xy 273.616357 -95.26423) (xy 273.584869 -95.185578) (xy 273.561001 -95.104288) (xy 273.544967 -95.021098)
			(xy 273.536914 -94.936761) (xy 5.550527 -94.936761) (xy 5.482549 -94.957792) (xy 5.371603 -94.983704)
			(xy 5.259104 -95.001726) (xy 5.145615 -95.011767) (xy 5.0317 -95.013778) (xy 4.917928 -95.007748)
			(xy 4.804864 -94.993708) (xy 4.693071 -94.971727) (xy 4.583108 -94.941916) (xy 4.475522 -94.904422)
			(xy 4.370848 -94.859432) (xy 4.269609 -94.807171) (xy 4.172308 -94.747899) (xy 4.079431 -94.681911)
			(xy 3.99144 -94.609536) (xy 3.908773 -94.531134) (xy 3.831843 -94.447097) (xy 3.761032 -94.357842)
			(xy 3.696693 -94.263814) (xy 3.639147 -94.165483) (xy 3.588681 -94.063337) (xy 3.545546 -93.957886)
			(xy 3.509957 -93.849654) (xy 3.482091 -93.739182) (xy 3.462086 -93.62702) (xy 3.450044 -93.513726)
			(xy 3.446023 -93.399864) (xy 0.509016 -93.399864) (xy 0.509016 -98.013) (xy 214.347099 -98.013) (xy 214.351129 -97.928402)
			(xy 214.363182 -97.844571) (xy 214.383149 -97.762265) (xy 214.410848 -97.682229) (xy 214.44603 -97.605189)
			(xy 214.488376 -97.531842) (xy 214.537502 -97.462852) (xy 214.592963 -97.398843) (xy 214.654257 -97.340397)
			(xy 214.720829 -97.288041) (xy 214.792077 -97.24225) (xy 214.867354 -97.203439) (xy 214.94598 -97.171959)
			(xy 215.027241 -97.148095) (xy 215.110404 -97.132064) (xy 215.194713 -97.124009) (xy 215.23706 -97.123504)
			(xy 215.283455 -97.1241) (xy 215.375743 -97.133741) (xy 215.466527 -97.152933) (xy 215.554821 -97.181468)
			(xy 215.597486 -97.199704) (xy 215.607428 -97.20351) (xy 215.628692 -97.20351) (xy 215.638634 -97.199704)
			(xy 215.681302 -97.181473) (xy 215.769592 -97.152925) (xy 215.860375 -97.133728) (xy 215.952664 -97.124091)
			(xy 215.99906 -97.123504) (xy 216.041067 -97.12399) (xy 216.124708 -97.131906) (xy 216.207231 -97.14767)
			(xy 216.2879 -97.171143) (xy 216.365997 -97.202116) (xy 216.440827 -97.240312) (xy 216.511723 -97.285392)
			(xy 216.578055 -97.336953) (xy 216.639231 -97.394538) (xy 216.667334 -97.425764) (xy 216.6747 -97.434146)
			(xy 216.694512 -97.443036) (xy 216.79281 -97.443036) (xy 216.812622 -97.434146) (xy 216.819988 -97.425764)
			(xy 216.848079 -97.394524) (xy 216.909243 -97.33692) (xy 216.975568 -97.285342) (xy 217.046463 -97.240252)
			(xy 217.121295 -97.202051) (xy 217.199398 -97.171081) (xy 217.280074 -97.147616) (xy 217.362604 -97.131868)
			(xy 217.446252 -97.123975) (xy 217.488262 -97.123504) (xy 217.534657 -97.124099) (xy 217.626945 -97.133741)
			(xy 217.717729 -97.152933) (xy 217.806023 -97.181468) (xy 217.848688 -97.199704) (xy 217.85863 -97.20351)
			(xy 217.879894 -97.20351) (xy 217.889836 -97.199704) (xy 217.932504 -97.181473) (xy 218.020794 -97.152925)
			(xy 218.111577 -97.133728) (xy 218.203866 -97.124091) (xy 218.250262 -97.123504) (xy 218.291199 -97.124004)
			(xy 218.372725 -97.13153) (xy 218.453216 -97.146514) (xy 218.531989 -97.168828) (xy 218.60838 -97.198285)
			(xy 218.681742 -97.234633) (xy 218.751455 -97.277567) (xy 218.81693 -97.326724) (xy 218.877611 -97.381687)
			(xy 218.932988 -97.441992) (xy 218.95816 -97.474278) (xy 218.965526 -97.48393) (xy 218.987116 -97.494344)
			(xy 219.093542 -97.492566) (xy 219.114878 -97.48139) (xy 219.12199 -97.471484) (xy 219.146898 -97.437102)
			(xy 219.202355 -97.372809) (xy 219.263686 -97.314092) (xy 219.330332 -97.261485) (xy 219.401687 -97.215468)
			(xy 219.477102 -97.176458) (xy 219.55589 -97.144811) (xy 219.637335 -97.120815) (xy 219.720696 -97.104688)
			(xy 219.805215 -97.096576) (xy 219.847668 -97.096072) (xy 219.894071 -97.096675) (xy 219.986369 -97.106372)
			(xy 220.077154 -97.125633) (xy 220.165439 -97.154247) (xy 220.208094 -97.172526) (xy 220.218036 -97.176332)
			(xy 220.2393 -97.176332) (xy 220.249242 -97.172526) (xy 220.291907 -97.154274) (xy 220.380194 -97.125678)
			(xy 220.470975 -97.106418) (xy 220.563267 -97.096703) (xy 220.609668 -97.096072) (xy 220.651684 -97.096525)
			(xy 220.73534 -97.104457) (xy 220.817875 -97.120244) (xy 220.898554 -97.143744) (xy 220.976656 -97.174749)
			(xy 221.051486 -97.212982) (xy 221.122376 -97.258102) (xy 221.188695 -97.309707) (xy 221.249851 -97.367337)
			(xy 221.277942 -97.398586) (xy 221.285308 -97.406968) (xy 221.30512 -97.415858) (xy 221.403418 -97.415858)
			(xy 221.42323 -97.406968) (xy 221.430596 -97.398586) (xy 221.458694 -97.367348) (xy 221.519864 -97.309741)
			(xy 221.586191 -97.258156) (xy 221.657084 -97.213051) (xy 221.731912 -97.174827) (xy 221.81001 -97.143825)
			(xy 221.890681 -97.120321) (xy 221.973209 -97.104524) (xy 222.056857 -97.096575) (xy 222.09887 -97.096072)
			(xy 222.145273 -97.096675) (xy 222.237571 -97.106372) (xy 222.328356 -97.125632) (xy 222.416641 -97.154247)
			(xy 222.459296 -97.172526) (xy 222.469238 -97.176332) (xy 222.490502 -97.176332) (xy 222.500444 -97.172526)
			(xy 222.543109 -97.154273) (xy 222.631395 -97.125678) (xy 222.722177 -97.106418) (xy 222.814469 -97.096703)
			(xy 222.86087 -97.096072) (xy 222.903898 -97.096585) (xy 222.989549 -97.104908) (xy 223.073998 -97.12146)
			(xy 223.156454 -97.146086) (xy 223.236148 -97.178557) (xy 223.312336 -97.218569) (xy 223.384305 -97.265748)
			(xy 223.451385 -97.319654) (xy 223.512948 -97.379783) (xy 223.568419 -97.445574) (xy 223.61728 -97.516413)
			(xy 223.638618 -97.55378) (xy 223.643347 -97.561498) (xy 223.657067 -97.573284) (xy 223.674025 -97.579573)
			(xy 223.683068 -97.579942) (xy 223.771714 -97.579942) (xy 223.78076 -97.579567) (xy 223.797731 -97.573298)
			(xy 223.811459 -97.561515) (xy 223.816164 -97.55378) (xy 223.837459 -97.516385) (xy 223.88631 -97.445532)
			(xy 223.941777 -97.379729) (xy 224.003339 -97.319589) (xy 224.070421 -97.265677) (xy 224.142397 -97.218495)
			(xy 224.218592 -97.178485) (xy 224.298296 -97.146021) (xy 224.380763 -97.121407) (xy 224.465221 -97.104872)
			(xy 224.550881 -97.096571) (xy 224.593912 -97.096072) (xy 224.640314 -97.096695) (xy 224.732612 -97.106386)
			(xy 224.823397 -97.125641) (xy 224.911682 -97.15425) (xy 224.954338 -97.172526) (xy 224.96428 -97.176332)
			(xy 224.985544 -97.176332) (xy 224.995486 -97.172526) (xy 225.038145 -97.154259) (xy 225.126434 -97.125668)
			(xy 225.217217 -97.106412) (xy 225.309511 -97.0967) (xy 225.355912 -97.096072) (xy 225.397927 -97.096565)
			(xy 225.481582 -97.104491) (xy 225.564116 -97.120273) (xy 225.644794 -97.143768) (xy 225.722896 -97.174768)
			(xy 225.797726 -97.212997) (xy 225.868618 -97.258112) (xy 225.934937 -97.309713) (xy 225.996095 -97.367339)
			(xy 226.024186 -97.398586) (xy 226.031552 -97.406968) (xy 226.051364 -97.415858) (xy 226.149662 -97.415858)
			(xy 226.169474 -97.406968) (xy 226.17684 -97.398586) (xy 226.204915 -97.367326) (xy 226.266088 -97.309721)
			(xy 226.332418 -97.258137) (xy 226.403314 -97.213033) (xy 226.478146 -97.174812) (xy 226.556246 -97.143813)
			(xy 226.63692 -97.120312) (xy 226.71945 -97.104518) (xy 226.8031 -97.096573) (xy 226.845114 -97.096072)
			(xy 226.891516 -97.096694) (xy 226.983814 -97.106386) (xy 227.074599 -97.125641) (xy 227.162884 -97.15425)
			(xy 227.20554 -97.172526) (xy 227.215482 -97.176332) (xy 227.236746 -97.176332) (xy 227.246688 -97.172526)
			(xy 227.289347 -97.154259) (xy 227.377636 -97.125667) (xy 227.468419 -97.106411) (xy 227.560713 -97.0967)
			(xy 227.607114 -97.096072) (xy 227.649476 -97.096509) (xy 227.733816 -97.104563) (xy 227.817008 -97.120598)
			(xy 227.898299 -97.144469) (xy 227.976953 -97.175958) (xy 228.052258 -97.214782) (xy 228.123532 -97.260588)
			(xy 228.190129 -97.312961) (xy 228.251445 -97.371427) (xy 228.306927 -97.435457) (xy 228.356071 -97.504471)
			(xy 228.398433 -97.577844) (xy 228.433628 -97.654912) (xy 228.461338 -97.734976) (xy 228.481312 -97.817311)
			(xy 228.493369 -97.901172) (xy 228.497401 -97.9858) (xy 228.496115 -98.0128) (xy 228.639776 -98.0128)
			(xy 228.643808 -97.928166) (xy 228.655866 -97.844299) (xy 228.675843 -97.761958) (xy 228.703556 -97.681889)
			(xy 228.738755 -97.604817) (xy 228.781121 -97.53144) (xy 228.830271 -97.462422) (xy 228.885758 -97.398389)
			(xy 228.947082 -97.339921) (xy 229.013685 -97.287547) (xy 229.084966 -97.241741) (xy 229.160278 -97.202918)
			(xy 229.238939 -97.171431) (xy 229.320238 -97.147563) (xy 229.403437 -97.131532) (xy 229.487783 -97.123482)
			(xy 229.530148 -97.122996) (xy 229.576551 -97.123604) (xy 229.668849 -97.133299) (xy 229.759634 -97.152558)
			(xy 229.847919 -97.181172) (xy 229.890574 -97.19945) (xy 229.900516 -97.203256) (xy 229.92178 -97.203256)
			(xy 229.931722 -97.19945) (xy 229.974377 -97.181173) (xy 230.062667 -97.152584) (xy 230.153452 -97.13333)
			(xy 230.245746 -97.123623) (xy 230.292148 -97.122996) (xy 230.334163 -97.123489) (xy 230.417817 -97.131418)
			(xy 230.50035 -97.147202) (xy 230.581028 -97.170698) (xy 230.659129 -97.201699) (xy 230.733959 -97.239927)
			(xy 230.80485 -97.285041) (xy 230.871171 -97.336641) (xy 230.93233 -97.394264) (xy 230.960422 -97.42551)
			(xy 230.967788 -97.433892) (xy 230.9876 -97.442782) (xy 231.085898 -97.442782) (xy 231.10571 -97.433892)
			(xy 231.113076 -97.42551) (xy 231.14119 -97.394286) (xy 231.202357 -97.336679) (xy 231.268682 -97.285092)
			(xy 231.339573 -97.239985) (xy 231.414399 -97.201759) (xy 231.492495 -97.170756) (xy 231.573164 -97.14725)
			(xy 231.65569 -97.131451) (xy 231.739338 -97.123499) (xy 231.78135 -97.122996) (xy 231.827753 -97.123604)
			(xy 231.920051 -97.133299) (xy 232.010836 -97.152558) (xy 232.099121 -97.181171) (xy 232.141776 -97.19945)
			(xy 232.151718 -97.203256) (xy 232.172982 -97.203256) (xy 232.182924 -97.19945) (xy 232.225592 -97.181205)
			(xy 232.313877 -97.152607) (xy 232.404658 -97.133345) (xy 232.49695 -97.123628) (xy 232.54335 -97.122996)
			(xy 232.586931 -97.123531) (xy 232.673673 -97.132067) (xy 232.759165 -97.149043) (xy 232.842588 -97.174296)
			(xy 232.923142 -97.207584) (xy 233.000056 -97.248588) (xy 233.072592 -97.296916) (xy 233.140056 -97.352103)
			(xy 233.201801 -97.413622) (xy 233.257236 -97.480883) (xy 233.30583 -97.553242) (xy 233.32694 -97.591372)
			(xy 233.333798 -97.604072) (xy 233.357928 -97.618296) (xy 233.477054 -97.616518) (xy 233.50093 -97.601532)
			(xy 233.50728 -97.588578) (xy 233.526 -97.552008) (xy 233.569301 -97.482183) (xy 233.618856 -97.416648)
			(xy 233.674243 -97.355962) (xy 233.734989 -97.300641) (xy 233.800577 -97.251157) (xy 233.870449 -97.207932)
			(xy 233.944009 -97.171333) (xy 234.02063 -97.141673) (xy 234.099659 -97.119205) (xy 234.180424 -97.104119)
			(xy 234.262235 -97.096545) (xy 234.303316 -97.096072) (xy 234.349718 -97.096694) (xy 234.442016 -97.106385)
			(xy 234.532801 -97.12564) (xy 234.621086 -97.15425) (xy 234.663742 -97.172526) (xy 234.673684 -97.176332)
			(xy 234.694948 -97.176332) (xy 234.70489 -97.172526) (xy 234.747548 -97.154258) (xy 234.835837 -97.125667)
			(xy 234.926621 -97.106411) (xy 235.018915 -97.0967) (xy 235.065316 -97.096072) (xy 235.107331 -97.096562)
			(xy 235.190986 -97.104489) (xy 235.27352 -97.120271) (xy 235.354198 -97.143767) (xy 235.4323 -97.174767)
			(xy 235.507131 -97.212996) (xy 235.578022 -97.258112) (xy 235.644341 -97.309713) (xy 235.705499 -97.367339)
			(xy 235.73359 -97.398586) (xy 235.740956 -97.406968) (xy 235.760768 -97.415858) (xy 235.859066 -97.415858)
			(xy 235.878878 -97.406968) (xy 235.886244 -97.398586) (xy 235.914369 -97.367373) (xy 235.975536 -97.309766)
			(xy 236.041859 -97.258179) (xy 236.112748 -97.213071) (xy 236.187573 -97.174845) (xy 236.265667 -97.14384)
			(xy 236.346335 -97.120332) (xy 236.42886 -97.104531) (xy 236.512506 -97.096577) (xy 236.554518 -97.096072)
			(xy 236.60092 -97.096693) (xy 236.693218 -97.106385) (xy 236.784003 -97.12564) (xy 236.872288 -97.154249)
			(xy 236.914944 -97.172526) (xy 236.924886 -97.176332) (xy 236.94615 -97.176332) (xy 236.956092 -97.172526)
			(xy 236.99875 -97.154257) (xy 237.087039 -97.125666) (xy 237.177823 -97.106411) (xy 237.270117 -97.0967)
			(xy 237.316518 -97.096072) (xy 237.357615 -97.096505) (xy 237.439458 -97.104088) (xy 237.520253 -97.119186)
			(xy 237.599312 -97.141671) (xy 237.675959 -97.171353) (xy 237.749543 -97.207976) (xy 237.819435 -97.251231)
			(xy 237.88504 -97.300747) (xy 237.945798 -97.356102) (xy 238.001192 -97.416825) (xy 238.05075 -97.482399)
			(xy 238.094048 -97.552263) (xy 238.112808 -97.588832) (xy 238.119158 -97.601786) (xy 238.143034 -97.616772)
			(xy 238.261906 -97.61855) (xy 238.28629 -97.604326) (xy 238.293148 -97.591626) (xy 238.314222 -97.553465)
			(xy 238.362786 -97.481062) (xy 238.4182 -97.413758) (xy 238.479934 -97.352199) (xy 238.547395 -97.296976)
			(xy 238.619936 -97.248619) (xy 238.69686 -97.207592) (xy 238.77743 -97.174288) (xy 238.860871 -97.149028)
			(xy 238.946384 -97.132052) (xy 239.033147 -97.123526) (xy 239.076738 -97.122996) (xy 239.123141 -97.123608)
			(xy 239.215438 -97.133302) (xy 239.306224 -97.15256) (xy 239.394509 -97.181172) (xy 239.437164 -97.19945)
			(xy 239.447106 -97.203256) (xy 239.46837 -97.203256) (xy 239.478312 -97.19945) (xy 239.520968 -97.181176)
			(xy 239.609258 -97.152586) (xy 239.700042 -97.133332) (xy 239.792337 -97.123623) (xy 239.838738 -97.122996)
			(xy 239.880752 -97.123496) (xy 239.964406 -97.131425) (xy 240.04694 -97.147207) (xy 240.127617 -97.170703)
			(xy 240.205719 -97.201702) (xy 240.280549 -97.239929) (xy 240.35144 -97.285043) (xy 240.417761 -97.336642)
			(xy 240.47892 -97.394265) (xy 240.507012 -97.42551) (xy 240.514378 -97.433892) (xy 240.53419 -97.442782)
			(xy 240.632488 -97.442782) (xy 240.6523 -97.433892) (xy 240.659666 -97.42551) (xy 240.687785 -97.394291)
			(xy 240.748952 -97.336683) (xy 240.815276 -97.285096) (xy 240.886166 -97.239989) (xy 240.960991 -97.201763)
			(xy 241.039086 -97.170759) (xy 241.119755 -97.147252) (xy 241.202281 -97.131452) (xy 241.285928 -97.1235)
			(xy 241.32794 -97.122996) (xy 241.374343 -97.123607) (xy 241.46664 -97.133301) (xy 241.557426 -97.15256)
			(xy 241.645711 -97.181172) (xy 241.688366 -97.19945) (xy 241.698308 -97.203256) (xy 241.719572 -97.203256)
			(xy 241.729514 -97.19945) (xy 241.77217 -97.181176) (xy 241.86046 -97.152585) (xy 241.951244 -97.133332)
			(xy 242.043539 -97.123623) (xy 242.08994 -97.122996) (xy 242.132297 -97.123586) (xy 242.216628 -97.131642)
			(xy 242.299811 -97.147678) (xy 242.381094 -97.171547) (xy 242.459739 -97.203035) (xy 242.535035 -97.241856)
			(xy 242.606301 -97.287659) (xy 242.67289 -97.340028) (xy 242.734199 -97.398489) (xy 242.789674 -97.462513)
			(xy 242.838812 -97.531521) (xy 242.881169 -97.604886) (xy 242.916359 -97.681946) (xy 242.944066 -97.762002)
			(xy 242.964038 -97.844329) (xy 242.976094 -97.928181) (xy 242.980125 -98.0128) (xy 242.976094 -98.097419)
			(xy 242.964038 -98.181271) (xy 242.944066 -98.263598) (xy 242.916359 -98.343654) (xy 242.881169 -98.420714)
			(xy 242.838812 -98.494079) (xy 242.789674 -98.563087) (xy 242.734199 -98.627111) (xy 242.67289 -98.685572)
			(xy 242.606301 -98.737941) (xy 242.535035 -98.783744) (xy 242.459739 -98.822565) (xy 242.381094 -98.854053)
			(xy 242.299811 -98.877922) (xy 242.216628 -98.893958) (xy 242.132297 -98.902014) (xy 242.08994 -98.90252)
			(xy 242.043537 -98.901915) (xy 241.951239 -98.892218) (xy 241.860454 -98.872958) (xy 241.772169 -98.844345)
			(xy 241.729514 -98.826066) (xy 241.719572 -98.82226) (xy 241.698308 -98.82226) (xy 241.688366 -98.826066)
			(xy 241.6457 -98.844315) (xy 241.557414 -98.872912) (xy 241.466632 -98.892172) (xy 241.374341 -98.901889)
			(xy 241.32794 -98.90252) (xy 241.285924 -98.902064) (xy 241.202268 -98.894132) (xy 241.119733 -98.878347)
			(xy 241.039054 -98.854846) (xy 240.960952 -98.823842) (xy 240.886122 -98.785609) (xy 240.815232 -98.740489)
			(xy 240.748913 -98.688884) (xy 240.687757 -98.631255) (xy 240.659666 -98.600006) (xy 240.6523 -98.591624)
			(xy 240.632488 -98.582734) (xy 240.53419 -98.582734) (xy 240.514378 -98.591624) (xy 240.507012 -98.600006)
			(xy 240.478908 -98.631239) (xy 240.417739 -98.688846) (xy 240.351413 -98.740432) (xy 240.280521 -98.785537)
			(xy 240.205693 -98.823762) (xy 240.127596 -98.854764) (xy 240.046926 -98.878269) (xy 239.964399 -98.894067)
			(xy 239.88075 -98.902017) (xy 239.838738 -98.90252) (xy 239.792335 -98.901915) (xy 239.700037 -98.892219)
			(xy 239.609252 -98.872959) (xy 239.520967 -98.844345) (xy 239.478312 -98.826066) (xy 239.46837 -98.82226)
			(xy 239.447106 -98.82226) (xy 239.437164 -98.826066) (xy 239.394498 -98.844316) (xy 239.306212 -98.872912)
			(xy 239.215431 -98.892173) (xy 239.123139 -98.901889) (xy 239.076738 -98.90252) (xy 239.035642 -98.902044)
			(xy 238.9538 -98.894466) (xy 238.873006 -98.879373) (xy 238.793948 -98.856892) (xy 238.7173 -98.827215)
			(xy 238.643717 -98.790595) (xy 238.573825 -98.747345) (xy 238.508219 -98.697833) (xy 238.44746 -98.64248)
			(xy 238.392066 -98.58176) (xy 238.342507 -98.516189) (xy 238.299208 -98.446327) (xy 238.280448 -98.40976)
			(xy 238.274098 -98.396806) (xy 238.250222 -98.38182) (xy 238.13135 -98.380042) (xy 238.106966 -98.394266)
			(xy 238.100108 -98.406966) (xy 238.079063 -98.445144) (xy 238.030497 -98.517548) (xy 237.97508 -98.584852)
			(xy 237.913343 -98.64641) (xy 237.845879 -98.701633) (xy 237.773335 -98.749989) (xy 237.696408 -98.791014)
			(xy 237.615835 -98.824316) (xy 237.532391 -98.849574) (xy 237.446875 -98.866545) (xy 237.36011 -98.875068)
			(xy 237.316518 -98.875596) (xy 237.270115 -98.875) (xy 237.177817 -98.865302) (xy 237.087031 -98.846039)
			(xy 236.998747 -98.817422) (xy 236.956092 -98.799142) (xy 236.94615 -98.795336) (xy 236.924886 -98.795336)
			(xy 236.914944 -98.799142) (xy 236.87228 -98.817397) (xy 236.783993 -98.845992) (xy 236.693211 -98.865251)
			(xy 236.600919 -98.874966) (xy 236.554518 -98.875596) (xy 236.512503 -98.875129) (xy 236.428848 -98.867197)
			(xy 236.346313 -98.85141) (xy 236.265636 -98.827911) (xy 236.187534 -98.796907) (xy 236.112704 -98.758676)
			(xy 236.041813 -98.713558) (xy 235.975493 -98.661956) (xy 235.914336 -98.604329) (xy 235.886244 -98.573082)
			(xy 235.878878 -98.5647) (xy 235.859066 -98.55581) (xy 235.760768 -98.55581) (xy 235.740956 -98.5647)
			(xy 235.73359 -98.573082) (xy 235.705492 -98.604321) (xy 235.644323 -98.661928) (xy 235.577996 -98.713514)
			(xy 235.507103 -98.75862) (xy 235.432275 -98.796844) (xy 235.354177 -98.827845) (xy 235.273506 -98.851349)
			(xy 235.190978 -98.867146) (xy 235.107329 -98.875094) (xy 235.065316 -98.875596) (xy 235.018913 -98.875001)
			(xy 234.926615 -98.865302) (xy 234.835829 -98.846039) (xy 234.747545 -98.817422) (xy 234.70489 -98.799142)
			(xy 234.694948 -98.795336) (xy 234.673684 -98.795336) (xy 234.663742 -98.799142) (xy 234.621078 -98.817397)
			(xy 234.532791 -98.845993) (xy 234.442009 -98.865252) (xy 234.349717 -98.874966) (xy 234.303316 -98.875596)
			(xy 234.259735 -98.875093) (xy 234.172991 -98.866554) (xy 234.087498 -98.849575) (xy 234.004075 -98.824318)
			(xy 233.92352 -98.791027) (xy 233.846606 -98.750019) (xy 233.77407 -98.701689) (xy 233.706607 -98.646498)
			(xy 233.644862 -98.584976) (xy 233.589428 -98.517712) (xy 233.540836 -98.445351) (xy 233.519726 -98.40722)
			(xy 233.512868 -98.39452) (xy 233.488738 -98.380296) (xy 233.369612 -98.382074) (xy 233.345736 -98.39706)
			(xy 233.339386 -98.410014) (xy 233.320611 -98.446555) (xy 233.277315 -98.516379) (xy 233.227765 -98.581914)
			(xy 233.172384 -98.6426) (xy 233.111643 -98.697922) (xy 233.04606 -98.747408) (xy 232.976193 -98.790636)
			(xy 232.902638 -98.827237) (xy 232.826022 -98.856901) (xy 232.746997 -98.879374) (xy 232.666237 -98.894464)
			(xy 232.584429 -98.902044) (xy 232.54335 -98.90252) (xy 232.496947 -98.901911) (xy 232.40465 -98.892216)
			(xy 232.313864 -98.872957) (xy 232.225579 -98.844344) (xy 232.182924 -98.826066) (xy 232.172982 -98.82226)
			(xy 232.151718 -98.82226) (xy 232.141776 -98.826066) (xy 232.099108 -98.844312) (xy 232.010823 -98.872909)
			(xy 231.920042 -98.892171) (xy 231.82775 -98.901888) (xy 231.78135 -98.90252) (xy 231.739335 -98.902057)
			(xy 231.655679 -98.894126) (xy 231.573143 -98.878341) (xy 231.492465 -98.854842) (xy 231.414363 -98.823839)
			(xy 231.339533 -98.785607) (xy 231.268642 -98.740488) (xy 231.202323 -98.688883) (xy 231.141167 -98.631254)
			(xy 231.113076 -98.600006) (xy 231.10571 -98.591624) (xy 231.085898 -98.582734) (xy 230.9876 -98.582734)
			(xy 230.967788 -98.591624) (xy 230.960422 -98.600006) (xy 230.932313 -98.631234) (xy 230.871144 -98.688841)
			(xy 230.804819 -98.740427) (xy 230.733927 -98.785534) (xy 230.659101 -98.823758) (xy 230.581005 -98.854761)
			(xy 230.500334 -98.878267) (xy 230.417808 -98.894066) (xy 230.33416 -98.902017) (xy 230.292148 -98.90252)
			(xy 230.245745 -98.901912) (xy 230.153448 -98.892216) (xy 230.062662 -98.872957) (xy 229.974377 -98.844344)
			(xy 229.931722 -98.826066) (xy 229.92178 -98.82226) (xy 229.900516 -98.82226) (xy 229.890574 -98.826066)
			(xy 229.847907 -98.844312) (xy 229.759621 -98.87291) (xy 229.66884 -98.892171) (xy 229.576548 -98.901889)
			(xy 229.530148 -98.90252) (xy 229.487783 -98.902118) (xy 229.403437 -98.894068) (xy 229.320238 -98.878037)
			(xy 229.238939 -98.854169) (xy 229.160278 -98.822682) (xy 229.084966 -98.783859) (xy 229.013685 -98.738053)
			(xy 228.947082 -98.685679) (xy 228.885758 -98.627211) (xy 228.830271 -98.563178) (xy 228.781121 -98.49416)
			(xy 228.738755 -98.420783) (xy 228.703556 -98.343711) (xy 228.675843 -98.263642) (xy 228.655866 -98.181301)
			(xy 228.643808 -98.097434) (xy 228.639776 -98.0128) (xy 228.496115 -98.0128) (xy 228.493369 -98.070428)
			(xy 228.481312 -98.154289) (xy 228.461338 -98.236624) (xy 228.433628 -98.316688) (xy 228.398433 -98.393756)
			(xy 228.356071 -98.467129) (xy 228.306927 -98.536143) (xy 228.251445 -98.600173) (xy 228.190129 -98.658639)
			(xy 228.123532 -98.711012) (xy 228.052258 -98.756818) (xy 227.976953 -98.795642) (xy 227.898299 -98.827131)
			(xy 227.817008 -98.851002) (xy 227.733816 -98.867037) (xy 227.649476 -98.875091) (xy 227.607114 -98.875596)
			(xy 227.560711 -98.875002) (xy 227.468413 -98.865303) (xy 227.377627 -98.84604) (xy 227.289343 -98.817422)
			(xy 227.246688 -98.799142) (xy 227.236746 -98.795336) (xy 227.215482 -98.795336) (xy 227.20554 -98.799142)
			(xy 227.162877 -98.817398) (xy 227.07459 -98.845993) (xy 226.983807 -98.865252) (xy 226.891515 -98.874966)
			(xy 226.845114 -98.875596) (xy 226.803099 -98.875132) (xy 226.719443 -98.867199) (xy 226.636909 -98.851412)
			(xy 226.556231 -98.827912) (xy 226.47813 -98.796908) (xy 226.4033 -98.758677) (xy 226.332409 -98.713559)
			(xy 226.266089 -98.661956) (xy 226.204932 -98.604329) (xy 226.17684 -98.573082) (xy 226.169474 -98.5647)
			(xy 226.149662 -98.55581) (xy 226.051364 -98.55581) (xy 226.031552 -98.5647) (xy 226.024186 -98.573082)
			(xy 225.996091 -98.604322) (xy 225.93492 -98.66193) (xy 225.868594 -98.713516) (xy 225.7977 -98.758621)
			(xy 225.722872 -98.796845) (xy 225.644774 -98.827847) (xy 225.564102 -98.85135) (xy 225.481574 -98.867146)
			(xy 225.397925 -98.875094) (xy 225.355912 -98.875596) (xy 225.309509 -98.875003) (xy 225.217211 -98.865303)
			(xy 225.126425 -98.84604) (xy 225.038141 -98.817423) (xy 224.995486 -98.799142) (xy 224.985544 -98.795336)
			(xy 224.96428 -98.795336) (xy 224.954338 -98.799142) (xy 224.911675 -98.817399) (xy 224.823388 -98.845994)
			(xy 224.732606 -98.865252) (xy 224.640313 -98.874966) (xy 224.593912 -98.875596) (xy 224.550884 -98.875115)
			(xy 224.46523 -98.866789) (xy 224.380781 -98.850235) (xy 224.298323 -98.825606) (xy 224.218628 -98.793132)
			(xy 224.14244 -98.753118) (xy 224.070471 -98.705935) (xy 224.003392 -98.652026) (xy 223.94183 -98.591893)
			(xy 223.88636 -98.526099) (xy 223.837501 -98.455257) (xy 223.816164 -98.417888) (xy 223.811456 -98.410156)
			(xy 223.797725 -98.398375) (xy 223.78076 -98.392092) (xy 223.771714 -98.391726) (xy 223.683068 -98.391726)
			(xy 223.674022 -98.392104) (xy 223.657053 -98.398374) (xy 223.643325 -98.410155) (xy 223.638618 -98.417888)
			(xy 223.61725 -98.45524) (xy 223.568406 -98.526093) (xy 223.512948 -98.591898) (xy 223.451394 -98.652039)
			(xy 223.38432 -98.705954) (xy 223.312352 -98.753139) (xy 223.236163 -98.793153) (xy 223.156466 -98.825623)
			(xy 223.074006 -98.850243) (xy 222.989554 -98.866785) (xy 222.903899 -98.875093) (xy 222.86087 -98.875596)
			(xy 222.814467 -98.874982) (xy 222.72217 -98.865289) (xy 222.631384 -98.846031) (xy 222.5431 -98.81742)
			(xy 222.500444 -98.799142) (xy 222.490502 -98.795336) (xy 222.469238 -98.795336) (xy 222.459296 -98.799142)
			(xy 222.416639 -98.817413) (xy 222.328349 -98.846004) (xy 222.237565 -98.865259) (xy 222.145271 -98.874969)
			(xy 222.09887 -98.875596) (xy 222.056856 -98.875093) (xy 221.973202 -98.867165) (xy 221.890668 -98.851383)
			(xy 221.809991 -98.827888) (xy 221.731889 -98.796889) (xy 221.657059 -98.758662) (xy 221.586168 -98.713549)
			(xy 221.519847 -98.66195) (xy 221.458688 -98.604327) (xy 221.430596 -98.573082) (xy 221.42323 -98.5647)
			(xy 221.403418 -98.55581) (xy 221.30512 -98.55581) (xy 221.285308 -98.5647) (xy 221.277942 -98.573082)
			(xy 221.249817 -98.604295) (xy 221.188651 -98.661904) (xy 221.122328 -98.713491) (xy 221.051439 -98.758599)
			(xy 220.976614 -98.796826) (xy 220.89852 -98.827831) (xy 220.817851 -98.851338) (xy 220.735326 -98.867139)
			(xy 220.65168 -98.875092) (xy 220.609668 -98.875596) (xy 220.563265 -98.874983) (xy 220.470968 -98.865289)
			(xy 220.380182 -98.846032) (xy 220.291898 -98.81742) (xy 220.249242 -98.799142) (xy 220.2393 -98.795336)
			(xy 220.218036 -98.795336) (xy 220.208094 -98.799142) (xy 220.165437 -98.817413) (xy 220.077147 -98.846004)
			(xy 219.986363 -98.865259) (xy 219.894069 -98.874969) (xy 219.847668 -98.875596) (xy 219.806723 -98.875148)
			(xy 219.725182 -98.867601) (xy 219.644679 -98.852594) (xy 219.565896 -98.830252) (xy 219.489499 -98.800765)
			(xy 219.416135 -98.764383) (xy 219.346425 -98.721413) (xy 219.280958 -98.672219) (xy 219.220289 -98.617217)
			(xy 219.164931 -98.556873) (xy 219.13977 -98.524568) (xy 219.132404 -98.514916) (xy 219.110814 -98.504502)
			(xy 219.004388 -98.50628) (xy 218.983052 -98.517456) (xy 218.97594 -98.527362) (xy 218.950986 -98.561702)
			(xy 218.895528 -98.625977) (xy 218.834198 -98.684675) (xy 218.767553 -98.737261) (xy 218.6962 -98.783257)
			(xy 218.620789 -98.822245) (xy 218.542006 -98.853868) (xy 218.460568 -98.87784) (xy 218.377216 -98.893943)
			(xy 218.292709 -98.902029) (xy 218.250262 -98.90252) (xy 218.203867 -98.901914) (xy 218.111579 -98.892276)
			(xy 218.020796 -98.873086) (xy 217.932501 -98.844555) (xy 217.889836 -98.82632) (xy 217.879894 -98.822514)
			(xy 217.85863 -98.822514) (xy 217.848688 -98.82632) (xy 217.806031 -98.844578) (xy 217.717737 -98.873118)
			(xy 217.62695 -98.892308) (xy 217.534659 -98.901937) (xy 217.488262 -98.90252) (xy 217.446255 -98.90201)
			(xy 217.362615 -98.894097) (xy 217.280094 -98.878335) (xy 217.199425 -98.854865) (xy 217.121328 -98.823895)
			(xy 217.046498 -98.785702) (xy 216.975601 -98.740625) (xy 216.909269 -98.689066) (xy 216.848092 -98.631484)
			(xy 216.819988 -98.60026) (xy 216.812622 -98.591878) (xy 216.79281 -98.582988) (xy 216.694512 -98.582988)
			(xy 216.6747 -98.591878) (xy 216.667334 -98.60026) (xy 216.639237 -98.631494) (xy 216.578074 -98.689098)
			(xy 216.511749 -98.740675) (xy 216.440855 -98.785766) (xy 216.366023 -98.823967) (xy 216.287921 -98.854938)
			(xy 216.207246 -98.878404) (xy 216.124717 -98.894154) (xy 216.04107 -98.902048) (xy 215.99906 -98.90252)
			(xy 215.952665 -98.901915) (xy 215.860377 -98.892276) (xy 215.769594 -98.873087) (xy 215.681299 -98.844555)
			(xy 215.638634 -98.82632) (xy 215.628692 -98.822514) (xy 215.607428 -98.822514) (xy 215.597486 -98.82632)
			(xy 215.55483 -98.844579) (xy 215.466535 -98.873119) (xy 215.375748 -98.892308) (xy 215.283457 -98.901937)
			(xy 215.23706 -98.90252) (xy 215.194713 -98.901991) (xy 215.110404 -98.893936) (xy 215.027241 -98.877905)
			(xy 214.94598 -98.854041) (xy 214.867354 -98.822561) (xy 214.792077 -98.78375) (xy 214.720829 -98.737959)
			(xy 214.654257 -98.685603) (xy 214.592963 -98.627157) (xy 214.537502 -98.563148) (xy 214.488376 -98.494158)
			(xy 214.44603 -98.420811) (xy 214.410848 -98.343771) (xy 214.383149 -98.263735) (xy 214.363182 -98.181429)
			(xy 214.351129 -98.097598) (xy 214.347099 -98.013) (xy 0.509016 -98.013) (xy 0.509016 -101.388361)
			(xy 214.756742 -101.388361) (xy 214.756742 -101.303639) (xy 214.764795 -101.219302) (xy 214.780829 -101.136112)
			(xy 214.804697 -101.054822) (xy 214.836185 -100.97617) (xy 214.875007 -100.900867) (xy 214.92081 -100.829595)
			(xy 214.973181 -100.762999) (xy 215.031646 -100.701684) (xy 215.095674 -100.646203) (xy 215.164686 -100.59706)
			(xy 215.238056 -100.5547) (xy 215.315121 -100.519505) (xy 215.395183 -100.491796) (xy 215.477516 -100.471822)
			(xy 215.561375 -100.459765) (xy 215.646 -100.455734) (xy 215.730625 -100.459765) (xy 215.814484 -100.471822)
			(xy 215.896817 -100.491796) (xy 215.976879 -100.519505) (xy 216.053944 -100.5547) (xy 216.127314 -100.59706)
			(xy 216.196326 -100.646203) (xy 216.260354 -100.701684) (xy 216.318819 -100.762999) (xy 216.37119 -100.829595)
			(xy 216.416993 -100.900867) (xy 216.455815 -100.97617) (xy 216.487303 -101.054822) (xy 216.511171 -101.136112)
			(xy 216.527205 -101.219302) (xy 216.535258 -101.303639) (xy 216.535762 -101.346) (xy 216.535258 -101.388361)
			(xy 216.527205 -101.472698) (xy 216.511171 -101.555888) (xy 216.487303 -101.637178) (xy 216.455815 -101.71583)
			(xy 216.450056 -101.727) (xy 268.350492 -101.727) (xy 268.351075 -101.680604) (xy 268.36072 -101.588316)
			(xy 268.379916 -101.497532) (xy 268.408454 -101.409239) (xy 268.426692 -101.366574) (xy 268.430498 -101.356632)
			(xy 268.430498 -101.335368) (xy 268.426692 -101.325426) (xy 268.408447 -101.282764) (xy 268.379903 -101.194471)
			(xy 268.36071 -101.103686) (xy 268.351077 -101.011396) (xy 268.350492 -100.965) (xy 268.351075 -100.918604)
			(xy 268.36072 -100.826316) (xy 268.379916 -100.735532) (xy 268.408454 -100.647239) (xy 268.426692 -100.604574)
			(xy 268.430498 -100.594632) (xy 268.430498 -100.573368) (xy 268.426692 -100.563426) (xy 268.408447 -100.520764)
			(xy 268.379903 -100.432471) (xy 268.36071 -100.341686) (xy 268.351077 -100.249396) (xy 268.350492 -100.203)
			(xy 268.351075 -100.156604) (xy 268.36072 -100.064316) (xy 268.379916 -99.973532) (xy 268.408454 -99.885239)
			(xy 268.426692 -99.842574) (xy 268.430498 -99.832632) (xy 268.430498 -99.811368) (xy 268.426692 -99.801426)
			(xy 268.408447 -99.758764) (xy 268.379903 -99.670471) (xy 268.36071 -99.579686) (xy 268.351077 -99.487396)
			(xy 268.350492 -99.441) (xy 268.351075 -99.394604) (xy 268.36072 -99.302316) (xy 268.379916 -99.211532)
			(xy 268.408454 -99.123239) (xy 268.426692 -99.080574) (xy 268.430498 -99.070632) (xy 268.430498 -99.049368)
			(xy 268.426692 -99.039426) (xy 268.408447 -98.996764) (xy 268.379903 -98.908471) (xy 268.36071 -98.817686)
			(xy 268.351077 -98.725396) (xy 268.350492 -98.679) (xy 268.351075 -98.632604) (xy 268.36072 -98.540316)
			(xy 268.379916 -98.449532) (xy 268.408454 -98.361239) (xy 268.426692 -98.318574) (xy 268.430498 -98.308632)
			(xy 268.430498 -98.287368) (xy 268.426692 -98.277426) (xy 268.408447 -98.234764) (xy 268.379903 -98.146471)
			(xy 268.36071 -98.055686) (xy 268.351077 -97.963396) (xy 268.350492 -97.917) (xy 268.350967 -97.875898)
			(xy 268.358552 -97.794043) (xy 268.373657 -97.713238) (xy 268.396153 -97.634171) (xy 268.425849 -97.557517)
			(xy 268.462491 -97.48393) (xy 268.505766 -97.414038) (xy 268.555306 -97.348437) (xy 268.610687 -97.287687)
			(xy 268.671437 -97.232306) (xy 268.737038 -97.182766) (xy 268.80693 -97.139491) (xy 268.880517 -97.102849)
			(xy 268.957171 -97.073153) (xy 269.036238 -97.050657) (xy 269.117043 -97.035552) (xy 269.198898 -97.027967)
			(xy 269.24 -97.027492) (xy 269.286396 -97.028075) (xy 269.378684 -97.03772) (xy 269.469468 -97.056916)
			(xy 269.557761 -97.085454) (xy 269.600426 -97.103692) (xy 269.610368 -97.107498) (xy 269.631632 -97.107498)
			(xy 269.641574 -97.103692) (xy 269.684236 -97.085447) (xy 269.772529 -97.056903) (xy 269.863314 -97.03771)
			(xy 269.955604 -97.028077) (xy 270.002 -97.027492) (xy 270.048396 -97.028075) (xy 270.140684 -97.03772)
			(xy 270.231468 -97.056916) (xy 270.319761 -97.085454) (xy 270.362426 -97.103692) (xy 270.372368 -97.107498)
			(xy 270.393632 -97.107498) (xy 270.403574 -97.103692) (xy 270.446236 -97.085447) (xy 270.534529 -97.056903)
			(xy 270.625314 -97.03771) (xy 270.717604 -97.028077) (xy 270.764 -97.027492) (xy 270.810396 -97.028075)
			(xy 270.902684 -97.03772) (xy 270.993468 -97.056916) (xy 271.081761 -97.085454) (xy 271.124426 -97.103692)
			(xy 271.134368 -97.107498) (xy 271.155632 -97.107498) (xy 271.165574 -97.103692) (xy 271.208236 -97.085447)
			(xy 271.296529 -97.056903) (xy 271.387314 -97.03771) (xy 271.479604 -97.028077) (xy 271.526 -97.027492)
			(xy 271.572396 -97.028075) (xy 271.664684 -97.03772) (xy 271.755468 -97.056916) (xy 271.843761 -97.085454)
			(xy 271.886426 -97.103692) (xy 271.896368 -97.107498) (xy 271.917632 -97.107498) (xy 271.927574 -97.103692)
			(xy 271.970236 -97.085447) (xy 272.058529 -97.056903) (xy 272.149314 -97.03771) (xy 272.241604 -97.028077)
			(xy 272.288 -97.027492) (xy 272.329102 -97.027967) (xy 272.410957 -97.035552) (xy 272.491762 -97.050657)
			(xy 272.570829 -97.073153) (xy 272.647483 -97.102849) (xy 272.72107 -97.139491) (xy 272.790962 -97.182766)
			(xy 272.856563 -97.232306) (xy 272.917313 -97.287687) (xy 272.972694 -97.348437) (xy 273.022234 -97.414038)
			(xy 273.065509 -97.48393) (xy 273.102151 -97.557517) (xy 273.131847 -97.634171) (xy 273.154343 -97.713238)
			(xy 273.169448 -97.794043) (xy 273.177033 -97.875898) (xy 273.177508 -97.917) (xy 273.176925 -97.963396)
			(xy 273.16728 -98.055684) (xy 273.148084 -98.146468) (xy 273.119546 -98.234761) (xy 273.101308 -98.277426)
			(xy 273.097502 -98.287368) (xy 273.097502 -98.308632) (xy 273.101308 -98.318574) (xy 273.119553 -98.361236)
			(xy 273.148097 -98.449529) (xy 273.16729 -98.540314) (xy 273.176923 -98.632604) (xy 273.177508 -98.679)
			(xy 273.177033 -98.720102) (xy 273.169448 -98.801957) (xy 273.154343 -98.882762) (xy 273.131847 -98.961829)
			(xy 273.102151 -99.038483) (xy 273.065509 -99.11207) (xy 273.022234 -99.181962) (xy 272.972694 -99.247563)
			(xy 272.917313 -99.308313) (xy 272.856563 -99.363694) (xy 272.790962 -99.413234) (xy 272.72107 -99.456509)
			(xy 272.647483 -99.493151) (xy 272.570829 -99.522847) (xy 272.491762 -99.545343) (xy 272.410957 -99.560448)
			(xy 272.329102 -99.568033) (xy 272.288 -99.568508) (xy 272.241604 -99.567925) (xy 272.149316 -99.55828)
			(xy 272.058532 -99.539084) (xy 271.970239 -99.510546) (xy 271.927574 -99.492308) (xy 271.917632 -99.488502)
			(xy 271.896368 -99.488502) (xy 271.886426 -99.492308) (xy 271.853507 -99.506537) (xy 271.785822 -99.530257)
			(xy 271.716442 -99.548437) (xy 271.681194 -99.555046) (xy 271.67107 -99.557344) (xy 271.653749 -99.568749)
			(xy 271.642344 -99.58607) (xy 271.640046 -99.596194) (xy 271.633416 -99.631437) (xy 271.61522 -99.70081)
			(xy 271.591513 -99.768498) (xy 271.577308 -99.801426) (xy 271.573502 -99.811368) (xy 271.573502 -99.832632)
			(xy 271.577308 -99.842574) (xy 271.591537 -99.875493) (xy 271.615257 -99.943178) (xy 271.633437 -100.012558)
			(xy 271.640046 -100.047806) (xy 271.642344 -100.05793) (xy 271.653749 -100.075251) (xy 271.67107 -100.086656)
			(xy 271.681194 -100.088954) (xy 271.716437 -100.095584) (xy 271.78581 -100.11378) (xy 271.853498 -100.137487)
			(xy 271.886426 -100.151692) (xy 271.896368 -100.155498) (xy 271.917632 -100.155498) (xy 271.927574 -100.151692)
			(xy 271.970236 -100.133447) (xy 272.058529 -100.104903) (xy 272.149314 -100.08571) (xy 272.241604 -100.076077)
			(xy 272.288 -100.075492) (xy 272.329102 -100.075967) (xy 272.410957 -100.083552) (xy 272.491762 -100.098657)
			(xy 272.570829 -100.121153) (xy 272.647483 -100.150849) (xy 272.72107 -100.187491) (xy 272.790962 -100.230766)
			(xy 272.856563 -100.280306) (xy 272.917313 -100.335687) (xy 272.972694 -100.396437) (xy 273.022234 -100.462038)
			(xy 273.065509 -100.53193) (xy 273.102151 -100.605517) (xy 273.131847 -100.682171) (xy 273.154343 -100.761238)
			(xy 273.169448 -100.842043) (xy 273.177033 -100.923898) (xy 273.177508 -100.965) (xy 273.176925 -101.011396)
			(xy 273.16728 -101.103684) (xy 273.148084 -101.194468) (xy 273.119546 -101.282761) (xy 273.101308 -101.325426)
			(xy 273.097502 -101.335368) (xy 273.097502 -101.356632) (xy 273.101308 -101.366574) (xy 273.119553 -101.409236)
			(xy 273.148097 -101.497529) (xy 273.16729 -101.588314) (xy 273.176923 -101.680604) (xy 273.177508 -101.727)
			(xy 273.177087 -101.76701) (xy 273.169907 -101.846708) (xy 273.155596 -101.925439) (xy 273.134269 -102.002565)
			(xy 273.106099 -102.077463) (xy 273.071314 -102.149528) (xy 273.030196 -102.218176) (xy 272.983076 -102.282852)
			(xy 272.957036 -102.313232) (xy 272.947892 -102.3239) (xy 272.942812 -102.350824) (xy 272.982436 -102.460806)
			(xy 273.003518 -102.478332) (xy 273.017488 -102.480618) (xy 273.058748 -102.487682) (xy 273.139783 -102.5087)
			(xy 273.202283 -102.531361) (xy 275.081742 -102.531361) (xy 275.081742 -102.446639) (xy 275.089795 -102.362302)
			(xy 275.105829 -102.279112) (xy 275.129697 -102.197822) (xy 275.161185 -102.11917) (xy 275.200007 -102.043867)
			(xy 275.24581 -101.972595) (xy 275.298181 -101.905999) (xy 275.356646 -101.844684) (xy 275.420674 -101.789203)
			(xy 275.489686 -101.74006) (xy 275.563056 -101.6977) (xy 275.640121 -101.662505) (xy 275.720183 -101.634796)
			(xy 275.802516 -101.614822) (xy 275.886375 -101.602765) (xy 275.971 -101.598734) (xy 276.055625 -101.602765)
			(xy 276.139484 -101.614822) (xy 276.221817 -101.634796) (xy 276.301879 -101.662505) (xy 276.378944 -101.6977)
			(xy 276.452314 -101.74006) (xy 276.521326 -101.789203) (xy 276.585354 -101.844684) (xy 276.643819 -101.905999)
			(xy 276.69619 -101.972595) (xy 276.741993 -102.043867) (xy 276.780815 -102.11917) (xy 276.812303 -102.197822)
			(xy 276.836171 -102.279112) (xy 276.852205 -102.362302) (xy 276.860258 -102.446639) (xy 276.860762 -102.489)
			(xy 276.860258 -102.531361) (xy 276.852205 -102.615698) (xy 276.836171 -102.698888) (xy 276.812303 -102.780178)
			(xy 276.780815 -102.85883) (xy 276.741993 -102.934133) (xy 276.69619 -103.005405) (xy 276.643819 -103.072001)
			(xy 276.585354 -103.133316) (xy 276.521326 -103.188797) (xy 276.452314 -103.23794) (xy 276.378944 -103.2803)
			(xy 276.301879 -103.315495) (xy 276.221817 -103.343204) (xy 276.139484 -103.363178) (xy 276.055625 -103.375235)
			(xy 275.971 -103.379267) (xy 275.886375 -103.375235) (xy 275.802516 -103.363178) (xy 275.720183 -103.343204)
			(xy 275.640121 -103.315495) (xy 275.563056 -103.2803) (xy 275.489686 -103.23794) (xy 275.420674 -103.188797)
			(xy 275.356646 -103.133316) (xy 275.298181 -103.072001) (xy 275.24581 -103.005405) (xy 275.200007 -102.934133)
			(xy 275.161185 -102.85883) (xy 275.129697 -102.780178) (xy 275.105829 -102.698888) (xy 275.089795 -102.615698)
			(xy 275.081742 -102.531361) (xy 273.202283 -102.531361) (xy 273.218486 -102.537236) (xy 273.29416 -102.573039)
			(xy 273.366137 -102.615792) (xy 273.43378 -102.665117) (xy 273.49649 -102.720577) (xy 273.553714 -102.781682)
			(xy 273.604945 -102.847892) (xy 273.649731 -102.918622) (xy 273.687675 -102.993246) (xy 273.718442 -103.071104)
			(xy 273.741759 -103.151508) (xy 273.757421 -103.233746) (xy 273.76529 -103.317092) (xy 273.765772 -103.35895)
			(xy 273.765268 -103.401298) (xy 273.757217 -103.485612) (xy 273.741188 -103.568778) (xy 273.717327 -103.650045)
			(xy 273.685848 -103.728675) (xy 273.647037 -103.803956) (xy 273.601247 -103.875208) (xy 273.548891 -103.941784)
			(xy 273.490443 -104.003082) (xy 273.426433 -104.058547) (xy 273.357441 -104.107676) (xy 273.284091 -104.150025)
			(xy 273.207048 -104.185209) (xy 273.127009 -104.212911) (xy 273.0447 -104.232879) (xy 272.960865 -104.244932)
			(xy 272.876264 -104.248963) (xy 272.791663 -104.244932) (xy 272.707828 -104.232879) (xy 272.625519 -104.212911)
			(xy 272.54548 -104.185209) (xy 272.468437 -104.150025) (xy 272.395087 -104.107676) (xy 272.326095 -104.058547)
			(xy 272.262085 -104.003082) (xy 272.203637 -103.941784) (xy 272.151281 -103.875208) (xy 272.105491 -103.803956)
			(xy 272.06668 -103.728675) (xy 272.035201 -103.650045) (xy 272.01134 -103.568778) (xy 271.995311 -103.485612)
			(xy 271.98726 -103.401298) (xy 271.986756 -103.35895) (xy 271.987216 -103.318941) (xy 271.994392 -103.239244)
			(xy 272.008698 -103.160515) (xy 272.03002 -103.083389) (xy 272.058184 -103.008491) (xy 272.092963 -102.936426)
			(xy 272.134076 -102.867777) (xy 272.181191 -102.803099) (xy 272.207228 -102.772718) (xy 272.216372 -102.76205)
			(xy 272.221452 -102.735126) (xy 272.181828 -102.625144) (xy 272.160746 -102.607618) (xy 272.146776 -102.605332)
			(xy 272.109108 -102.598853) (xy 272.034963 -102.580278) (xy 271.962681 -102.555417) (xy 271.927574 -102.540308)
			(xy 271.917632 -102.536502) (xy 271.896368 -102.536502) (xy 271.886426 -102.540308) (xy 271.843764 -102.558553)
			(xy 271.755471 -102.587097) (xy 271.664686 -102.60629) (xy 271.572396 -102.615923) (xy 271.526 -102.616508)
			(xy 271.479604 -102.615925) (xy 271.387316 -102.60628) (xy 271.296532 -102.587084) (xy 271.208239 -102.558546)
			(xy 271.165574 -102.540308) (xy 271.155632 -102.536502) (xy 271.134368 -102.536502) (xy 271.124426 -102.540308)
			(xy 271.081764 -102.558553) (xy 270.993471 -102.587097) (xy 270.902686 -102.60629) (xy 270.810396 -102.615923)
			(xy 270.764 -102.616508) (xy 270.717604 -102.615925) (xy 270.625316 -102.60628) (xy 270.534532 -102.587084)
			(xy 270.446239 -102.558546) (xy 270.403574 -102.540308) (xy 270.393632 -102.536502) (xy 270.372368 -102.536502)
			(xy 270.362426 -102.540308) (xy 270.319764 -102.558553) (xy 270.231471 -102.587097) (xy 270.140686 -102.60629)
			(xy 270.048396 -102.615923) (xy 270.002 -102.616508) (xy 269.955604 -102.615925) (xy 269.863316 -102.60628)
			(xy 269.772532 -102.587084) (xy 269.684239 -102.558546) (xy 269.641574 -102.540308) (xy 269.631632 -102.536502)
			(xy 269.610368 -102.536502) (xy 269.600426 -102.540308) (xy 269.557764 -102.558553) (xy 269.469471 -102.587097)
			(xy 269.378686 -102.60629) (xy 269.286396 -102.615923) (xy 269.24 -102.616508) (xy 269.198898 -102.616033)
			(xy 269.117043 -102.608448) (xy 269.036238 -102.593343) (xy 268.957171 -102.570847) (xy 268.880517 -102.541151)
			(xy 268.80693 -102.504509) (xy 268.737038 -102.461234) (xy 268.671437 -102.411694) (xy 268.610687 -102.356313)
			(xy 268.555306 -102.295563) (xy 268.505766 -102.229962) (xy 268.462491 -102.16007) (xy 268.425849 -102.086483)
			(xy 268.396153 -102.009829) (xy 268.373657 -101.930762) (xy 268.358552 -101.849957) (xy 268.350967 -101.768102)
			(xy 268.350492 -101.727) (xy 216.450056 -101.727) (xy 216.416993 -101.791133) (xy 216.37119 -101.862405)
			(xy 216.318819 -101.929001) (xy 216.260354 -101.990316) (xy 216.196326 -102.045797) (xy 216.127314 -102.09494)
			(xy 216.053944 -102.1373) (xy 215.976879 -102.172495) (xy 215.896817 -102.200204) (xy 215.814484 -102.220178)
			(xy 215.730625 -102.232235) (xy 215.646 -102.236267) (xy 215.561375 -102.232235) (xy 215.477516 -102.220178)
			(xy 215.395183 -102.200204) (xy 215.315121 -102.172495) (xy 215.238056 -102.1373) (xy 215.164686 -102.09494)
			(xy 215.095674 -102.045797) (xy 215.031646 -101.990316) (xy 214.973181 -101.929001) (xy 214.92081 -101.862405)
			(xy 214.875007 -101.791133) (xy 214.836185 -101.71583) (xy 214.804697 -101.637178) (xy 214.780829 -101.555888)
			(xy 214.764795 -101.472698) (xy 214.756742 -101.388361) (xy 0.509016 -101.388361) (xy 0.509016 -108.3818)
			(xy 28.498292 -108.3818) (xy 28.498875 -108.335404) (xy 28.50852 -108.243116) (xy 28.527716 -108.152332)
			(xy 28.556254 -108.064039) (xy 28.574492 -108.021374) (xy 28.578397 -108.011452) (xy 28.578397 -107.990148)
			(xy 28.574492 -107.980226) (xy 28.556247 -107.937564) (xy 28.527703 -107.849271) (xy 28.50851 -107.758486)
			(xy 28.498877 -107.666196) (xy 28.498292 -107.6198) (xy 28.498723 -107.581372) (xy 28.505365 -107.504803)
			(xy 28.518591 -107.429093) (xy 28.538303 -107.354808) (xy 28.564353 -107.282501) (xy 28.58008 -107.247436)
			(xy 28.584223 -107.237163) (xy 28.584223 -107.215037) (xy 28.58008 -107.204764) (xy 28.564356 -107.169698)
			(xy 28.53831 -107.097389) (xy 28.518597 -107.023104) (xy 28.505365 -106.947396) (xy 28.498711 -106.870828)
			(xy 28.498292 -106.8324) (xy 28.498875 -106.786004) (xy 28.50852 -106.693716) (xy 28.527716 -106.602932)
			(xy 28.556254 -106.514639) (xy 28.574492 -106.471974) (xy 28.578397 -106.462052) (xy 28.578397 -106.440748)
			(xy 28.574492 -106.430826) (xy 28.556247 -106.388164) (xy 28.527703 -106.299871) (xy 28.50851 -106.209086)
			(xy 28.498877 -106.116796) (xy 28.498292 -106.0704) (xy 28.498875 -106.024004) (xy 28.50852 -105.931716)
			(xy 28.527716 -105.840932) (xy 28.556254 -105.752639) (xy 28.574492 -105.709974) (xy 28.578397 -105.700052)
			(xy 28.578397 -105.678748) (xy 28.574492 -105.668826) (xy 28.556247 -105.626164) (xy 28.527703 -105.537871)
			(xy 28.50851 -105.447086) (xy 28.498877 -105.354796) (xy 28.498292 -105.3084) (xy 28.498875 -105.262004)
			(xy 28.50852 -105.169716) (xy 28.527716 -105.078932) (xy 28.556254 -104.990639) (xy 28.574492 -104.947974)
			(xy 28.578397 -104.938052) (xy 28.578397 -104.916748) (xy 28.574492 -104.906826) (xy 28.556247 -104.864164)
			(xy 28.527703 -104.775871) (xy 28.50851 -104.685086) (xy 28.498877 -104.592796) (xy 28.498292 -104.5464)
			(xy 28.498875 -104.500004) (xy 28.50852 -104.407716) (xy 28.527716 -104.316932) (xy 28.556254 -104.228639)
			(xy 28.574492 -104.185974) (xy 28.578397 -104.176052) (xy 28.578397 -104.154748) (xy 28.574492 -104.144826)
			(xy 28.556247 -104.102164) (xy 28.527703 -104.013871) (xy 28.50851 -103.923086) (xy 28.498877 -103.830796)
			(xy 28.498292 -103.7844) (xy 28.498767 -103.743298) (xy 28.506352 -103.661443) (xy 28.521457 -103.580638)
			(xy 28.543953 -103.501571) (xy 28.573649 -103.424917) (xy 28.610291 -103.35133) (xy 28.653566 -103.281438)
			(xy 28.703106 -103.215837) (xy 28.758487 -103.155087) (xy 28.819237 -103.099706) (xy 28.884838 -103.050166)
			(xy 28.95473 -103.006891) (xy 29.028317 -102.970249) (xy 29.104971 -102.940553) (xy 29.184038 -102.918057)
			(xy 29.264843 -102.902952) (xy 29.346698 -102.895367) (xy 29.3878 -102.894892) (xy 29.433417 -102.895466)
			(xy 29.524172 -102.904799) (xy 29.613497 -102.923367) (xy 29.700453 -102.950974) (xy 29.78413 -102.987332)
			(xy 29.824172 -103.009192) (xy 29.832335 -103.013339) (xy 29.8504 -103.0162) (xy 29.86831 -103.012491)
			(xy 29.876242 -103.007922) (xy 29.911906 -102.985856) (xy 29.986639 -102.947783) (xy 30.064625 -102.916916)
			(xy 30.145171 -102.89353) (xy 30.227561 -102.877832) (xy 30.311064 -102.869963) (xy 30.353 -102.869492)
			(xy 30.39679 -102.86998) (xy 30.483949 -102.878545) (xy 30.569843 -102.89564) (xy 30.65364 -102.921101)
			(xy 30.734526 -102.95468) (xy 30.77337 -102.974902) (xy 30.784836 -102.98032) (xy 30.810164 -102.98032)
			(xy 30.82163 -102.974902) (xy 30.860471 -102.954677) (xy 30.941366 -102.921126) (xy 31.025164 -102.89568)
			(xy 31.111056 -102.878584) (xy 31.198212 -102.870005) (xy 31.242 -102.869492) (xy 31.283102 -102.869967)
			(xy 31.364957 -102.877552) (xy 31.445762 -102.892657) (xy 31.524829 -102.915153) (xy 31.601483 -102.944849)
			(xy 31.67507 -102.981491) (xy 31.744962 -103.024766) (xy 31.810563 -103.074306) (xy 31.871313 -103.129687)
			(xy 31.926694 -103.190437) (xy 31.976234 -103.256038) (xy 32.019509 -103.32593) (xy 32.056151 -103.399517)
			(xy 32.085847 -103.476171) (xy 32.108343 -103.555238) (xy 32.123448 -103.636043) (xy 32.131033 -103.717898)
			(xy 32.131508 -103.759) (xy 32.130925 -103.805396) (xy 32.12128 -103.897684) (xy 32.102084 -103.988468)
			(xy 32.073546 -104.076761) (xy 32.055308 -104.119426) (xy 32.051502 -104.129368) (xy 32.051502 -104.150632)
			(xy 32.055308 -104.160574) (xy 32.073553 -104.203236) (xy 32.102097 -104.291529) (xy 32.12129 -104.382314)
			(xy 32.130923 -104.474604) (xy 32.131508 -104.521) (xy 32.130925 -104.567396) (xy 32.12128 -104.659684)
			(xy 32.102084 -104.750468) (xy 32.073546 -104.838761) (xy 32.055308 -104.881426) (xy 32.051502 -104.891368)
			(xy 32.051502 -104.912632) (xy 32.055308 -104.922574) (xy 32.073553 -104.965236) (xy 32.102097 -105.053529)
			(xy 32.12129 -105.144314) (xy 32.130923 -105.236604) (xy 32.131508 -105.283) (xy 32.130925 -105.329396)
			(xy 32.12128 -105.421684) (xy 32.102084 -105.512468) (xy 32.073546 -105.600761) (xy 32.055308 -105.643426)
			(xy 32.051502 -105.653368) (xy 32.051502 -105.674632) (xy 32.055308 -105.684574) (xy 32.073553 -105.727236)
			(xy 32.102097 -105.815529) (xy 32.12129 -105.906314) (xy 32.130923 -105.998604) (xy 32.131508 -106.045)
			(xy 32.130925 -106.091396) (xy 32.12128 -106.183684) (xy 32.102084 -106.274468) (xy 32.073546 -106.362761)
			(xy 32.055308 -106.405426) (xy 32.051502 -106.415368) (xy 32.051502 -106.436632) (xy 32.055308 -106.446574)
			(xy 32.073553 -106.489236) (xy 32.102097 -106.577529) (xy 32.12129 -106.668314) (xy 32.130923 -106.760604)
			(xy 32.131508 -106.807) (xy 32.131149 -106.845449) (xy 32.124566 -106.922065) (xy 32.111388 -106.997826)
			(xy 32.091715 -107.072165) (xy 32.065692 -107.144526) (xy 32.049974 -107.179618) (xy 32.045874 -107.189831)
			(xy 32.045885 -107.211818) (xy 32.049974 -107.222036) (xy 32.065681 -107.257103) (xy 32.091668 -107.329421)
			(xy 32.111325 -107.40371) (xy 32.124505 -107.479417) (xy 32.131112 -107.555977) (xy 32.131508 -107.5944)
			(xy 32.130925 -107.640796) (xy 32.12128 -107.733084) (xy 32.102084 -107.823868) (xy 32.073546 -107.912161)
			(xy 32.055308 -107.954826) (xy 32.051403 -107.964748) (xy 32.051403 -107.986052) (xy 32.055308 -107.995974)
			(xy 32.073553 -108.038636) (xy 32.102097 -108.126929) (xy 32.12129 -108.217714) (xy 32.130923 -108.310004)
			(xy 32.131508 -108.3564) (xy 38.937692 -108.3564) (xy 38.938275 -108.310004) (xy 38.94792 -108.217716)
			(xy 38.967116 -108.126932) (xy 38.995654 -108.038639) (xy 39.013892 -107.995974) (xy 39.017797 -107.986052)
			(xy 39.017797 -107.964748) (xy 39.013892 -107.954826) (xy 38.995647 -107.912164) (xy 38.967103 -107.823871)
			(xy 38.94791 -107.733086) (xy 38.938277 -107.640796) (xy 38.937692 -107.5944) (xy 38.938251 -107.550173)
			(xy 38.947033 -107.462156) (xy 38.964509 -107.375446) (xy 38.990508 -107.2909) (xy 39.024773 -107.209352)
			(xy 39.045388 -107.17022) (xy 39.050228 -107.160228) (xy 39.051661 -107.138093) (xy 39.048182 -107.127548)
			(xy 39.033858 -107.089132) (xy 39.011486 -107.010251) (xy 38.996473 -106.929644) (xy 38.988949 -106.847997)
			(xy 38.988492 -106.807) (xy 38.989075 -106.760604) (xy 38.99872 -106.668316) (xy 39.017916 -106.577532)
			(xy 39.046454 -106.489239) (xy 39.064692 -106.446574) (xy 39.068498 -106.436632) (xy 39.068498 -106.415368)
			(xy 39.064692 -106.405426) (xy 39.046447 -106.362764) (xy 39.017903 -106.274471) (xy 38.99871 -106.183686)
			(xy 38.989077 -106.091396) (xy 38.988492 -106.045) (xy 38.989075 -105.998604) (xy 38.99872 -105.906316)
			(xy 39.017916 -105.815532) (xy 39.046454 -105.727239) (xy 39.064692 -105.684574) (xy 39.068498 -105.674632)
			(xy 39.068498 -105.653368) (xy 39.064692 -105.643426) (xy 39.046447 -105.600764) (xy 39.017903 -105.512471)
			(xy 38.99871 -105.421686) (xy 38.989077 -105.329396) (xy 38.988492 -105.283) (xy 38.989075 -105.236604)
			(xy 38.99872 -105.144316) (xy 39.017916 -105.053532) (xy 39.046454 -104.965239) (xy 39.064692 -104.922574)
			(xy 39.068498 -104.912632) (xy 39.068498 -104.891368) (xy 39.064692 -104.881426) (xy 39.046447 -104.838764)
			(xy 39.017903 -104.750471) (xy 38.99871 -104.659686) (xy 38.989077 -104.567396) (xy 38.988492 -104.521)
			(xy 38.989075 -104.474604) (xy 38.99872 -104.382316) (xy 39.017916 -104.291532) (xy 39.046454 -104.203239)
			(xy 39.064692 -104.160574) (xy 39.068498 -104.150632) (xy 39.068498 -104.129368) (xy 39.064692 -104.119426)
			(xy 39.046447 -104.076764) (xy 39.017903 -103.988471) (xy 38.99871 -103.897686) (xy 38.989077 -103.805396)
			(xy 38.988492 -103.759) (xy 38.988967 -103.717898) (xy 38.996552 -103.636043) (xy 39.011657 -103.555238)
			(xy 39.034153 -103.476171) (xy 39.063849 -103.399517) (xy 39.100491 -103.32593) (xy 39.143766 -103.256038)
			(xy 39.193306 -103.190437) (xy 39.248687 -103.129687) (xy 39.309437 -103.074306) (xy 39.375038 -103.024766)
			(xy 39.44493 -102.981491) (xy 39.518517 -102.944849) (xy 39.595171 -102.915153) (xy 39.674238 -102.892657)
			(xy 39.755043 -102.877552) (xy 39.836898 -102.869967) (xy 39.878 -102.869492) (xy 39.92179 -102.86998)
			(xy 40.008949 -102.878545) (xy 40.094843 -102.89564) (xy 40.17864 -102.921101) (xy 40.259526 -102.95468)
			(xy 40.29837 -102.974902) (xy 40.309836 -102.98032) (xy 40.335164 -102.98032) (xy 40.34663 -102.974902)
			(xy 40.385471 -102.954677) (xy 40.466366 -102.921126) (xy 40.550164 -102.89568) (xy 40.636056 -102.878584)
			(xy 40.723212 -102.870005) (xy 40.767 -102.869492) (xy 40.813379 -102.870097) (xy 40.905633 -102.879747)
			(xy 40.996382 -102.898942) (xy 41.084642 -102.927473) (xy 41.169455 -102.965032) (xy 41.209976 -102.987602)
			(xy 41.221253 -102.993254) (xy 41.246432 -102.993937) (xy 41.257982 -102.988872) (xy 41.295102 -102.970822)
			(xy 41.372033 -102.940898) (xy 41.451405 -102.918227) (xy 41.532535 -102.903004) (xy 41.614727 -102.89536)
			(xy 41.656 -102.894892) (xy 41.697102 -102.895367) (xy 41.778957 -102.902952) (xy 41.859762 -102.918057)
			(xy 41.938829 -102.940553) (xy 42.015483 -102.970249) (xy 42.08907 -103.006891) (xy 42.158962 -103.050166)
			(xy 42.224563 -103.099706) (xy 42.285313 -103.155087) (xy 42.340694 -103.215837) (xy 42.390234 -103.281438)
			(xy 42.433509 -103.35133) (xy 42.470151 -103.424917) (xy 42.499847 -103.501571) (xy 42.522343 -103.580638)
			(xy 42.537448 -103.661443) (xy 42.545033 -103.743298) (xy 42.545508 -103.7844) (xy 42.544925 -103.830796)
			(xy 42.53528 -103.923084) (xy 42.516084 -104.013868) (xy 42.487546 -104.102161) (xy 42.469308 -104.144826)
			(xy 42.465403 -104.154748) (xy 42.465403 -104.176052) (xy 42.469308 -104.185974) (xy 42.487553 -104.228636)
			(xy 42.516097 -104.316929) (xy 42.53529 -104.407714) (xy 42.544923 -104.500004) (xy 42.545508 -104.5464)
			(xy 42.544925 -104.592796) (xy 42.53528 -104.685084) (xy 42.516084 -104.775868) (xy 42.487546 -104.864161)
			(xy 42.469308 -104.906826) (xy 42.465403 -104.916748) (xy 42.465403 -104.938052) (xy 42.469308 -104.947974)
			(xy 42.487553 -104.990636) (xy 42.516097 -105.078929) (xy 42.53529 -105.169714) (xy 42.544923 -105.262004)
			(xy 42.545508 -105.3084) (xy 42.544925 -105.354796) (xy 42.53528 -105.447084) (xy 42.516084 -105.537868)
			(xy 42.487546 -105.626161) (xy 42.469308 -105.668826) (xy 42.465403 -105.678748) (xy 42.465403 -105.700052)
			(xy 42.469308 -105.709974) (xy 42.487553 -105.752636) (xy 42.516097 -105.840929) (xy 42.525034 -105.883202)
			(xy 201.446892 -105.883202) (xy 201.447476 -105.836806) (xy 201.45712 -105.744518) (xy 201.476316 -105.653734)
			(xy 201.504854 -105.565441) (xy 201.523092 -105.522776) (xy 201.526896 -105.512833) (xy 201.526897 -105.49157)
			(xy 201.523092 -105.481628) (xy 201.504848 -105.438966) (xy 201.476304 -105.350673) (xy 201.45711 -105.259888)
			(xy 201.447477 -105.167598) (xy 201.446892 -105.121202) (xy 201.447364 -105.078635) (xy 201.455472 -104.993887)
			(xy 201.471642 -104.910303) (xy 201.495727 -104.828647) (xy 201.511154 -104.78897) (xy 201.514396 -104.779715)
			(xy 201.514403 -104.760122) (xy 201.511154 -104.75087) (xy 201.495726 -104.711195) (xy 201.47165 -104.629536)
			(xy 201.455485 -104.545952) (xy 201.447378 -104.461205) (xy 201.446892 -104.418638) (xy 201.447488 -104.372243)
			(xy 201.457129 -104.279955) (xy 201.476321 -104.189171) (xy 201.504856 -104.100877) (xy 201.523092 -104.058212)
			(xy 201.526875 -104.048263) (xy 201.526889 -104.027006) (xy 201.523092 -104.017064) (xy 201.50486 -103.974397)
			(xy 201.476312 -103.886106) (xy 201.457116 -103.795323) (xy 201.447479 -103.703034) (xy 201.446892 -103.656638)
			(xy 201.447488 -103.610243) (xy 201.457129 -103.517955) (xy 201.476321 -103.427171) (xy 201.504856 -103.338877)
			(xy 201.523092 -103.296212) (xy 201.526875 -103.286263) (xy 201.526889 -103.265006) (xy 201.523092 -103.255064)
			(xy 201.50486 -103.212397) (xy 201.476312 -103.124106) (xy 201.457116 -103.033323) (xy 201.447479 -102.941034)
			(xy 201.446892 -102.894638) (xy 201.447449 -102.853533) (xy 201.455029 -102.771674) (xy 201.470129 -102.690863)
			(xy 201.492619 -102.61179) (xy 201.522308 -102.535128) (xy 201.558942 -102.461532) (xy 201.60221 -102.39163)
			(xy 201.651741 -102.326017) (xy 201.707115 -102.265254) (xy 201.767857 -102.209858) (xy 201.833451 -102.160301)
			(xy 201.903337 -102.117007) (xy 201.976919 -102.080345) (xy 202.053569 -102.050627) (xy 202.132634 -102.028106)
			(xy 202.213439 -102.012976) (xy 202.295295 -102.005364) (xy 202.3364 -102.004876) (xy 202.38045 -102.00545)
			(xy 202.468114 -102.014227) (xy 202.554483 -102.031616) (xy 202.638713 -102.057447) (xy 202.679554 -102.073964)
			(xy 202.688564 -102.077299) (xy 202.707756 -102.077697) (xy 202.716892 -102.074726) (xy 202.754276 -102.061238)
			(xy 202.83092 -102.040197) (xy 202.909137 -102.026086) (xy 202.988302 -102.019017) (xy 203.028042 -102.018592)
			(xy 203.074437 -102.019195) (xy 203.166725 -102.028834) (xy 203.257509 -102.048024) (xy 203.345803 -102.076557)
			(xy 203.388468 -102.094792) (xy 203.39841 -102.098598) (xy 203.419674 -102.098598) (xy 203.429616 -102.094792)
			(xy 203.472273 -102.076533) (xy 203.560567 -102.047993) (xy 203.651354 -102.028804) (xy 203.743645 -102.019175)
			(xy 203.790042 -102.018592) (xy 203.836437 -102.019195) (xy 203.928725 -102.028834) (xy 204.019509 -102.048024)
			(xy 204.107803 -102.076557) (xy 204.150468 -102.094792) (xy 204.16041 -102.098598) (xy 204.181674 -102.098598)
			(xy 204.191616 -102.094792) (xy 204.234273 -102.076533) (xy 204.322567 -102.047993) (xy 204.413354 -102.028804)
			(xy 204.505645 -102.019175) (xy 204.552042 -102.018592) (xy 204.598437 -102.019195) (xy 204.690725 -102.028834)
			(xy 204.781509 -102.048024) (xy 204.869803 -102.076557) (xy 204.912468 -102.094792) (xy 204.92241 -102.098598)
			(xy 204.943674 -102.098598) (xy 204.953616 -102.094792) (xy 204.996273 -102.076533) (xy 205.084567 -102.047993)
			(xy 205.175354 -102.028804) (xy 205.267645 -102.019175) (xy 205.314042 -102.018592) (xy 205.360437 -102.019195)
			(xy 205.452725 -102.028834) (xy 205.543509 -102.048024) (xy 205.631803 -102.076557) (xy 205.674468 -102.094792)
			(xy 205.68441 -102.098598) (xy 205.705674 -102.098598) (xy 205.715616 -102.094792) (xy 205.758273 -102.076533)
			(xy 205.846567 -102.047993) (xy 205.937354 -102.028804) (xy 206.029645 -102.019175) (xy 206.076042 -102.018592)
			(xy 206.122437 -102.019195) (xy 206.214725 -102.028834) (xy 206.305509 -102.048024) (xy 206.393803 -102.076557)
			(xy 206.436468 -102.094792) (xy 206.44641 -102.098598) (xy 206.467674 -102.098598) (xy 206.477616 -102.094792)
			(xy 206.520273 -102.076533) (xy 206.608567 -102.047993) (xy 206.699354 -102.028804) (xy 206.791645 -102.019175)
			(xy 206.838042 -102.018592) (xy 206.879551 -102.019069) (xy 206.962209 -102.026787) (xy 207.043788 -102.042181)
			(xy 207.123575 -102.065115) (xy 207.1624 -102.079806) (xy 207.171897 -102.08298) (xy 207.191897 -102.082587)
			(xy 207.201262 -102.079044) (xy 207.243424 -102.061305) (xy 207.330583 -102.033534) (xy 207.420131 -102.014855)
			(xy 207.511124 -102.005463) (xy 207.556862 -102.004876) (xy 207.597969 -102.005349) (xy 207.679833 -102.01293)
			(xy 207.760649 -102.028032) (xy 207.839727 -102.050525) (xy 207.916392 -102.080217) (xy 207.989991 -102.116856)
			(xy 208.059896 -102.160128) (xy 208.125511 -102.209665) (xy 208.186276 -102.265044) (xy 208.241672 -102.325793)
			(xy 208.291228 -102.391394) (xy 208.334521 -102.461287) (xy 208.37118 -102.534875) (xy 208.400895 -102.611532)
			(xy 208.42341 -102.690604) (xy 208.438535 -102.771415) (xy 208.446139 -102.853277) (xy 208.446624 -102.894384)
			(xy 208.446027 -102.940787) (xy 208.436328 -103.033085) (xy 208.417066 -103.12387) (xy 208.38845 -103.212155)
			(xy 208.37017 -103.25481) (xy 208.366371 -103.264755) (xy 208.366365 -103.286016) (xy 208.37017 -103.295958)
			(xy 208.388427 -103.338621) (xy 208.417021 -103.426908) (xy 208.43628 -103.51769) (xy 208.445994 -103.609983)
			(xy 208.446624 -103.656384) (xy 208.446027 -103.702787) (xy 208.436328 -103.795085) (xy 208.417066 -103.88587)
			(xy 208.38845 -103.974155) (xy 208.37017 -104.01681) (xy 208.366371 -104.026755) (xy 208.366365 -104.048016)
			(xy 208.37017 -104.057958) (xy 208.388427 -104.100621) (xy 208.417021 -104.188908) (xy 208.43628 -104.27969)
			(xy 208.445994 -104.371983) (xy 208.446624 -104.418384) (xy 208.446109 -104.460957) (xy 208.437948 -104.545711)
			(xy 208.421718 -104.629296) (xy 208.397568 -104.710946) (xy 208.382108 -104.750616) (xy 208.378875 -104.759874)
			(xy 208.378863 -104.779464) (xy 208.382108 -104.788716) (xy 208.39754 -104.828395) (xy 208.421676 -104.910046)
			(xy 208.43791 -104.993628) (xy 208.446096 -105.078377) (xy 208.446624 -105.120948) (xy 208.446014 -105.167351)
			(xy 208.436319 -105.259648) (xy 208.417061 -105.350434) (xy 208.388448 -105.438718) (xy 208.37017 -105.481374)
			(xy 208.366333 -105.491307) (xy 208.366351 -105.51258) (xy 208.37017 -105.522522) (xy 208.388448 -105.565176)
			(xy 208.417037 -105.653467) (xy 208.43629 -105.744252) (xy 208.445997 -105.836546) (xy 208.446624 -105.882948)
			(xy 208.446621 -105.883202) (xy 215.929464 -105.883202) (xy 215.930093 -105.8368) (xy 215.939782 -105.744503)
			(xy 215.959035 -105.653717) (xy 215.987643 -105.565432) (xy 216.005918 -105.522776) (xy 216.009721 -105.512833)
			(xy 216.009721 -105.49157) (xy 216.005918 -105.481628) (xy 215.987656 -105.438967) (xy 215.959063 -105.350679)
			(xy 215.939806 -105.259896) (xy 215.930093 -105.167603) (xy 215.929464 -105.121202) (xy 215.929976 -105.078629)
			(xy 215.938138 -104.993875) (xy 215.954369 -104.910289) (xy 215.978519 -104.82864) (xy 215.99398 -104.78897)
			(xy 215.997221 -104.779714) (xy 215.997228 -104.760122) (xy 215.99398 -104.75087) (xy 215.978542 -104.711193)
			(xy 215.954408 -104.629541) (xy 215.938175 -104.545959) (xy 215.929991 -104.461209) (xy 215.929464 -104.418638)
			(xy 215.93007 -104.372235) (xy 215.939766 -104.279937) (xy 215.959026 -104.189152) (xy 215.98764 -104.100867)
			(xy 216.005918 -104.058212) (xy 216.0097 -104.048263) (xy 216.009714 -104.027006) (xy 216.005918 -104.017064)
			(xy 215.987667 -103.974398) (xy 215.959071 -103.886112) (xy 215.939811 -103.795331) (xy 215.930095 -103.703039)
			(xy 215.929464 -103.656638) (xy 215.93007 -103.610235) (xy 215.939766 -103.517937) (xy 215.959026 -103.427152)
			(xy 215.98764 -103.338867) (xy 216.005918 -103.296212) (xy 216.0097 -103.286263) (xy 216.009714 -103.265006)
			(xy 216.005918 -103.255064) (xy 215.987667 -103.212398) (xy 215.959071 -103.124112) (xy 215.939811 -103.033331)
			(xy 215.930095 -102.941039) (xy 215.929464 -102.894638) (xy 215.929935 -102.853523) (xy 215.937519 -102.771643)
			(xy 215.952626 -102.690813) (xy 215.975127 -102.611721) (xy 216.00483 -102.535043) (xy 216.041481 -102.461433)
			(xy 216.084768 -102.391519) (xy 216.134322 -102.325897) (xy 216.18972 -102.265128) (xy 216.250488 -102.20973)
			(xy 216.316109 -102.160175) (xy 216.386023 -102.116887) (xy 216.459632 -102.080234) (xy 216.53631 -102.050531)
			(xy 216.615401 -102.028029) (xy 216.696232 -102.01292) (xy 216.778111 -102.005335) (xy 216.819226 -102.004876)
			(xy 216.863277 -102.005441) (xy 216.950941 -102.014221) (xy 217.03731 -102.031612) (xy 217.12154 -102.057446)
			(xy 217.16238 -102.073964) (xy 217.171386 -102.077313) (xy 217.190582 -102.077702) (xy 217.199718 -102.074726)
			(xy 217.237099 -102.061231) (xy 217.313744 -102.040192) (xy 217.391962 -102.026083) (xy 217.471128 -102.019016)
			(xy 217.510868 -102.018592) (xy 217.557263 -102.019186) (xy 217.649551 -102.028828) (xy 217.740335 -102.048021)
			(xy 217.828629 -102.076556) (xy 217.871294 -102.094792) (xy 217.881236 -102.098598) (xy 217.9025 -102.098598)
			(xy 217.912442 -102.094792) (xy 217.955109 -102.076558) (xy 218.043399 -102.048011) (xy 218.134183 -102.028815)
			(xy 218.226472 -102.019179) (xy 218.272868 -102.018592) (xy 218.319263 -102.019186) (xy 218.411551 -102.028828)
			(xy 218.502335 -102.048021) (xy 218.590629 -102.076556) (xy 218.633294 -102.094792) (xy 218.643236 -102.098598)
			(xy 218.6645 -102.098598) (xy 218.674442 -102.094792) (xy 218.717109 -102.076558) (xy 218.805399 -102.048011)
			(xy 218.896183 -102.028815) (xy 218.988472 -102.019179) (xy 219.034868 -102.018592) (xy 219.081263 -102.019186)
			(xy 219.173551 -102.028828) (xy 219.264335 -102.048021) (xy 219.352629 -102.076556) (xy 219.395294 -102.094792)
			(xy 219.405236 -102.098598) (xy 219.4265 -102.098598) (xy 219.436442 -102.094792) (xy 219.479109 -102.076558)
			(xy 219.567399 -102.048011) (xy 219.658183 -102.028815) (xy 219.750472 -102.019179) (xy 219.796868 -102.018592)
			(xy 219.843263 -102.019186) (xy 219.935551 -102.028828) (xy 220.026335 -102.048021) (xy 220.114629 -102.076556)
			(xy 220.157294 -102.094792) (xy 220.167236 -102.098598) (xy 220.1885 -102.098598) (xy 220.198442 -102.094792)
			(xy 220.241109 -102.076558) (xy 220.329399 -102.048011) (xy 220.420183 -102.028815) (xy 220.512472 -102.019179)
			(xy 220.558868 -102.018592) (xy 220.605263 -102.019186) (xy 220.697551 -102.028828) (xy 220.788335 -102.048021)
			(xy 220.876629 -102.076556) (xy 220.919294 -102.094792) (xy 220.929236 -102.098598) (xy 220.9505 -102.098598)
			(xy 220.960442 -102.094792) (xy 221.003109 -102.076558) (xy 221.091399 -102.048011) (xy 221.182183 -102.028815)
			(xy 221.274472 -102.019179) (xy 221.320868 -102.018592) (xy 221.362377 -102.01906) (xy 221.445036 -102.026781)
			(xy 221.526614 -102.042177) (xy 221.606401 -102.065114) (xy 221.645226 -102.079806) (xy 221.654719 -102.082995)
			(xy 221.674723 -102.082593) (xy 221.684088 -102.079044) (xy 221.726247 -102.061296) (xy 221.813407 -102.033528)
			(xy 221.902956 -102.014851) (xy 221.99395 -102.005462) (xy 222.039688 -102.004876) (xy 222.08079 -102.005378)
			(xy 222.162643 -102.012962) (xy 222.243447 -102.028065) (xy 222.322513 -102.05056) (xy 222.399166 -102.080255)
			(xy 222.472752 -102.116895) (xy 222.542644 -102.160169) (xy 222.608245 -102.209706) (xy 222.668995 -102.265086)
			(xy 222.724376 -102.325834) (xy 222.773916 -102.391433) (xy 222.817191 -102.461323) (xy 222.853834 -102.534908)
			(xy 222.883531 -102.61156) (xy 222.906028 -102.690626) (xy 222.921134 -102.771429) (xy 222.928721 -102.853282)
			(xy 222.929196 -102.894384) (xy 222.928609 -102.940779) (xy 222.918965 -103.033068) (xy 222.89977 -103.123852)
			(xy 222.871233 -103.212145) (xy 222.852996 -103.25481) (xy 222.849201 -103.264755) (xy 222.849195 -103.286016)
			(xy 222.852996 -103.295958) (xy 222.871235 -103.338623) (xy 222.899781 -103.426914) (xy 222.918975 -103.517698)
			(xy 222.92861 -103.609988) (xy 222.929196 -103.656384) (xy 222.928609 -103.702779) (xy 222.918965 -103.795068)
			(xy 222.89977 -103.885852) (xy 222.871233 -103.974145) (xy 222.852996 -104.01681) (xy 222.849201 -104.026755)
			(xy 222.849195 -104.048016) (xy 222.852996 -104.057958) (xy 222.871235 -104.100623) (xy 222.899781 -104.188914)
			(xy 222.918975 -104.279698) (xy 222.92861 -104.371988) (xy 222.929196 -104.418384) (xy 222.928713 -104.460951)
			(xy 222.920608 -104.545698) (xy 222.90444 -104.629282) (xy 222.880359 -104.710939) (xy 222.864934 -104.750616)
			(xy 222.8617 -104.759874) (xy 222.861688 -104.779464) (xy 222.864934 -104.788716) (xy 222.880357 -104.828393)
			(xy 222.904434 -104.910051) (xy 222.908221 -104.929629) (xy 270.263616 -104.929629) (xy 270.263616 -104.844907)
			(xy 270.271669 -104.76057) (xy 270.287703 -104.67738) (xy 270.311571 -104.59609) (xy 270.343059 -104.517438)
			(xy 270.381881 -104.442135) (xy 270.427684 -104.370863) (xy 270.480055 -104.304267) (xy 270.53852 -104.242952)
			(xy 270.602548 -104.187471) (xy 270.67156 -104.138328) (xy 270.74493 -104.095968) (xy 270.821995 -104.060773)
			(xy 270.902057 -104.033064) (xy 270.98439 -104.01309) (xy 271.068249 -104.001033) (xy 271.152874 -103.997002)
			(xy 271.237499 -104.001033) (xy 271.321358 -104.01309) (xy 271.403691 -104.033064) (xy 271.483753 -104.060773)
			(xy 271.560818 -104.095968) (xy 271.634188 -104.138328) (xy 271.7032 -104.187471) (xy 271.767228 -104.242952)
			(xy 271.825693 -104.304267) (xy 271.878064 -104.370863) (xy 271.923867 -104.442135) (xy 271.962689 -104.517438)
			(xy 271.994177 -104.59609) (xy 272.018045 -104.67738) (xy 272.034079 -104.76057) (xy 272.042132 -104.844907)
			(xy 272.042636 -104.887268) (xy 272.042132 -104.929629) (xy 272.034079 -105.013966) (xy 272.018045 -105.097156)
			(xy 271.994177 -105.178446) (xy 271.962689 -105.257098) (xy 271.923867 -105.332401) (xy 271.878064 -105.403673)
			(xy 271.825693 -105.470269) (xy 271.767228 -105.531584) (xy 271.7032 -105.587065) (xy 271.634188 -105.636208)
			(xy 271.560818 -105.678568) (xy 271.483753 -105.713763) (xy 271.403691 -105.741472) (xy 271.321358 -105.761446)
			(xy 271.237499 -105.773503) (xy 271.152874 -105.777535) (xy 271.068249 -105.773503) (xy 270.98439 -105.761446)
			(xy 270.902057 -105.741472) (xy 270.821995 -105.713763) (xy 270.74493 -105.678568) (xy 270.67156 -105.636208)
			(xy 270.602548 -105.587065) (xy 270.53852 -105.531584) (xy 270.480055 -105.470269) (xy 270.427684 -105.403673)
			(xy 270.381881 -105.332401) (xy 270.343059 -105.257098) (xy 270.311571 -105.178446) (xy 270.287703 -105.097156)
			(xy 270.271669 -105.013966) (xy 270.263616 -104.929629) (xy 222.908221 -104.929629) (xy 222.920601 -104.993635)
			(xy 222.92871 -105.078381) (xy 222.929196 -105.120948) (xy 222.928596 -105.167343) (xy 222.918956 -105.259631)
			(xy 222.899765 -105.350415) (xy 222.871232 -105.438709) (xy 222.852996 -105.481374) (xy 222.849163 -105.491308)
			(xy 222.849181 -105.512579) (xy 222.852996 -105.522522) (xy 222.871223 -105.565192) (xy 222.899772 -105.653481)
			(xy 222.91897 -105.744264) (xy 222.928608 -105.836553) (xy 222.929196 -105.882948) (xy 222.928779 -105.924052)
			(xy 222.92119 -106.005908) (xy 222.90608 -106.086715) (xy 222.883579 -106.165783) (xy 222.853879 -106.242437)
			(xy 222.817233 -106.316025) (xy 222.773954 -106.385917) (xy 222.761182 -106.402829) (xy 268.600678 -106.402829)
			(xy 268.600678 -106.318107) (xy 268.608731 -106.23377) (xy 268.624765 -106.15058) (xy 268.648633 -106.06929)
			(xy 268.680121 -105.990638) (xy 268.718943 -105.915335) (xy 268.764746 -105.844063) (xy 268.817117 -105.777467)
			(xy 268.875582 -105.716152) (xy 268.93961 -105.660671) (xy 269.008622 -105.611528) (xy 269.081992 -105.569168)
			(xy 269.159057 -105.533973) (xy 269.239119 -105.506264) (xy 269.321452 -105.48629) (xy 269.405311 -105.474233)
			(xy 269.489936 -105.470202) (xy 269.574561 -105.474233) (xy 269.65842 -105.48629) (xy 269.740753 -105.506264)
			(xy 269.820815 -105.533973) (xy 269.89788 -105.569168) (xy 269.97125 -105.611528) (xy 270.040262 -105.660671)
			(xy 270.10429 -105.716152) (xy 270.162755 -105.777467) (xy 270.215126 -105.844063) (xy 270.260929 -105.915335)
			(xy 270.299751 -105.990638) (xy 270.331239 -106.06929) (xy 270.355107 -106.15058) (xy 270.371141 -106.23377)
			(xy 270.379194 -106.318107) (xy 270.379698 -106.360468) (xy 270.379194 -106.402829) (xy 270.371141 -106.487166)
			(xy 270.355107 -106.570356) (xy 270.331239 -106.651646) (xy 270.299751 -106.730298) (xy 270.260929 -106.805601)
			(xy 270.215126 -106.876873) (xy 270.162755 -106.943469) (xy 270.10429 -107.004784) (xy 270.040262 -107.060265)
			(xy 269.97125 -107.109408) (xy 269.89788 -107.151768) (xy 269.820815 -107.186963) (xy 269.740753 -107.214672)
			(xy 269.65842 -107.234646) (xy 269.574561 -107.246703) (xy 269.489936 -107.250735) (xy 269.405311 -107.246703)
			(xy 269.321452 -107.234646) (xy 269.239119 -107.214672) (xy 269.159057 -107.186963) (xy 269.081992 -107.151768)
			(xy 269.008622 -107.109408) (xy 268.93961 -107.060265) (xy 268.875582 -107.004784) (xy 268.817117 -106.943469)
			(xy 268.764746 -106.876873) (xy 268.718943 -106.805601) (xy 268.680121 -106.730298) (xy 268.648633 -106.651646)
			(xy 268.624765 -106.570356) (xy 268.608731 -106.487166) (xy 268.600678 -106.402829) (xy 222.761182 -106.402829)
			(xy 222.724411 -106.451518) (xy 222.669026 -106.512268) (xy 222.608272 -106.567649) (xy 222.542668 -106.617188)
			(xy 222.472772 -106.660463) (xy 222.399183 -106.697104) (xy 222.322526 -106.726799) (xy 222.243456 -106.749294)
			(xy 222.162648 -106.764398) (xy 222.080792 -106.771982) (xy 222.039688 -106.772456) (xy 221.998179 -106.771973)
			(xy 221.915521 -106.764257) (xy 221.833943 -106.748865) (xy 221.754155 -106.725932) (xy 221.71533 -106.711242)
			(xy 221.705829 -106.708082) (xy 221.685833 -106.708464) (xy 221.676468 -106.712004) (xy 221.634314 -106.729763)
			(xy 221.547152 -106.757529) (xy 221.457601 -106.776203) (xy 221.366607 -106.785588) (xy 221.320868 -106.786172)
			(xy 221.274473 -106.785568) (xy 221.182185 -106.77593) (xy 221.091401 -106.75674) (xy 221.003107 -106.728207)
			(xy 220.960442 -106.709972) (xy 220.9505 -106.706166) (xy 220.929236 -106.706166) (xy 220.919294 -106.709972)
			(xy 220.876635 -106.728225) (xy 220.788342 -106.756768) (xy 220.697556 -106.775958) (xy 220.605264 -106.785589)
			(xy 220.558868 -106.786172) (xy 220.512473 -106.785568) (xy 220.420185 -106.77593) (xy 220.329401 -106.75674)
			(xy 220.241107 -106.728207) (xy 220.198442 -106.709972) (xy 220.1885 -106.706166) (xy 220.167236 -106.706166)
			(xy 220.157294 -106.709972) (xy 220.114635 -106.728225) (xy 220.026342 -106.756768) (xy 219.935556 -106.775958)
			(xy 219.843264 -106.785589) (xy 219.796868 -106.786172) (xy 219.750473 -106.785568) (xy 219.658185 -106.77593)
			(xy 219.567401 -106.75674) (xy 219.479107 -106.728207) (xy 219.436442 -106.709972) (xy 219.4265 -106.706166)
			(xy 219.405236 -106.706166) (xy 219.395294 -106.709972) (xy 219.352635 -106.728225) (xy 219.264342 -106.756768)
			(xy 219.173556 -106.775958) (xy 219.081264 -106.785589) (xy 219.034868 -106.786172) (xy 218.988473 -106.785568)
			(xy 218.896185 -106.77593) (xy 218.805401 -106.75674) (xy 218.717107 -106.728207) (xy 218.674442 -106.709972)
			(xy 218.6645 -106.706166) (xy 218.643236 -106.706166) (xy 218.633294 -106.709972) (xy 218.590635 -106.728225)
			(xy 218.502342 -106.756768) (xy 218.411556 -106.775958) (xy 218.319264 -106.785589) (xy 218.272868 -106.786172)
			(xy 218.226473 -106.785568) (xy 218.134185 -106.77593) (xy 218.043401 -106.75674) (xy 217.955107 -106.728207)
			(xy 217.912442 -106.709972) (xy 217.9025 -106.706166) (xy 217.881236 -106.706166) (xy 217.871294 -106.709972)
			(xy 217.828635 -106.728225) (xy 217.740342 -106.756768) (xy 217.649556 -106.775958) (xy 217.557264 -106.785589)
			(xy 217.510868 -106.786172) (xy 217.466823 -106.785646) (xy 217.379163 -106.776938) (xy 217.292793 -106.759609)
			(xy 217.208558 -106.733831) (xy 217.167714 -106.717338) (xy 217.158709 -106.713986) (xy 217.139512 -106.713599)
			(xy 217.130376 -106.716576) (xy 217.093 -106.7301) (xy 217.016359 -106.751198) (xy 216.938142 -106.765371)
			(xy 216.858971 -106.772505) (xy 216.819226 -106.772964) (xy 216.778112 -106.772477) (xy 216.696233 -106.764892)
			(xy 216.615404 -106.749785) (xy 216.536314 -106.727283) (xy 216.459637 -106.697581) (xy 216.386028 -106.66093)
			(xy 216.316115 -106.617643) (xy 216.250494 -106.568091) (xy 216.189725 -106.512694) (xy 216.134327 -106.451927)
			(xy 216.084773 -106.386308) (xy 216.041484 -106.316396) (xy 216.004831 -106.242788) (xy 215.975125 -106.166113)
			(xy 215.952622 -106.087023) (xy 215.937512 -106.006194) (xy 215.929925 -105.924316) (xy 215.929464 -105.883202)
			(xy 208.446621 -105.883202) (xy 208.446193 -105.924059) (xy 208.438601 -106.00593) (xy 208.423487 -106.08675)
			(xy 208.400978 -106.165831) (xy 208.371268 -106.242498) (xy 208.33461 -106.316096) (xy 208.291317 -106.385997)
			(xy 208.241758 -106.451604) (xy 208.186356 -106.512358) (xy 208.125584 -106.567741) (xy 208.059961 -106.617279)
			(xy 207.990046 -106.66055) (xy 207.916436 -106.697184) (xy 207.83976 -106.726869) (xy 207.760672 -106.749352)
			(xy 207.679846 -106.764441) (xy 207.597973 -106.772007) (xy 207.556862 -106.772456) (xy 207.515353 -106.771982)
			(xy 207.432694 -106.764263) (xy 207.351116 -106.748869) (xy 207.271329 -106.725933) (xy 207.232504 -106.711242)
			(xy 207.223007 -106.708067) (xy 207.203007 -106.708459) (xy 207.193642 -106.712004) (xy 207.151478 -106.729739)
			(xy 207.06432 -106.757511) (xy 206.974772 -106.776192) (xy 206.88378 -106.785585) (xy 206.838042 -106.786172)
			(xy 206.791647 -106.785577) (xy 206.699359 -106.775936) (xy 206.608575 -106.756744) (xy 206.520281 -106.728209)
			(xy 206.477616 -106.709972) (xy 206.467674 -106.706166) (xy 206.44641 -106.706166) (xy 206.436468 -106.709972)
			(xy 206.393799 -106.728201) (xy 206.305509 -106.756749) (xy 206.214726 -106.775947) (xy 206.122438 -106.785585)
			(xy 206.076042 -106.786172) (xy 206.029647 -106.785577) (xy 205.937359 -106.775936) (xy 205.846575 -106.756744)
			(xy 205.758281 -106.728209) (xy 205.715616 -106.709972) (xy 205.705674 -106.706166) (xy 205.68441 -106.706166)
			(xy 205.674468 -106.709972) (xy 205.631799 -106.728201) (xy 205.543509 -106.756749) (xy 205.452726 -106.775947)
			(xy 205.360438 -106.785585) (xy 205.314042 -106.786172) (xy 205.267647 -106.785577) (xy 205.175359 -106.775936)
			(xy 205.084575 -106.756744) (xy 204.996281 -106.728209) (xy 204.953616 -106.709972) (xy 204.943674 -106.706166)
			(xy 204.92241 -106.706166) (xy 204.912468 -106.709972) (xy 204.869799 -106.728201) (xy 204.781509 -106.756749)
			(xy 204.690726 -106.775947) (xy 204.598438 -106.785585) (xy 204.552042 -106.786172) (xy 204.505647 -106.785577)
			(xy 204.413359 -106.775936) (xy 204.322575 -106.756744) (xy 204.234281 -106.728209) (xy 204.191616 -106.709972)
			(xy 204.181674 -106.706166) (xy 204.16041 -106.706166) (xy 204.150468 -106.709972) (xy 204.107799 -106.728201)
			(xy 204.019509 -106.756749) (xy 203.928726 -106.775947) (xy 203.836438 -106.785585) (xy 203.790042 -106.786172)
			(xy 203.743647 -106.785577) (xy 203.651359 -106.775936) (xy 203.560575 -106.756744) (xy 203.472281 -106.728209)
			(xy 203.429616 -106.709972) (xy 203.419674 -106.706166) (xy 203.39841 -106.706166) (xy 203.388468 -106.709972)
			(xy 203.345799 -106.728201) (xy 203.257509 -106.756749) (xy 203.166726 -106.775947) (xy 203.074438 -106.785585)
			(xy 203.028042 -106.786172) (xy 202.983997 -106.785621) (xy 202.896338 -106.77692) (xy 202.809969 -106.759599)
			(xy 202.725733 -106.733828) (xy 202.684888 -106.717338) (xy 202.675887 -106.713972) (xy 202.656687 -106.713594)
			(xy 202.64755 -106.716576) (xy 202.610166 -106.730079) (xy 202.533529 -106.751183) (xy 202.455313 -106.765361)
			(xy 202.376145 -106.772501) (xy 202.3364 -106.772964) (xy 202.295288 -106.772547) (xy 202.213415 -106.764959)
			(xy 202.132592 -106.749847) (xy 202.053508 -106.727341) (xy 201.976839 -106.697632) (xy 201.903239 -106.660975)
			(xy 201.833336 -106.617681) (xy 201.767727 -106.568121) (xy 201.706971 -106.512718) (xy 201.651588 -106.451944)
			(xy 201.60205 -106.386318) (xy 201.55878 -106.316401) (xy 201.522147 -106.242788) (xy 201.492464 -106.166109)
			(xy 201.469984 -106.087018) (xy 201.4549 -106.00619) (xy 201.447339 -105.924314) (xy 201.446892 -105.883202)
			(xy 42.525034 -105.883202) (xy 42.53529 -105.931714) (xy 42.544923 -106.024004) (xy 42.545508 -106.0704)
			(xy 42.544925 -106.116796) (xy 42.53528 -106.209084) (xy 42.516084 -106.299868) (xy 42.487546 -106.388161)
			(xy 42.469308 -106.430826) (xy 42.465403 -106.440748) (xy 42.465403 -106.462052) (xy 42.469308 -106.471974)
			(xy 42.487553 -106.514636) (xy 42.516097 -106.602929) (xy 42.53529 -106.693714) (xy 42.544923 -106.786004)
			(xy 42.545508 -106.8324) (xy 42.544974 -106.876652) (xy 42.53619 -106.964719) (xy 42.51871 -107.05148)
			(xy 42.492705 -107.136077) (xy 42.458433 -107.217676) (xy 42.437812 -107.256834) (xy 42.432976 -107.266759)
			(xy 42.431544 -107.28877) (xy 42.435018 -107.299252) (xy 42.449342 -107.337668) (xy 42.471714 -107.416549)
			(xy 42.486727 -107.497156) (xy 42.494251 -107.578803) (xy 42.494708 -107.6198) (xy 42.494125 -107.666196)
			(xy 42.48448 -107.758484) (xy 42.465284 -107.849268) (xy 42.436746 -107.937561) (xy 42.418508 -107.980226)
			(xy 42.414603 -107.990148) (xy 42.414603 -108.011452) (xy 42.418508 -108.021374) (xy 42.436753 -108.064036)
			(xy 42.465297 -108.152329) (xy 42.48449 -108.243114) (xy 42.494123 -108.335404) (xy 42.494708 -108.3818)
			(xy 42.494233 -108.422902) (xy 42.486648 -108.504757) (xy 42.471543 -108.585562) (xy 42.449047 -108.664629)
			(xy 42.419351 -108.741283) (xy 42.382709 -108.81487) (xy 42.339434 -108.884762) (xy 42.289894 -108.950363)
			(xy 42.234513 -109.011113) (xy 42.173763 -109.066494) (xy 42.108162 -109.116034) (xy 42.03827 -109.159309)
			(xy 41.964683 -109.195951) (xy 41.888029 -109.225647) (xy 41.808962 -109.248143) (xy 41.728157 -109.263248)
			(xy 41.646302 -109.270833) (xy 41.6052 -109.271308) (xy 41.558821 -109.270703) (xy 41.466567 -109.261053)
			(xy 41.375818 -109.241858) (xy 41.287558 -109.213327) (xy 41.202745 -109.175768) (xy 41.162224 -109.153198)
			(xy 41.150947 -109.147546) (xy 41.125768 -109.146863) (xy 41.114218 -109.151928) (xy 41.077098 -109.169978)
			(xy 41.000167 -109.199902) (xy 40.920795 -109.222573) (xy 40.839665 -109.237796) (xy 40.757473 -109.24544)
			(xy 40.7162 -109.245908) (xy 40.672407 -109.245348) (xy 40.585246 -109.236718) (xy 40.499354 -109.219572)
			(xy 40.41556 -109.194075) (xy 40.334675 -109.160474) (xy 40.29583 -109.140244) (xy 40.284364 -109.134826)
			(xy 40.259036 -109.134826) (xy 40.24757 -109.140244) (xy 40.208728 -109.160483) (xy 40.127852 -109.194119)
			(xy 40.044059 -109.219632) (xy 39.958163 -109.236777) (xy 39.870996 -109.245387) (xy 39.8272 -109.245908)
			(xy 39.786098 -109.245433) (xy 39.704243 -109.237848) (xy 39.623438 -109.222743) (xy 39.544371 -109.200247)
			(xy 39.467717 -109.170551) (xy 39.39413 -109.133909) (xy 39.324238 -109.090634) (xy 39.258637 -109.041094)
			(xy 39.197887 -108.985713) (xy 39.142506 -108.924963) (xy 39.092966 -108.859362) (xy 39.049691 -108.78947)
			(xy 39.013049 -108.715883) (xy 38.983353 -108.639229) (xy 38.960857 -108.560162) (xy 38.945752 -108.479357)
			(xy 38.938167 -108.397502) (xy 38.937692 -108.3564) (xy 32.131508 -108.3564) (xy 32.131033 -108.397502)
			(xy 32.123448 -108.479357) (xy 32.108343 -108.560162) (xy 32.085847 -108.639229) (xy 32.056151 -108.715883)
			(xy 32.019509 -108.78947) (xy 31.976234 -108.859362) (xy 31.926694 -108.924963) (xy 31.871313 -108.985713)
			(xy 31.810563 -109.041094) (xy 31.744962 -109.090634) (xy 31.67507 -109.133909) (xy 31.601483 -109.170551)
			(xy 31.524829 -109.200247) (xy 31.445762 -109.222743) (xy 31.364957 -109.237848) (xy 31.283102 -109.245433)
			(xy 31.242 -109.245908) (xy 31.198207 -109.245348) (xy 31.111046 -109.236718) (xy 31.025154 -109.219572)
			(xy 30.94136 -109.194075) (xy 30.860475 -109.160474) (xy 30.82163 -109.140244) (xy 30.810164 -109.134826)
			(xy 30.784836 -109.134826) (xy 30.77337 -109.140244) (xy 30.734528 -109.160483) (xy 30.653652 -109.194119)
			(xy 30.569859 -109.219632) (xy 30.483963 -109.236777) (xy 30.396796 -109.245387) (xy 30.353 -109.245908)
			(xy 30.307377 -109.245294) (xy 30.216612 -109.235924) (xy 30.127284 -109.217312) (xy 30.040329 -109.189655)
			(xy 29.956662 -109.153242) (xy 29.916628 -109.131354) (xy 29.908405 -109.127232) (xy 29.890238 -109.12446)
			(xy 29.872258 -109.128261) (xy 29.864304 -109.132878) (xy 29.82866 -109.154937) (xy 29.753965 -109.19299)
			(xy 29.67602 -109.223846) (xy 29.595518 -109.247231) (xy 29.513173 -109.262937) (xy 29.429715 -109.270825)
			(xy 29.3878 -109.271308) (xy 29.346698 -109.270833) (xy 29.264843 -109.263248) (xy 29.184038 -109.248143)
			(xy 29.104971 -109.225647) (xy 29.028317 -109.195951) (xy 28.95473 -109.159309) (xy 28.884838 -109.116034)
			(xy 28.819237 -109.066494) (xy 28.758487 -109.011113) (xy 28.703106 -108.950363) (xy 28.653566 -108.884762)
			(xy 28.610291 -108.81487) (xy 28.573649 -108.741283) (xy 28.543953 -108.664629) (xy 28.521457 -108.585562)
			(xy 28.506352 -108.504757) (xy 28.498767 -108.422902) (xy 28.498292 -108.3818) (xy 0.509016 -108.3818)
			(xy 0.509016 -112.268) (xy 141.857988 -112.268) (xy 141.862018 -112.183399) (xy 141.874071 -112.099564)
			(xy 141.894039 -112.017255) (xy 141.921741 -111.937216) (xy 141.956925 -111.860173) (xy 141.999274 -111.786823)
			(xy 142.048403 -111.717831) (xy 142.103868 -111.653821) (xy 142.165166 -111.595373) (xy 142.231742 -111.543017)
			(xy 142.302994 -111.497227) (xy 142.378275 -111.458416) (xy 142.456905 -111.426937) (xy 142.538172 -111.403076)
			(xy 142.621338 -111.387047) (xy 142.705652 -111.378996) (xy 142.748 -111.378492) (xy 142.786284 -111.37888)
			(xy 142.862573 -111.385419) (xy 142.938015 -111.3985) (xy 143.012052 -111.418027) (xy 143.048228 -111.430562)
			(xy 143.056665 -111.433213) (xy 143.074335 -111.433213) (xy 143.082772 -111.430562) (xy 143.11895 -111.418037)
			(xy 143.19299 -111.398529) (xy 143.268431 -111.385449) (xy 143.344717 -111.378894) (xy 143.383 -111.378492)
			(xy 143.425348 -111.378996) (xy 143.509662 -111.387047) (xy 143.592828 -111.403076) (xy 143.674095 -111.426937)
			(xy 143.752725 -111.458416) (xy 143.828006 -111.497227) (xy 143.899258 -111.543017) (xy 143.965834 -111.595373)
			(xy 144.027132 -111.653821) (xy 144.082597 -111.717831) (xy 144.131726 -111.786823) (xy 144.174075 -111.860173)
			(xy 144.209259 -111.937216) (xy 144.236961 -112.017255) (xy 144.256929 -112.099564) (xy 144.268982 -112.183399)
			(xy 144.273013 -112.268) (xy 144.268982 -112.352601) (xy 144.256929 -112.436436) (xy 144.236961 -112.518745)
			(xy 144.209259 -112.598784) (xy 144.174075 -112.675827) (xy 144.131726 -112.749177) (xy 144.082597 -112.818169)
			(xy 144.027132 -112.882179) (xy 143.965834 -112.940627) (xy 143.899258 -112.992983) (xy 143.828006 -113.038773)
			(xy 143.752725 -113.077584) (xy 143.674095 -113.109063) (xy 143.592828 -113.132924) (xy 143.509662 -113.148953)
			(xy 143.425348 -113.157004) (xy 143.383 -113.157508) (xy 143.344716 -113.15712) (xy 143.268427 -113.150581)
			(xy 143.192985 -113.1375) (xy 143.118948 -113.117973) (xy 143.082772 -113.105438) (xy 143.074335 -113.102787)
			(xy 143.056665 -113.102787) (xy 143.048228 -113.105438) (xy 143.01205 -113.117963) (xy 142.93801 -113.137471)
			(xy 142.862569 -113.150551) (xy 142.786283 -113.157106) (xy 142.748 -113.157508) (xy 142.705652 -113.157004)
			(xy 142.621338 -113.148953) (xy 142.538172 -113.132924) (xy 142.456905 -113.109063) (xy 142.378275 -113.077584)
			(xy 142.302994 -113.038773) (xy 142.231742 -112.992983) (xy 142.165166 -112.940627) (xy 142.103868 -112.882179)
			(xy 142.048403 -112.818169) (xy 141.999274 -112.749177) (xy 141.956925 -112.675827) (xy 141.921741 -112.598784)
			(xy 141.894039 -112.518745) (xy 141.874071 -112.436436) (xy 141.862018 -112.352601) (xy 141.857988 -112.268)
			(xy 0.509016 -112.268) (xy 0.509016 -113.229898) (xy 0.509506 -113.299774) (xy 0.517342 -113.439307)
			(xy 0.53299 -113.578181) (xy 0.556399 -113.715959) (xy 0.573755 -113.792) (xy 268.350492 -113.792)
			(xy 268.351075 -113.745604) (xy 268.36072 -113.653316) (xy 268.379916 -113.562532) (xy 268.408454 -113.474239)
			(xy 268.426692 -113.431574) (xy 268.430498 -113.421632) (xy 268.430498 -113.400368) (xy 268.426692 -113.390426)
			(xy 268.408447 -113.347764) (xy 268.379903 -113.259471) (xy 268.36071 -113.168686) (xy 268.351077 -113.076396)
			(xy 268.350492 -113.03) (xy 268.351075 -112.983604) (xy 268.36072 -112.891316) (xy 268.379916 -112.800532)
			(xy 268.408454 -112.712239) (xy 268.426692 -112.669574) (xy 268.430498 -112.659632) (xy 268.430498 -112.638368)
			(xy 268.426692 -112.628426) (xy 268.408447 -112.585764) (xy 268.379903 -112.497471) (xy 268.36071 -112.406686)
			(xy 268.351077 -112.314396) (xy 268.350492 -112.268) (xy 268.351075 -112.221604) (xy 268.36072 -112.129316)
			(xy 268.379916 -112.038532) (xy 268.408454 -111.950239) (xy 268.426692 -111.907574) (xy 268.430498 -111.897632)
			(xy 268.430498 -111.876368) (xy 268.426692 -111.866426) (xy 268.408447 -111.823764) (xy 268.379903 -111.735471)
			(xy 268.36071 -111.644686) (xy 268.351077 -111.552396) (xy 268.350492 -111.506) (xy 268.351075 -111.459604)
			(xy 268.36072 -111.367316) (xy 268.379916 -111.276532) (xy 268.408454 -111.188239) (xy 268.426692 -111.145574)
			(xy 268.430498 -111.135632) (xy 268.430498 -111.114368) (xy 268.426692 -111.104426) (xy 268.408447 -111.061764)
			(xy 268.379903 -110.973471) (xy 268.36071 -110.882686) (xy 268.351077 -110.790396) (xy 268.350492 -110.744)
			(xy 268.351075 -110.697604) (xy 268.36072 -110.605316) (xy 268.379916 -110.514532) (xy 268.408454 -110.426239)
			(xy 268.426692 -110.383574) (xy 268.430498 -110.373632) (xy 268.430498 -110.352368) (xy 268.426692 -110.342426)
			(xy 268.408447 -110.299764) (xy 268.379903 -110.211471) (xy 268.36071 -110.120686) (xy 268.351077 -110.028396)
			(xy 268.350492 -109.982) (xy 268.350967 -109.940898) (xy 268.358552 -109.859043) (xy 268.373657 -109.778238)
			(xy 268.396153 -109.699171) (xy 268.425849 -109.622517) (xy 268.462491 -109.54893) (xy 268.505766 -109.479038)
			(xy 268.555306 -109.413437) (xy 268.610687 -109.352687) (xy 268.671437 -109.297306) (xy 268.737038 -109.247766)
			(xy 268.80693 -109.204491) (xy 268.880517 -109.167849) (xy 268.957171 -109.138153) (xy 269.036238 -109.115657)
			(xy 269.117043 -109.100552) (xy 269.198898 -109.092967) (xy 269.24 -109.092492) (xy 269.286396 -109.093075)
			(xy 269.378684 -109.10272) (xy 269.469468 -109.121916) (xy 269.557761 -109.150454) (xy 269.600426 -109.168692)
			(xy 269.610368 -109.172498) (xy 269.631632 -109.172498) (xy 269.641574 -109.168692) (xy 269.684236 -109.150447)
			(xy 269.772529 -109.121903) (xy 269.863314 -109.10271) (xy 269.955604 -109.093077) (xy 270.002 -109.092492)
			(xy 270.048396 -109.093075) (xy 270.140684 -109.10272) (xy 270.231468 -109.121916) (xy 270.319761 -109.150454)
			(xy 270.362426 -109.168692) (xy 270.372368 -109.172498) (xy 270.393632 -109.172498) (xy 270.403574 -109.168692)
			(xy 270.446236 -109.150447) (xy 270.534529 -109.121903) (xy 270.625314 -109.10271) (xy 270.717604 -109.093077)
			(xy 270.764 -109.092492) (xy 270.810396 -109.093075) (xy 270.902684 -109.10272) (xy 270.993468 -109.121916)
			(xy 271.081761 -109.150454) (xy 271.124426 -109.168692) (xy 271.134368 -109.172498) (xy 271.155632 -109.172498)
			(xy 271.165574 -109.168692) (xy 271.208236 -109.150447) (xy 271.296529 -109.121903) (xy 271.387314 -109.10271)
			(xy 271.479604 -109.093077) (xy 271.526 -109.092492) (xy 271.572396 -109.093075) (xy 271.664684 -109.10272)
			(xy 271.755468 -109.121916) (xy 271.843761 -109.150454) (xy 271.886426 -109.168692) (xy 271.896368 -109.172498)
			(xy 271.917632 -109.172498) (xy 271.927574 -109.168692) (xy 271.970236 -109.150447) (xy 272.058529 -109.121903)
			(xy 272.149314 -109.10271) (xy 272.241604 -109.093077) (xy 272.288 -109.092492) (xy 272.329102 -109.092967)
			(xy 272.410957 -109.100552) (xy 272.491762 -109.115657) (xy 272.570829 -109.138153) (xy 272.647483 -109.167849)
			(xy 272.72107 -109.204491) (xy 272.790962 -109.247766) (xy 272.856563 -109.297306) (xy 272.917313 -109.352687)
			(xy 272.972694 -109.413437) (xy 273.022234 -109.479038) (xy 273.065509 -109.54893) (xy 273.102151 -109.622517)
			(xy 273.131847 -109.699171) (xy 273.154343 -109.778238) (xy 273.169448 -109.859043) (xy 273.177033 -109.940898)
			(xy 273.177508 -109.982) (xy 273.176925 -110.028396) (xy 273.16728 -110.120684) (xy 273.148084 -110.211468)
			(xy 273.119546 -110.299761) (xy 273.101308 -110.342426) (xy 273.097502 -110.352368) (xy 273.097502 -110.373632)
			(xy 273.101308 -110.383574) (xy 273.119553 -110.426236) (xy 273.148097 -110.514529) (xy 273.16729 -110.605314)
			(xy 273.176923 -110.697604) (xy 273.177508 -110.744) (xy 273.177033 -110.785102) (xy 273.169448 -110.866957)
			(xy 273.154343 -110.947762) (xy 273.131847 -111.026829) (xy 273.102151 -111.103483) (xy 273.065509 -111.17707)
			(xy 273.022234 -111.246962) (xy 272.972694 -111.312563) (xy 272.917313 -111.373313) (xy 272.856563 -111.428694)
			(xy 272.790962 -111.478234) (xy 272.72107 -111.521509) (xy 272.647483 -111.558151) (xy 272.570829 -111.587847)
			(xy 272.491762 -111.610343) (xy 272.410957 -111.625448) (xy 272.329102 -111.633033) (xy 272.288 -111.633508)
			(xy 272.241604 -111.632925) (xy 272.149316 -111.62328) (xy 272.058532 -111.604084) (xy 271.970239 -111.575546)
			(xy 271.927574 -111.557308) (xy 271.917632 -111.553502) (xy 271.896368 -111.553502) (xy 271.886426 -111.557308)
			(xy 271.853507 -111.571537) (xy 271.785822 -111.595257) (xy 271.716442 -111.613437) (xy 271.681194 -111.620046)
			(xy 271.67107 -111.622344) (xy 271.653749 -111.633749) (xy 271.642344 -111.65107) (xy 271.640046 -111.661194)
			(xy 271.633416 -111.696437) (xy 271.61522 -111.76581) (xy 271.591513 -111.833498) (xy 271.577308 -111.866426)
			(xy 271.573502 -111.876368) (xy 271.573502 -111.897632) (xy 271.577308 -111.907574) (xy 271.591537 -111.940493)
			(xy 271.615257 -112.008178) (xy 271.633437 -112.077558) (xy 271.640046 -112.112806) (xy 271.642344 -112.12293)
			(xy 271.653749 -112.140251) (xy 271.67107 -112.151656) (xy 271.681194 -112.153954) (xy 271.716437 -112.160584)
			(xy 271.78581 -112.17878) (xy 271.853498 -112.202487) (xy 271.886426 -112.216692) (xy 271.896368 -112.220498)
			(xy 271.917632 -112.220498) (xy 271.927574 -112.216692) (xy 271.970236 -112.198447) (xy 272.058529 -112.169903)
			(xy 272.149314 -112.15071) (xy 272.241604 -112.141077) (xy 272.288 -112.140492) (xy 272.329102 -112.140967)
			(xy 272.410957 -112.148552) (xy 272.491762 -112.163657) (xy 272.570829 -112.186153) (xy 272.647483 -112.215849)
			(xy 272.72107 -112.252491) (xy 272.790962 -112.295766) (xy 272.856563 -112.345306) (xy 272.917313 -112.400687)
			(xy 272.972694 -112.461437) (xy 273.022234 -112.527038) (xy 273.065509 -112.59693) (xy 273.102151 -112.670517)
			(xy 273.131847 -112.747171) (xy 273.154343 -112.826238) (xy 273.169448 -112.907043) (xy 273.177033 -112.988898)
			(xy 273.177508 -113.03) (xy 273.176925 -113.076396) (xy 273.16728 -113.168684) (xy 273.148084 -113.259468)
			(xy 273.119546 -113.347761) (xy 273.101308 -113.390426) (xy 273.097502 -113.400368) (xy 273.097502 -113.421632)
			(xy 273.101308 -113.431574) (xy 273.119553 -113.474236) (xy 273.148097 -113.562529) (xy 273.16729 -113.653314)
			(xy 273.176923 -113.745604) (xy 273.177508 -113.792) (xy 273.177033 -113.833102) (xy 273.169448 -113.914957)
			(xy 273.154343 -113.995762) (xy 273.131847 -114.074829) (xy 273.102151 -114.151483) (xy 273.065509 -114.22507)
			(xy 273.022234 -114.294962) (xy 272.972694 -114.360563) (xy 272.917313 -114.421313) (xy 272.856563 -114.476694)
			(xy 272.790962 -114.526234) (xy 272.72107 -114.569509) (xy 272.647483 -114.606151) (xy 272.570829 -114.635847)
			(xy 272.491762 -114.658343) (xy 272.410957 -114.673448) (xy 272.329102 -114.681033) (xy 272.288 -114.681508)
			(xy 272.241604 -114.680925) (xy 272.149316 -114.67128) (xy 272.058532 -114.652084) (xy 271.970239 -114.623546)
			(xy 271.927574 -114.605308) (xy 271.917632 -114.601502) (xy 271.896368 -114.601502) (xy 271.886426 -114.605308)
			(xy 271.843764 -114.623553) (xy 271.755471 -114.652097) (xy 271.664686 -114.67129) (xy 271.572396 -114.680923)
			(xy 271.526 -114.681508) (xy 271.479604 -114.680925) (xy 271.387316 -114.67128) (xy 271.296532 -114.652084)
			(xy 271.208239 -114.623546) (xy 271.165574 -114.605308) (xy 271.155632 -114.601502) (xy 271.134368 -114.601502)
			(xy 271.124426 -114.605308) (xy 271.081764 -114.623553) (xy 270.993471 -114.652097) (xy 270.902686 -114.67129)
			(xy 270.810396 -114.680923) (xy 270.764 -114.681508) (xy 270.717604 -114.680925) (xy 270.625316 -114.67128)
			(xy 270.534532 -114.652084) (xy 270.446239 -114.623546) (xy 270.403574 -114.605308) (xy 270.393632 -114.601502)
			(xy 270.372368 -114.601502) (xy 270.362426 -114.605308) (xy 270.319764 -114.623553) (xy 270.231471 -114.652097)
			(xy 270.140686 -114.67129) (xy 270.048396 -114.680923) (xy 270.002 -114.681508) (xy 269.955604 -114.680925)
			(xy 269.863316 -114.67128) (xy 269.772532 -114.652084) (xy 269.684239 -114.623546) (xy 269.641574 -114.605308)
			(xy 269.631632 -114.601502) (xy 269.610368 -114.601502) (xy 269.600426 -114.605308) (xy 269.557764 -114.623553)
			(xy 269.469471 -114.652097) (xy 269.378686 -114.67129) (xy 269.286396 -114.680923) (xy 269.24 -114.681508)
			(xy 269.198898 -114.681033) (xy 269.117043 -114.673448) (xy 269.036238 -114.658343) (xy 268.957171 -114.635847)
			(xy 268.880517 -114.606151) (xy 268.80693 -114.569509) (xy 268.737038 -114.526234) (xy 268.671437 -114.476694)
			(xy 268.610687 -114.421313) (xy 268.555306 -114.360563) (xy 268.505766 -114.294962) (xy 268.462491 -114.22507)
			(xy 268.425849 -114.151483) (xy 268.396153 -114.074829) (xy 268.373657 -113.995762) (xy 268.358552 -113.914957)
			(xy 268.350967 -113.833102) (xy 268.350492 -113.792) (xy 0.573755 -113.792) (xy 0.587497 -113.852208)
			(xy 0.626186 -113.986499) (xy 0.672343 -114.118409) (xy 0.725824 -114.247524) (xy 0.78646 -114.373436)
			(xy 0.854061 -114.495751) (xy 0.928414 -114.614083) (xy 1.009285 -114.72806) (xy 1.09642 -114.837323)
			(xy 1.189543 -114.941529) (xy 1.288363 -115.040349) (xy 1.392569 -115.133472) (xy 1.501832 -115.220607)
			(xy 1.615809 -115.301478) (xy 1.734141 -115.375831) (xy 1.856456 -115.443432) (xy 1.982368 -115.504068)
			(xy 2.111483 -115.557549) (xy 2.243393 -115.603706) (xy 2.377684 -115.642395) (xy 2.513933 -115.673493)
			(xy 2.651711 -115.696902) (xy 2.790585 -115.71255) (xy 2.930118 -115.720386) (xy 2.999994 -115.720876)
			(xy 9.59993 -115.720876) (xy 9.643968 -115.721358) (xy 9.731709 -115.729037) (xy 9.818446 -115.744333)
			(xy 9.90352 -115.767131) (xy 9.986284 -115.797257) (xy 10.066107 -115.834482) (xy 10.142382 -115.878522)
			(xy 10.214528 -115.929042) (xy 10.281997 -115.985658) (xy 10.344275 -116.047939) (xy 10.400887 -116.11541)
			(xy 10.451404 -116.187559) (xy 10.49544 -116.263836) (xy 10.532661 -116.34366) (xy 10.562783 -116.426425)
			(xy 10.585577 -116.511501) (xy 10.60087 -116.598239) (xy 10.608544 -116.68598) (xy 10.609072 -116.730018)
			(xy 10.609072 -116.971769) (xy 270.314162 -116.971769) (xy 270.314162 -116.887047) (xy 270.322215 -116.80271)
			(xy 270.338249 -116.71952) (xy 270.362117 -116.63823) (xy 270.393605 -116.559578) (xy 270.432427 -116.484275)
			(xy 270.47823 -116.413003) (xy 270.530601 -116.346407) (xy 270.589066 -116.285092) (xy 270.653094 -116.229611)
			(xy 270.722106 -116.180468) (xy 270.795476 -116.138108) (xy 270.872541 -116.102913) (xy 270.952603 -116.075204)
			(xy 271.034936 -116.05523) (xy 271.118795 -116.043173) (xy 271.20342 -116.039142) (xy 271.288045 -116.043173)
			(xy 271.371904 -116.05523) (xy 271.454237 -116.075204) (xy 271.534299 -116.102913) (xy 271.611364 -116.138108)
			(xy 271.684734 -116.180468) (xy 271.753746 -116.229611) (xy 271.817774 -116.285092) (xy 271.876239 -116.346407)
			(xy 271.92861 -116.413003) (xy 271.974413 -116.484275) (xy 272.013235 -116.559578) (xy 272.044723 -116.63823)
			(xy 272.068591 -116.71952) (xy 272.084625 -116.80271) (xy 272.092678 -116.887047) (xy 272.093182 -116.929408)
			(xy 272.092678 -116.971769) (xy 272.084625 -117.056106) (xy 272.068591 -117.139296) (xy 272.044723 -117.220586)
			(xy 272.013235 -117.299238) (xy 271.974413 -117.374541) (xy 271.92861 -117.445813) (xy 271.876239 -117.512409)
			(xy 271.817774 -117.573724) (xy 271.753746 -117.629205) (xy 271.684734 -117.678348) (xy 271.611364 -117.720708)
			(xy 271.534299 -117.755903) (xy 271.454237 -117.783612) (xy 271.371904 -117.803586) (xy 271.288045 -117.815643)
			(xy 271.20342 -117.819675) (xy 271.118795 -117.815643) (xy 271.034936 -117.803586) (xy 270.952603 -117.783612)
			(xy 270.872541 -117.755903) (xy 270.795476 -117.720708) (xy 270.722106 -117.678348) (xy 270.653094 -117.629205)
			(xy 270.589066 -117.573724) (xy 270.530601 -117.512409) (xy 270.47823 -117.445813) (xy 270.432427 -117.374541)
			(xy 270.393605 -117.299238) (xy 270.362117 -117.220586) (xy 270.338249 -117.139296) (xy 270.322215 -117.056106)
			(xy 270.314162 -116.971769) (xy 10.609072 -116.971769) (xy 10.609072 -122.48007) (xy 12.909653 -122.48007)
			(xy 12.913615 -122.339639) (xy 12.92549 -122.199655) (xy 12.94524 -122.060564) (xy 12.972802 -121.922808)
			(xy 13.008088 -121.786825) (xy 13.050986 -121.653048) (xy 13.101359 -121.521903) (xy 13.159047 -121.393807)
			(xy 13.223867 -121.269168) (xy 13.295611 -121.148382) (xy 13.374053 -121.031834) (xy 13.458942 -120.919895)
			(xy 13.550008 -120.812921) (xy 13.646962 -120.711253) (xy 13.749494 -120.615213) (xy 13.857279 -120.525108)
			(xy 13.969973 -120.441224) (xy 14.087218 -120.363828) (xy 14.208641 -120.293167) (xy 14.333855 -120.229466)
			(xy 14.462462 -120.172926) (xy 14.594052 -120.123729) (xy 14.728208 -120.08203) (xy 14.864501 -120.047962)
			(xy 15.002499 -120.021634) (xy 15.141762 -120.00313) (xy 15.281846 -119.992508) (xy 15.422307 -119.989803)
			(xy 15.562696 -119.995022) (xy 15.702568 -120.008149) (xy 15.841477 -120.029143) (xy 15.978981 -120.057936)
			(xy 16.114643 -120.094438) (xy 16.248031 -120.138531) (xy 16.37872 -120.190076) (xy 16.506295 -120.248908)
			(xy 16.630349 -120.31484) (xy 16.750487 -120.387663) (xy 16.866328 -120.467145) (xy 16.977503 -120.553032)
			(xy 17.083658 -120.645052) (xy 17.184455 -120.742911) (xy 17.232376 -120.794272) (xy 17.241266 -120.803924)
			(xy 17.264888 -120.812052) (xy 17.3736 -120.795542) (xy 17.393666 -120.780556) (xy 17.399 -120.768872)
			(xy 17.438151 -120.687) (xy 17.522868 -120.526483) (xy 17.614754 -120.36996) (xy 17.713621 -120.21775)
			(xy 17.819267 -120.070165) (xy 17.931475 -119.927505) (xy 18.050018 -119.790064) (xy 18.174651 -119.65812)
			(xy 18.305121 -119.531945) (xy 18.441161 -119.411797) (xy 18.582492 -119.29792) (xy 18.728826 -119.190548)
			(xy 18.879864 -119.089899) (xy 19.035297 -118.996181) (xy 19.194807 -118.909584) (xy 19.358068 -118.830285)
			(xy 19.524747 -118.758447) (xy 19.694502 -118.694216) (xy 19.866987 -118.637724) (xy 20.04185 -118.589086)
			(xy 20.218732 -118.548401) (xy 20.397272 -118.515753) (xy 20.577105 -118.491209) (xy 20.757864 -118.474818)
			(xy 20.93918 -118.466614) (xy 21.02993 -118.466108) (xy 21.120007 -118.466613) (xy 21.147082 -118.467829)
			(xy 268.757142 -118.467829) (xy 268.757142 -118.383107) (xy 268.765195 -118.29877) (xy 268.781229 -118.21558)
			(xy 268.805097 -118.13429) (xy 268.836585 -118.055638) (xy 268.875407 -117.980335) (xy 268.92121 -117.909063)
			(xy 268.973581 -117.842467) (xy 269.032046 -117.781152) (xy 269.096074 -117.725671) (xy 269.165086 -117.676528)
			(xy 269.238456 -117.634168) (xy 269.315521 -117.598973) (xy 269.395583 -117.571264) (xy 269.477916 -117.55129)
			(xy 269.561775 -117.539233) (xy 269.6464 -117.535202) (xy 269.731025 -117.539233) (xy 269.814884 -117.55129)
			(xy 269.897217 -117.571264) (xy 269.977279 -117.598973) (xy 270.054344 -117.634168) (xy 270.127714 -117.676528)
			(xy 270.196726 -117.725671) (xy 270.260754 -117.781152) (xy 270.319219 -117.842467) (xy 270.37159 -117.909063)
			(xy 270.417393 -117.980335) (xy 270.456215 -118.055638) (xy 270.487703 -118.13429) (xy 270.511571 -118.21558)
			(xy 270.527605 -118.29877) (xy 270.535658 -118.383107) (xy 270.536162 -118.425468) (xy 270.535658 -118.467829)
			(xy 270.527605 -118.552166) (xy 270.511571 -118.635356) (xy 270.487703 -118.716646) (xy 270.456215 -118.795298)
			(xy 270.417393 -118.870601) (xy 270.37159 -118.941873) (xy 270.319219 -119.008469) (xy 270.260754 -119.069784)
			(xy 270.196726 -119.125265) (xy 270.127714 -119.174408) (xy 270.054344 -119.216768) (xy 269.977279 -119.251963)
			(xy 269.897217 -119.279672) (xy 269.814884 -119.299646) (xy 269.731025 -119.311703) (xy 269.6464 -119.315735)
			(xy 269.561775 -119.311703) (xy 269.477916 -119.299646) (xy 269.395583 -119.279672) (xy 269.315521 -119.251963)
			(xy 269.238456 -119.216768) (xy 269.165086 -119.174408) (xy 269.096074 -119.125265) (xy 269.032046 -119.069784)
			(xy 268.973581 -119.008469) (xy 268.92121 -118.941873) (xy 268.875407 -118.870601) (xy 268.836585 -118.795298)
			(xy 268.805097 -118.716646) (xy 268.781229 -118.635356) (xy 268.765195 -118.552166) (xy 268.757142 -118.467829)
			(xy 21.147082 -118.467829) (xy 21.299979 -118.474696) (xy 21.479408 -118.490845) (xy 21.657931 -118.515027)
			(xy 21.83519 -118.547195) (xy 22.010827 -118.587283) (xy 22.184488 -118.63521) (xy 22.355825 -118.690881)
			(xy 22.524491 -118.754183) (xy 22.690147 -118.824987) (xy 22.85246 -118.903153) (xy 23.011103 -118.988522)
			(xy 23.165755 -119.080923) (xy 23.316107 -119.180169) (xy 23.461854 -119.286061) (xy 23.602704 -119.398385)
			(xy 23.738373 -119.516915) (xy 23.868587 -119.641413) (xy 23.993085 -119.771627) (xy 24.111615 -119.907296)
			(xy 24.223939 -120.048146) (xy 24.329831 -120.193893) (xy 24.429077 -120.344245) (xy 24.521478 -120.498897)
			(xy 24.606847 -120.65754) (xy 24.685013 -120.819853) (xy 24.755817 -120.985509) (xy 24.819119 -121.154175)
			(xy 24.87479 -121.325512) (xy 24.922717 -121.499173) (xy 24.962805 -121.67481) (xy 24.994973 -121.852069)
			(xy 25.019155 -122.030592) (xy 25.035304 -122.210021) (xy 25.043387 -122.389993) (xy 25.043387 -122.48007)
			(xy 25.159471 -122.48007) (xy 25.16346 -122.339172) (xy 25.175414 -122.198725) (xy 25.195294 -122.05918)
			(xy 25.223037 -121.920983) (xy 25.258555 -121.784577) (xy 25.301732 -121.650398) (xy 25.352432 -121.518878)
			(xy 25.410492 -121.390436) (xy 25.475724 -121.265485) (xy 25.547922 -121.144424) (xy 25.626853 -121.027642)
			(xy 25.712264 -120.915513) (xy 25.803883 -120.808395) (xy 25.901415 -120.706632) (xy 26.004547 -120.61055)
			(xy 26.112951 -120.520457) (xy 26.226278 -120.43664) (xy 26.344165 -120.35937) (xy 26.466235 -120.288893)
			(xy 26.592097 -120.225434) (xy 26.721347 -120.169199) (xy 26.853572 -120.120365) (xy 26.988348 -120.07909)
			(xy 27.125243 -120.045507) (xy 27.263819 -120.019722) (xy 27.403632 -120.001818) (xy 27.544234 -119.991853)
			(xy 27.685174 -119.989858) (xy 27.826002 -119.995841) (xy 27.966265 -120.009781) (xy 28.105515 -120.031634)
			(xy 28.243306 -120.06133) (xy 28.379196 -120.098774) (xy 28.51275 -120.143846) (xy 28.64354 -120.196402)
			(xy 28.771147 -120.256273) (xy 28.895163 -120.323268) (xy 29.015189 -120.397171) (xy 29.130843 -120.477747)
			(xy 29.241752 -120.564736) (xy 29.347563 -120.657861) (xy 29.447935 -120.756823) (xy 29.542548 -120.861305)
			(xy 29.631099 -120.970973) (xy 29.713303 -121.085475) (xy 29.788897 -121.204444) (xy 29.791898 -121.209816)
			(xy 62.652667 -121.209816) (xy 62.65664 -121.089706) (xy 62.668543 -120.970121) (xy 62.688324 -120.851584)
			(xy 62.715895 -120.734613) (xy 62.751137 -120.61972) (xy 62.793894 -120.507408) (xy 62.843982 -120.398167)
			(xy 62.901179 -120.292476) (xy 62.965237 -120.190795) (xy 63.035874 -120.093571) (xy 63.112783 -120.001228)
			(xy 63.195627 -119.914169) (xy 63.284043 -119.832776) (xy 63.377646 -119.757405) (xy 63.476025 -119.688384)
			(xy 63.57875 -119.626016) (xy 63.685373 -119.570574) (xy 63.795427 -119.5223) (xy 63.908431 -119.481405)
			(xy 64.023891 -119.448068) (xy 64.141301 -119.422434) (xy 64.260149 -119.404616) (xy 64.379915 -119.394692)
			(xy 64.500074 -119.392705) (xy 64.620102 -119.398664) (xy 64.739474 -119.412543) (xy 64.857668 -119.43428)
			(xy 64.974167 -119.463782) (xy 65.088461 -119.500918) (xy 65.200051 -119.545527) (xy 65.308449 -119.597414)
			(xy 65.41318 -119.656351) (xy 65.513787 -119.722081) (xy 65.609831 -119.794316) (xy 65.70089 -119.872742)
			(xy 65.786567 -119.957013) (xy 65.866487 -120.046763) (xy 65.9403 -120.141599) (xy 66.007685 -120.241106)
			(xy 66.068346 -120.344849) (xy 66.122017 -120.452374) (xy 66.168465 -120.563211) (xy 66.207486 -120.676875)
			(xy 66.23891 -120.79287) (xy 66.262599 -120.910689) (xy 66.278449 -121.029815) (xy 66.286391 -121.149728)
			(xy 66.286888 -121.209816) (xy 102.652587 -121.209816) (xy 102.65656 -121.089706) (xy 102.668463 -120.970121)
			(xy 102.688244 -120.851584) (xy 102.715815 -120.734613) (xy 102.751057 -120.61972) (xy 102.793814 -120.507408)
			(xy 102.843902 -120.398167) (xy 102.901099 -120.292476) (xy 102.965157 -120.190795) (xy 103.035794 -120.093571)
			(xy 103.112703 -120.001228) (xy 103.195547 -119.914169) (xy 103.283963 -119.832776) (xy 103.377566 -119.757405)
			(xy 103.475945 -119.688384) (xy 103.57867 -119.626016) (xy 103.685293 -119.570574) (xy 103.795347 -119.5223)
			(xy 103.908351 -119.481405) (xy 104.023811 -119.448068) (xy 104.141221 -119.422434) (xy 104.260069 -119.404616)
			(xy 104.379835 -119.394692) (xy 104.499994 -119.392705) (xy 104.620022 -119.398664) (xy 104.739394 -119.412543)
			(xy 104.857588 -119.43428) (xy 104.974087 -119.463782) (xy 105.088381 -119.500918) (xy 105.199971 -119.545527)
			(xy 105.308369 -119.597414) (xy 105.4131 -119.656351) (xy 105.513707 -119.722081) (xy 105.609751 -119.794316)
			(xy 105.70081 -119.872742) (xy 105.786487 -119.957013) (xy 105.866407 -120.046763) (xy 105.94022 -120.141599)
			(xy 106.007605 -120.241106) (xy 106.068266 -120.344849) (xy 106.121937 -120.452374) (xy 106.168385 -120.563211)
			(xy 106.207406 -120.676875) (xy 106.23883 -120.79287) (xy 106.262519 -120.910689) (xy 106.278369 -121.029815)
			(xy 106.286311 -121.149728) (xy 106.286808 -121.209816) (xy 142.652761 -121.209816) (xy 142.656734 -121.089706)
			(xy 142.668637 -120.970121) (xy 142.688418 -120.851584) (xy 142.715989 -120.734613) (xy 142.751231 -120.61972)
			(xy 142.793988 -120.507408) (xy 142.844076 -120.398167) (xy 142.901273 -120.292476) (xy 142.965331 -120.190795)
			(xy 143.035968 -120.093571) (xy 143.112877 -120.001228) (xy 143.195721 -119.914169) (xy 143.284137 -119.832776)
			(xy 143.37774 -119.757405) (xy 143.476119 -119.688384) (xy 143.578844 -119.626016) (xy 143.685467 -119.570574)
			(xy 143.795521 -119.5223) (xy 143.908525 -119.481405) (xy 144.023985 -119.448068) (xy 144.141395 -119.422434)
			(xy 144.260243 -119.404616) (xy 144.380009 -119.394692) (xy 144.500168 -119.392705) (xy 144.620196 -119.398664)
			(xy 144.739568 -119.412543) (xy 144.857762 -119.43428) (xy 144.974261 -119.463782) (xy 145.088555 -119.500918)
			(xy 145.200145 -119.545527) (xy 145.308543 -119.597414) (xy 145.413274 -119.656351) (xy 145.513881 -119.722081)
			(xy 145.609925 -119.794316) (xy 145.700984 -119.872742) (xy 145.786661 -119.957013) (xy 145.866581 -120.046763)
			(xy 145.940394 -120.141599) (xy 146.007779 -120.241106) (xy 146.06844 -120.344849) (xy 146.122111 -120.452374)
			(xy 146.168559 -120.563211) (xy 146.20758 -120.676875) (xy 146.239004 -120.79287) (xy 146.262693 -120.910689)
			(xy 146.278543 -121.029815) (xy 146.286485 -121.149728) (xy 146.286982 -121.209816) (xy 182.652935 -121.209816)
			(xy 182.656908 -121.089706) (xy 182.668811 -120.970121) (xy 182.688592 -120.851584) (xy 182.716163 -120.734613)
			(xy 182.751405 -120.61972) (xy 182.794162 -120.507408) (xy 182.84425 -120.398167) (xy 182.901447 -120.292476)
			(xy 182.965505 -120.190795) (xy 183.036142 -120.093571) (xy 183.113051 -120.001228) (xy 183.195895 -119.914169)
			(xy 183.284311 -119.832776) (xy 183.377914 -119.757405) (xy 183.476293 -119.688384) (xy 183.579018 -119.626016)
			(xy 183.685641 -119.570574) (xy 183.795695 -119.5223) (xy 183.908699 -119.481405) (xy 184.024159 -119.448068)
			(xy 184.141569 -119.422434) (xy 184.260417 -119.404616) (xy 184.380183 -119.394692) (xy 184.500342 -119.392705)
			(xy 184.62037 -119.398664) (xy 184.739742 -119.412543) (xy 184.857936 -119.43428) (xy 184.974435 -119.463782)
			(xy 185.088729 -119.500918) (xy 185.200319 -119.545527) (xy 185.308717 -119.597414) (xy 185.413448 -119.656351)
			(xy 185.514055 -119.722081) (xy 185.610099 -119.794316) (xy 185.701158 -119.872742) (xy 185.786835 -119.957013)
			(xy 185.866755 -120.046763) (xy 185.940568 -120.141599) (xy 186.007953 -120.241106) (xy 186.068614 -120.344849)
			(xy 186.122285 -120.452374) (xy 186.168733 -120.563211) (xy 186.207754 -120.676875) (xy 186.239178 -120.79287)
			(xy 186.262867 -120.910689) (xy 186.278717 -121.029815) (xy 186.286659 -121.149728) (xy 186.287156 -121.209816)
			(xy 186.286659 -121.269904) (xy 186.278717 -121.389817) (xy 186.262867 -121.508943) (xy 186.239178 -121.626762)
			(xy 186.207754 -121.742757) (xy 186.168733 -121.856421) (xy 186.122285 -121.967258) (xy 186.068614 -122.074783)
			(xy 186.007953 -122.178526) (xy 185.940568 -122.278033) (xy 185.866755 -122.372869) (xy 185.786835 -122.462619)
			(xy 185.701158 -122.54689) (xy 185.610099 -122.625316) (xy 185.514055 -122.697551) (xy 185.413448 -122.763281)
			(xy 185.330851 -122.809762) (xy 201.460608 -122.809762) (xy 201.461219 -122.763359) (xy 201.470913 -122.671062)
			(xy 201.490171 -122.580276) (xy 201.518784 -122.491991) (xy 201.537062 -122.449336) (xy 201.540892 -122.439401)
			(xy 201.540877 -122.41813) (xy 201.537062 -122.408188) (xy 201.518789 -122.365532) (xy 201.490198 -122.277242)
			(xy 201.470944 -122.186458) (xy 201.461235 -122.094163) (xy 201.460608 -122.047762) (xy 201.461152 -122.004334)
			(xy 201.469646 -121.917893) (xy 201.486519 -121.83269) (xy 201.511611 -121.749536) (xy 201.527664 -121.70918)
			(xy 201.531108 -121.699762) (xy 201.531126 -121.679728) (xy 201.527664 -121.670318) (xy 201.511607 -121.629963)
			(xy 201.486507 -121.54681) (xy 201.469633 -121.461607) (xy 201.461143 -121.375165) (xy 201.460608 -121.331736)
			(xy 201.46121 -121.285333) (xy 201.470907 -121.193035) (xy 201.490167 -121.10225) (xy 201.518783 -121.013965)
			(xy 201.537062 -120.97131) (xy 201.540848 -120.961362) (xy 201.540862 -120.940104) (xy 201.537062 -120.930162)
			(xy 201.518813 -120.887496) (xy 201.490216 -120.79921) (xy 201.470955 -120.708428) (xy 201.461239 -120.616137)
			(xy 201.460608 -120.569736) (xy 201.461087 -120.528625) (xy 201.468672 -120.446755) (xy 201.48378 -120.365934)
			(xy 201.506282 -120.286852) (xy 201.535987 -120.210185) (xy 201.57264 -120.136586) (xy 201.61593 -120.066683)
			(xy 201.665486 -120.001075) (xy 201.720885 -119.940319) (xy 201.781655 -119.884936) (xy 201.847277 -119.835397)
			(xy 201.91719 -119.792126) (xy 201.990799 -119.755492) (xy 202.067474 -119.725808) (xy 202.146562 -119.703326)
			(xy 202.227387 -119.688239) (xy 202.309259 -119.680676) (xy 202.35037 -119.680228) (xy 202.396765 -119.680818)
			(xy 202.489054 -119.690461) (xy 202.579837 -119.709654) (xy 202.668131 -119.738191) (xy 202.710796 -119.756428)
			(xy 202.720738 -119.760234) (xy 202.742002 -119.760234) (xy 202.751944 -119.756428) (xy 202.794611 -119.738195)
			(xy 202.882902 -119.709648) (xy 202.973685 -119.690451) (xy 203.065974 -119.680814) (xy 203.11237 -119.680228)
			(xy 203.158765 -119.680818) (xy 203.251054 -119.690461) (xy 203.341837 -119.709654) (xy 203.430131 -119.738191)
			(xy 203.472796 -119.756428) (xy 203.482738 -119.760234) (xy 203.504002 -119.760234) (xy 203.513944 -119.756428)
			(xy 203.556611 -119.738195) (xy 203.644902 -119.709648) (xy 203.735685 -119.690451) (xy 203.827974 -119.680814)
			(xy 203.87437 -119.680228) (xy 203.920765 -119.680818) (xy 204.013054 -119.690461) (xy 204.103837 -119.709654)
			(xy 204.192131 -119.738191) (xy 204.234796 -119.756428) (xy 204.244738 -119.760234) (xy 204.266002 -119.760234)
			(xy 204.275944 -119.756428) (xy 204.318611 -119.738195) (xy 204.406902 -119.709648) (xy 204.497685 -119.690451)
			(xy 204.589974 -119.680814) (xy 204.63637 -119.680228) (xy 204.682765 -119.680818) (xy 204.775054 -119.690461)
			(xy 204.865837 -119.709654) (xy 204.954131 -119.738191) (xy 204.996796 -119.756428) (xy 205.006738 -119.760234)
			(xy 205.028002 -119.760234) (xy 205.037944 -119.756428) (xy 205.080611 -119.738195) (xy 205.168902 -119.709648)
			(xy 205.259685 -119.690451) (xy 205.351974 -119.680814) (xy 205.39837 -119.680228) (xy 205.444765 -119.680818)
			(xy 205.537054 -119.690461) (xy 205.627837 -119.709654) (xy 205.716131 -119.738191) (xy 205.758796 -119.756428)
			(xy 205.768738 -119.760234) (xy 205.790002 -119.760234) (xy 205.799944 -119.756428) (xy 205.842611 -119.738195)
			(xy 205.930902 -119.709648) (xy 206.021685 -119.690451) (xy 206.113974 -119.680814) (xy 206.16037 -119.680228)
			(xy 206.206765 -119.680818) (xy 206.299054 -119.690461) (xy 206.389837 -119.709654) (xy 206.478131 -119.738191)
			(xy 206.520796 -119.756428) (xy 206.530738 -119.760234) (xy 206.552002 -119.760234) (xy 206.561944 -119.756428)
			(xy 206.604611 -119.738195) (xy 206.692902 -119.709648) (xy 206.783685 -119.690451) (xy 206.875974 -119.680814)
			(xy 206.92237 -119.680228) (xy 206.968765 -119.680818) (xy 207.061054 -119.690461) (xy 207.151837 -119.709654)
			(xy 207.240131 -119.738191) (xy 207.282796 -119.756428) (xy 207.292738 -119.760234) (xy 207.314002 -119.760234)
			(xy 207.323944 -119.756428) (xy 207.366611 -119.738195) (xy 207.454902 -119.709648) (xy 207.545685 -119.690451)
			(xy 207.637974 -119.680814) (xy 207.68437 -119.680228) (xy 207.725476 -119.680741) (xy 207.807338 -119.688323)
			(xy 207.888151 -119.703424) (xy 207.967226 -119.725916) (xy 208.043889 -119.755607) (xy 208.117486 -119.792244)
			(xy 208.18739 -119.835514) (xy 208.253003 -119.885048) (xy 208.313767 -119.940425) (xy 208.369164 -120.00117)
			(xy 208.41872 -120.066768) (xy 208.462013 -120.136657) (xy 208.498674 -120.210242) (xy 208.528391 -120.286895)
			(xy 208.550909 -120.365963) (xy 208.566037 -120.446771) (xy 208.573645 -120.52863) (xy 208.574132 -120.569736)
			(xy 208.573517 -120.616138) (xy 208.563823 -120.708436) (xy 208.544566 -120.799221) (xy 208.515955 -120.887506)
			(xy 208.497678 -120.930162) (xy 208.493853 -120.940098) (xy 208.493867 -120.961367) (xy 208.497678 -120.97131)
			(xy 208.515953 -121.013966) (xy 208.544542 -121.102256) (xy 208.563796 -121.19304) (xy 208.573505 -121.285335)
			(xy 208.574132 -121.331736) (xy 208.573584 -121.375164) (xy 208.565091 -121.461605) (xy 208.548219 -121.546808)
			(xy 208.523128 -121.629962) (xy 208.507076 -121.670318) (xy 208.503705 -121.679744) (xy 208.503722 -121.699746)
			(xy 208.507076 -121.70918) (xy 208.523129 -121.749537) (xy 208.54823 -121.832688) (xy 208.565107 -121.917891)
			(xy 208.573597 -122.004333) (xy 208.574132 -122.047762) (xy 208.573526 -122.094165) (xy 208.56383 -122.186463)
			(xy 208.54457 -122.277248) (xy 208.515957 -122.365533) (xy 208.497678 -122.408188) (xy 208.493897 -122.418137)
			(xy 208.493882 -122.439394) (xy 208.497678 -122.449336) (xy 208.515928 -122.492002) (xy 208.544524 -122.580288)
			(xy 208.563785 -122.671069) (xy 208.573501 -122.763361) (xy 208.574132 -122.809762) (xy 215.837516 -122.809762)
			(xy 215.838126 -122.763359) (xy 215.847821 -122.671062) (xy 215.867079 -122.580276) (xy 215.895692 -122.491991)
			(xy 215.91397 -122.449336) (xy 215.917799 -122.439401) (xy 215.917785 -122.41813) (xy 215.91397 -122.408188)
			(xy 215.895691 -122.365534) (xy 215.867103 -122.277243) (xy 215.847851 -122.186458) (xy 215.838143 -122.094164)
			(xy 215.837516 -122.047762) (xy 215.83806 -122.004334) (xy 215.846553 -121.917893) (xy 215.863427 -121.83269)
			(xy 215.888519 -121.749536) (xy 215.904572 -121.70918) (xy 215.908015 -121.699762) (xy 215.908033 -121.679728)
			(xy 215.904572 -121.670318) (xy 215.888515 -121.629963) (xy 215.863416 -121.54681) (xy 215.846541 -121.461607)
			(xy 215.838051 -121.375165) (xy 215.837516 -121.331736) (xy 215.838117 -121.285333) (xy 215.847814 -121.193035)
			(xy 215.867075 -121.10225) (xy 215.89569 -121.013965) (xy 215.91397 -120.97131) (xy 215.917755 -120.961361)
			(xy 215.917769 -120.940104) (xy 215.91397 -120.930162) (xy 215.895716 -120.887498) (xy 215.867121 -120.799211)
			(xy 215.847862 -120.708429) (xy 215.838147 -120.616137) (xy 215.837516 -120.569736) (xy 215.837987 -120.528625)
			(xy 215.845572 -120.446754) (xy 215.86068 -120.365933) (xy 215.883183 -120.286851) (xy 215.912888 -120.210183)
			(xy 215.949542 -120.136583) (xy 215.992832 -120.066681) (xy 216.042388 -120.001072) (xy 216.097788 -119.940317)
			(xy 216.158558 -119.884933) (xy 216.224181 -119.835395) (xy 216.294095 -119.792124) (xy 216.367704 -119.75549)
			(xy 216.44438 -119.725806) (xy 216.523469 -119.703324) (xy 216.604294 -119.688238) (xy 216.686167 -119.680676)
			(xy 216.727278 -119.680228) (xy 216.773673 -119.680816) (xy 216.865962 -119.690459) (xy 216.956746 -119.709653)
			(xy 217.045039 -119.738191) (xy 217.087704 -119.756428) (xy 217.097646 -119.760234) (xy 217.11891 -119.760234)
			(xy 217.128852 -119.756428) (xy 217.171518 -119.738193) (xy 217.259809 -119.709646) (xy 217.350593 -119.69045)
			(xy 217.442882 -119.680814) (xy 217.489278 -119.680228) (xy 217.535673 -119.680816) (xy 217.627962 -119.690459)
			(xy 217.718746 -119.709653) (xy 217.807039 -119.738191) (xy 217.849704 -119.756428) (xy 217.859646 -119.760234)
			(xy 217.88091 -119.760234) (xy 217.890852 -119.756428) (xy 217.933518 -119.738193) (xy 218.021809 -119.709646)
			(xy 218.112593 -119.69045) (xy 218.204882 -119.680814) (xy 218.251278 -119.680228) (xy 218.297673 -119.680816)
			(xy 218.389962 -119.690459) (xy 218.480746 -119.709653) (xy 218.569039 -119.738191) (xy 218.611704 -119.756428)
			(xy 218.621646 -119.760234) (xy 218.64291 -119.760234) (xy 218.652852 -119.756428) (xy 218.695518 -119.738193)
			(xy 218.783809 -119.709646) (xy 218.874593 -119.69045) (xy 218.966882 -119.680814) (xy 219.013278 -119.680228)
			(xy 219.059673 -119.680816) (xy 219.151962 -119.690459) (xy 219.242746 -119.709653) (xy 219.331039 -119.738191)
			(xy 219.373704 -119.756428) (xy 219.383646 -119.760234) (xy 219.40491 -119.760234) (xy 219.414852 -119.756428)
			(xy 219.457518 -119.738193) (xy 219.545809 -119.709646) (xy 219.636593 -119.69045) (xy 219.728882 -119.680814)
			(xy 219.775278 -119.680228) (xy 219.821673 -119.680816) (xy 219.913962 -119.690459) (xy 220.004746 -119.709653)
			(xy 220.093039 -119.738191) (xy 220.135704 -119.756428) (xy 220.145646 -119.760234) (xy 220.16691 -119.760234)
			(xy 220.176852 -119.756428) (xy 220.219518 -119.738193) (xy 220.307809 -119.709646) (xy 220.398593 -119.69045)
			(xy 220.490882 -119.680814) (xy 220.537278 -119.680228) (xy 220.583673 -119.680816) (xy 220.675962 -119.690459)
			(xy 220.766746 -119.709653) (xy 220.855039 -119.738191) (xy 220.897704 -119.756428) (xy 220.907646 -119.760234)
			(xy 220.92891 -119.760234) (xy 220.938852 -119.756428) (xy 220.981518 -119.738193) (xy 221.069809 -119.709646)
			(xy 221.160593 -119.69045) (xy 221.252882 -119.680814) (xy 221.299278 -119.680228) (xy 221.345673 -119.680816)
			(xy 221.437962 -119.690459) (xy 221.528746 -119.709653) (xy 221.617039 -119.738191) (xy 221.659704 -119.756428)
			(xy 221.669646 -119.760234) (xy 221.69091 -119.760234) (xy 221.700852 -119.756428) (xy 221.743518 -119.738193)
			(xy 221.831809 -119.709646) (xy 221.922593 -119.69045) (xy 222.014882 -119.680814) (xy 222.061278 -119.680228)
			(xy 222.102384 -119.680733) (xy 222.184246 -119.688316) (xy 222.265059 -119.703418) (xy 222.344135 -119.72591)
			(xy 222.420798 -119.755602) (xy 222.494395 -119.792239) (xy 222.564298 -119.83551) (xy 222.629912 -119.885045)
			(xy 222.690676 -119.940422) (xy 222.746072 -120.001168) (xy 222.795628 -120.066766) (xy 222.838921 -120.136655)
			(xy 222.875582 -120.21024) (xy 222.905299 -120.286894) (xy 222.927817 -120.365962) (xy 222.942945 -120.446771)
			(xy 222.950553 -120.52863) (xy 222.95104 -120.569736) (xy 222.950424 -120.616138) (xy 222.940731 -120.708436)
			(xy 222.921474 -120.799221) (xy 222.892863 -120.887506) (xy 222.874586 -120.930162) (xy 222.87076 -120.940098)
			(xy 222.870774 -120.961367) (xy 222.874586 -120.97131) (xy 222.892861 -121.013965) (xy 222.921451 -121.102256)
			(xy 222.940704 -121.19304) (xy 222.950413 -121.285335) (xy 222.95104 -121.331736) (xy 222.950499 -121.375165)
			(xy 222.942005 -121.461606) (xy 222.925131 -121.546808) (xy 222.900038 -121.629962) (xy 222.883984 -121.670318)
			(xy 222.880612 -121.679744) (xy 222.88063 -121.699746) (xy 222.883984 -121.70918) (xy 222.900038 -121.749536)
			(xy 222.925139 -121.832688) (xy 222.942015 -121.917891) (xy 222.950505 -122.004333) (xy 222.95104 -122.047762)
			(xy 222.950434 -122.094165) (xy 222.940737 -122.186463) (xy 222.921478 -122.277248) (xy 222.892864 -122.365533)
			(xy 222.874586 -122.408188) (xy 222.870804 -122.418137) (xy 222.87079 -122.439394) (xy 222.874586 -122.449336)
			(xy 222.892837 -122.492001) (xy 222.921433 -122.580288) (xy 222.940693 -122.671069) (xy 222.950409 -122.763361)
			(xy 222.95104 -122.809762) (xy 222.950563 -122.851239) (xy 222.942823 -122.933832) (xy 222.927426 -123.015345)
			(xy 222.904504 -123.09507) (xy 222.889826 -123.133866) (xy 222.886651 -123.143365) (xy 222.887035 -123.163366)
			(xy 222.890588 -123.172728) (xy 222.908345 -123.214883) (xy 222.936112 -123.302044) (xy 222.954787 -123.391595)
			(xy 222.964172 -123.482589) (xy 222.964756 -123.528328) (xy 222.964274 -123.569438) (xy 222.956685 -123.651306)
			(xy 222.941572 -123.732125) (xy 222.919067 -123.811204) (xy 222.88936 -123.887869) (xy 222.852705 -123.961465)
			(xy 222.809414 -124.031365) (xy 222.759859 -124.096972) (xy 222.70446 -124.157726) (xy 222.643692 -124.213108)
			(xy 222.578072 -124.262647) (xy 222.508161 -124.305918) (xy 222.434555 -124.342554) (xy 222.357882 -124.372241)
			(xy 222.278797 -124.394726) (xy 222.197974 -124.409817) (xy 222.116104 -124.417385) (xy 222.074994 -124.417836)
			(xy 222.028598 -124.417253) (xy 221.93631 -124.407607) (xy 221.845526 -124.388412) (xy 221.757233 -124.359874)
			(xy 221.714568 -124.341636) (xy 221.704626 -124.33783) (xy 221.683362 -124.33783) (xy 221.67342 -124.341636)
			(xy 221.630759 -124.359884) (xy 221.542466 -124.388427) (xy 221.451681 -124.407619) (xy 221.35939 -124.417251)
			(xy 221.312994 -124.417836) (xy 221.266598 -124.417253) (xy 221.17431 -124.407607) (xy 221.083526 -124.388412)
			(xy 220.995233 -124.359874) (xy 220.952568 -124.341636) (xy 220.942626 -124.33783) (xy 220.921362 -124.33783)
			(xy 220.91142 -124.341636) (xy 220.868759 -124.359884) (xy 220.780466 -124.388427) (xy 220.689681 -124.407619)
			(xy 220.59739 -124.417251) (xy 220.550994 -124.417836) (xy 220.504598 -124.417253) (xy 220.41231 -124.407607)
			(xy 220.321526 -124.388412) (xy 220.233233 -124.359874) (xy 220.190568 -124.341636) (xy 220.180626 -124.33783)
			(xy 220.159362 -124.33783) (xy 220.14942 -124.341636) (xy 220.106759 -124.359884) (xy 220.018466 -124.388427)
			(xy 219.927681 -124.407619) (xy 219.83539 -124.417251) (xy 219.788994 -124.417836) (xy 219.742598 -124.417253)
			(xy 219.65031 -124.407607) (xy 219.559526 -124.388412) (xy 219.471233 -124.359874) (xy 219.428568 -124.341636)
			(xy 219.418626 -124.33783) (xy 219.397362 -124.33783) (xy 219.38742 -124.341636) (xy 219.344759 -124.359884)
			(xy 219.256466 -124.388427) (xy 219.165681 -124.407619) (xy 219.07339 -124.417251) (xy 219.026994 -124.417836)
			(xy 218.980598 -124.417253) (xy 218.88831 -124.407607) (xy 218.797526 -124.388412) (xy 218.709233 -124.359874)
			(xy 218.666568 -124.341636) (xy 218.656626 -124.33783) (xy 218.635362 -124.33783) (xy 218.62542 -124.341636)
			(xy 218.582759 -124.359884) (xy 218.494466 -124.388427) (xy 218.403681 -124.407619) (xy 218.31139 -124.417251)
			(xy 218.264994 -124.417836) (xy 218.218598 -124.417253) (xy 218.12631 -124.407607) (xy 218.035526 -124.388412)
			(xy 217.947233 -124.359874) (xy 217.904568 -124.341636) (xy 217.894626 -124.33783) (xy 217.873362 -124.33783)
			(xy 217.86342 -124.341636) (xy 217.820759 -124.359884) (xy 217.732466 -124.388427) (xy 217.641681 -124.407619)
			(xy 217.54939 -124.417251) (xy 217.502994 -124.417836) (xy 217.456598 -124.417253) (xy 217.36431 -124.407607)
			(xy 217.273526 -124.388412) (xy 217.185233 -124.359874) (xy 217.142568 -124.341636) (xy 217.132626 -124.33783)
			(xy 217.111362 -124.33783) (xy 217.10142 -124.341636) (xy 217.058759 -124.359884) (xy 216.970466 -124.388427)
			(xy 216.879681 -124.407619) (xy 216.78739 -124.417251) (xy 216.740994 -124.417836) (xy 216.699886 -124.417393)
			(xy 216.618022 -124.409808) (xy 216.537206 -124.394703) (xy 216.458128 -124.372207) (xy 216.381463 -124.342511)
			(xy 216.307865 -124.30587) (xy 216.23796 -124.262595) (xy 216.172346 -124.213056) (xy 216.111582 -124.157675)
			(xy 216.056186 -124.096925) (xy 216.00663 -124.031323) (xy 215.963338 -123.961429) (xy 215.926678 -123.88784)
			(xy 215.896964 -123.811182) (xy 215.874448 -123.73211) (xy 215.859323 -123.651298) (xy 215.851717 -123.569436)
			(xy 215.851232 -123.528328) (xy 215.851707 -123.486851) (xy 215.859448 -123.404258) (xy 215.874846 -123.322745)
			(xy 215.897768 -123.24302) (xy 215.912446 -123.204224) (xy 215.915622 -123.194726) (xy 215.915236 -123.174725)
			(xy 215.911684 -123.165362) (xy 215.893922 -123.123209) (xy 215.866157 -123.036047) (xy 215.847484 -122.946496)
			(xy 215.838099 -122.855501) (xy 215.837516 -122.809762) (xy 208.574132 -122.809762) (xy 208.573649 -122.851239)
			(xy 208.56591 -122.933831) (xy 208.550514 -123.015344) (xy 208.527595 -123.09507) (xy 208.512918 -123.133866)
			(xy 208.509744 -123.143365) (xy 208.510127 -123.163365) (xy 208.51368 -123.172728) (xy 208.531436 -123.214883)
			(xy 208.559204 -123.302044) (xy 208.577878 -123.391595) (xy 208.587264 -123.482589) (xy 208.587848 -123.528328)
			(xy 208.587374 -123.569438) (xy 208.579784 -123.651307) (xy 208.564672 -123.732126) (xy 208.542166 -123.811205)
			(xy 208.512459 -123.887871) (xy 208.475803 -123.961467) (xy 208.432513 -124.031368) (xy 208.382957 -124.096975)
			(xy 208.327557 -124.157729) (xy 208.266788 -124.213111) (xy 208.201168 -124.26265) (xy 208.131256 -124.305921)
			(xy 208.057649 -124.342556) (xy 207.980976 -124.372243) (xy 207.90189 -124.394727) (xy 207.821067 -124.409818)
			(xy 207.739196 -124.417385) (xy 207.698086 -124.417836) (xy 207.65169 -124.417256) (xy 207.559402 -124.407609)
			(xy 207.468618 -124.388413) (xy 207.380325 -124.359874) (xy 207.33766 -124.341636) (xy 207.327718 -124.33783)
			(xy 207.306454 -124.33783) (xy 207.296512 -124.341636) (xy 207.253852 -124.359887) (xy 207.165559 -124.388429)
			(xy 207.074773 -124.40762) (xy 206.982482 -124.417252) (xy 206.936086 -124.417836) (xy 206.88969 -124.417256)
			(xy 206.797402 -124.407609) (xy 206.706618 -124.388413) (xy 206.618325 -124.359874) (xy 206.57566 -124.341636)
			(xy 206.565718 -124.33783) (xy 206.544454 -124.33783) (xy 206.534512 -124.341636) (xy 206.491852 -124.359887)
			(xy 206.403559 -124.388429) (xy 206.312773 -124.40762) (xy 206.220482 -124.417252) (xy 206.174086 -124.417836)
			(xy 206.12769 -124.417256) (xy 206.035402 -124.407609) (xy 205.944618 -124.388413) (xy 205.856325 -124.359874)
			(xy 205.81366 -124.341636) (xy 205.803718 -124.33783) (xy 205.782454 -124.33783) (xy 205.772512 -124.341636)
			(xy 205.729852 -124.359887) (xy 205.641559 -124.388429) (xy 205.550773 -124.40762) (xy 205.458482 -124.417252)
			(xy 205.412086 -124.417836) (xy 205.36569 -124.417256) (xy 205.273402 -124.407609) (xy 205.182618 -124.388413)
			(xy 205.094325 -124.359874) (xy 205.05166 -124.341636) (xy 205.041718 -124.33783) (xy 205.020454 -124.33783)
			(xy 205.010512 -124.341636) (xy 204.967852 -124.359887) (xy 204.879559 -124.388429) (xy 204.788773 -124.40762)
			(xy 204.696482 -124.417252) (xy 204.650086 -124.417836) (xy 204.60369 -124.417256) (xy 204.511402 -124.407609)
			(xy 204.420618 -124.388413) (xy 204.332325 -124.359874) (xy 204.28966 -124.341636) (xy 204.279718 -124.33783)
			(xy 204.258454 -124.33783) (xy 204.248512 -124.341636) (xy 204.205852 -124.359887) (xy 204.117559 -124.388429)
			(xy 204.026773 -124.40762) (xy 203.934482 -124.417252) (xy 203.888086 -124.417836) (xy 203.84169 -124.417256)
			(xy 203.749402 -124.407609) (xy 203.658618 -124.388413) (xy 203.570325 -124.359874) (xy 203.52766 -124.341636)
			(xy 203.517718 -124.33783) (xy 203.496454 -124.33783) (xy 203.486512 -124.341636) (xy 203.443852 -124.359887)
			(xy 203.355559 -124.388429) (xy 203.264773 -124.40762) (xy 203.172482 -124.417252) (xy 203.126086 -124.417836)
			(xy 203.07969 -124.417256) (xy 202.987402 -124.407609) (xy 202.896618 -124.388413) (xy 202.808325 -124.359874)
			(xy 202.76566 -124.341636) (xy 202.755718 -124.33783) (xy 202.734454 -124.33783) (xy 202.724512 -124.341636)
			(xy 202.681852 -124.359887) (xy 202.593559 -124.388429) (xy 202.502773 -124.40762) (xy 202.410482 -124.417252)
			(xy 202.364086 -124.417836) (xy 202.322978 -124.417401) (xy 202.241113 -124.409815) (xy 202.160298 -124.394709)
			(xy 202.08122 -124.372212) (xy 202.004555 -124.342516) (xy 201.930956 -124.305875) (xy 201.861052 -124.262599)
			(xy 201.795437 -124.21306) (xy 201.734673 -124.157678) (xy 201.679277 -124.096927) (xy 201.629722 -124.031325)
			(xy 201.58643 -123.961431) (xy 201.54977 -123.887841) (xy 201.520056 -123.811183) (xy 201.49754 -123.732111)
			(xy 201.482415 -123.651299) (xy 201.474809 -123.569436) (xy 201.474324 -123.528328) (xy 201.4748 -123.486851)
			(xy 201.48254 -123.404258) (xy 201.497938 -123.322745) (xy 201.52086 -123.24302) (xy 201.535538 -123.204224)
			(xy 201.538714 -123.194726) (xy 201.538328 -123.174725) (xy 201.534776 -123.165362) (xy 201.517014 -123.123209)
			(xy 201.489249 -123.036047) (xy 201.470576 -122.946496) (xy 201.461191 -122.855501) (xy 201.460608 -122.809762)
			(xy 185.330851 -122.809762) (xy 185.308717 -122.822218) (xy 185.200319 -122.874105) (xy 185.088729 -122.918714)
			(xy 184.974435 -122.95585) (xy 184.857936 -122.985352) (xy 184.739742 -123.007089) (xy 184.62037 -123.020968)
			(xy 184.500342 -123.026927) (xy 184.380183 -123.02494) (xy 184.260417 -123.015016) (xy 184.141569 -122.997198)
			(xy 184.024159 -122.971564) (xy 183.908699 -122.938227) (xy 183.795695 -122.897332) (xy 183.685641 -122.849058)
			(xy 183.579018 -122.793616) (xy 183.476293 -122.731248) (xy 183.377914 -122.662227) (xy 183.284311 -122.586856)
			(xy 183.195895 -122.505463) (xy 183.113051 -122.418404) (xy 183.036142 -122.326061) (xy 182.965505 -122.228837)
			(xy 182.901447 -122.127156) (xy 182.84425 -122.021465) (xy 182.794162 -121.912224) (xy 182.751405 -121.799912)
			(xy 182.716163 -121.685019) (xy 182.688592 -121.568048) (xy 182.668811 -121.449511) (xy 182.656908 -121.329926)
			(xy 182.652935 -121.209816) (xy 146.286982 -121.209816) (xy 146.286485 -121.269904) (xy 146.278543 -121.389817)
			(xy 146.262693 -121.508943) (xy 146.239004 -121.626762) (xy 146.20758 -121.742757) (xy 146.168559 -121.856421)
			(xy 146.122111 -121.967258) (xy 146.06844 -122.074783) (xy 146.007779 -122.178526) (xy 145.940394 -122.278033)
			(xy 145.866581 -122.372869) (xy 145.786661 -122.462619) (xy 145.700984 -122.54689) (xy 145.609925 -122.625316)
			(xy 145.513881 -122.697551) (xy 145.413274 -122.763281) (xy 145.308543 -122.822218) (xy 145.200145 -122.874105)
			(xy 145.088555 -122.918714) (xy 144.974261 -122.95585) (xy 144.857762 -122.985352) (xy 144.739568 -123.007089)
			(xy 144.620196 -123.020968) (xy 144.500168 -123.026927) (xy 144.380009 -123.02494) (xy 144.260243 -123.015016)
			(xy 144.141395 -122.997198) (xy 144.023985 -122.971564) (xy 143.908525 -122.938227) (xy 143.795521 -122.897332)
			(xy 143.685467 -122.849058) (xy 143.578844 -122.793616) (xy 143.476119 -122.731248) (xy 143.37774 -122.662227)
			(xy 143.284137 -122.586856) (xy 143.195721 -122.505463) (xy 143.112877 -122.418404) (xy 143.035968 -122.326061)
			(xy 142.965331 -122.228837) (xy 142.901273 -122.127156) (xy 142.844076 -122.021465) (xy 142.793988 -121.912224)
			(xy 142.751231 -121.799912) (xy 142.715989 -121.685019) (xy 142.688418 -121.568048) (xy 142.668637 -121.449511)
			(xy 142.656734 -121.329926) (xy 142.652761 -121.209816) (xy 106.286808 -121.209816) (xy 106.286311 -121.269904)
			(xy 106.278369 -121.389817) (xy 106.262519 -121.508943) (xy 106.23883 -121.626762) (xy 106.207406 -121.742757)
			(xy 106.168385 -121.856421) (xy 106.121937 -121.967258) (xy 106.068266 -122.074783) (xy 106.007605 -122.178526)
			(xy 105.94022 -122.278033) (xy 105.866407 -122.372869) (xy 105.786487 -122.462619) (xy 105.70081 -122.54689)
			(xy 105.609751 -122.625316) (xy 105.513707 -122.697551) (xy 105.4131 -122.763281) (xy 105.308369 -122.822218)
			(xy 105.199971 -122.874105) (xy 105.088381 -122.918714) (xy 104.974087 -122.95585) (xy 104.857588 -122.985352)
			(xy 104.739394 -123.007089) (xy 104.620022 -123.020968) (xy 104.499994 -123.026927) (xy 104.379835 -123.02494)
			(xy 104.260069 -123.015016) (xy 104.141221 -122.997198) (xy 104.023811 -122.971564) (xy 103.908351 -122.938227)
			(xy 103.795347 -122.897332) (xy 103.685293 -122.849058) (xy 103.57867 -122.793616) (xy 103.475945 -122.731248)
			(xy 103.377566 -122.662227) (xy 103.283963 -122.586856) (xy 103.195547 -122.505463) (xy 103.112703 -122.418404)
			(xy 103.035794 -122.326061) (xy 102.965157 -122.228837) (xy 102.901099 -122.127156) (xy 102.843902 -122.021465)
			(xy 102.793814 -121.912224) (xy 102.751057 -121.799912) (xy 102.715815 -121.685019) (xy 102.688244 -121.568048)
			(xy 102.668463 -121.449511) (xy 102.65656 -121.329926) (xy 102.652587 -121.209816) (xy 66.286888 -121.209816)
			(xy 66.286391 -121.269904) (xy 66.278449 -121.389817) (xy 66.262599 -121.508943) (xy 66.23891 -121.626762)
			(xy 66.207486 -121.742757) (xy 66.168465 -121.856421) (xy 66.122017 -121.967258) (xy 66.068346 -122.074783)
			(xy 66.007685 -122.178526) (xy 65.9403 -122.278033) (xy 65.866487 -122.372869) (xy 65.786567 -122.462619)
			(xy 65.70089 -122.54689) (xy 65.609831 -122.625316) (xy 65.513787 -122.697551) (xy 65.41318 -122.763281)
			(xy 65.308449 -122.822218) (xy 65.200051 -122.874105) (xy 65.088461 -122.918714) (xy 64.974167 -122.95585)
			(xy 64.857668 -122.985352) (xy 64.739474 -123.007089) (xy 64.620102 -123.020968) (xy 64.500074 -123.026927)
			(xy 64.379915 -123.02494) (xy 64.260149 -123.015016) (xy 64.141301 -122.997198) (xy 64.023891 -122.971564)
			(xy 63.908431 -122.938227) (xy 63.795427 -122.897332) (xy 63.685373 -122.849058) (xy 63.57875 -122.793616)
			(xy 63.476025 -122.731248) (xy 63.377646 -122.662227) (xy 63.284043 -122.586856) (xy 63.195627 -122.505463)
			(xy 63.112783 -122.418404) (xy 63.035874 -122.326061) (xy 62.965237 -122.228837) (xy 62.901179 -122.127156)
			(xy 62.843982 -122.021465) (xy 62.793894 -121.912224) (xy 62.751137 -121.799912) (xy 62.715895 -121.685019)
			(xy 62.688324 -121.568048) (xy 62.668543 -121.449511) (xy 62.65664 -121.329926) (xy 62.652667 -121.209816)
			(xy 29.791898 -121.209816) (xy 29.85764 -121.327499) (xy 29.919311 -121.454246) (xy 29.973712 -121.584279)
			(xy 30.02067 -121.717182) (xy 30.060033 -121.852528) (xy 30.091676 -121.989885) (xy 30.115498 -122.128812)
			(xy 30.131421 -122.268864) (xy 30.139396 -122.409593) (xy 30.139894 -122.48007) (xy 30.139396 -122.550547)
			(xy 30.131421 -122.691276) (xy 30.115498 -122.831328) (xy 30.091676 -122.970255) (xy 30.060033 -123.107612)
			(xy 30.02067 -123.242958) (xy 29.973712 -123.375861) (xy 29.919311 -123.505894) (xy 29.85764 -123.632641)
			(xy 29.788897 -123.755696) (xy 29.713303 -123.874665) (xy 29.631099 -123.989167) (xy 29.542548 -124.098835)
			(xy 29.447935 -124.203317) (xy 29.347563 -124.302279) (xy 29.241752 -124.395404) (xy 29.130843 -124.482393)
			(xy 29.015189 -124.562969) (xy 28.895163 -124.636872) (xy 28.771147 -124.703867) (xy 28.64354 -124.763738)
			(xy 28.51275 -124.816294) (xy 28.379196 -124.861366) (xy 28.243306 -124.89881) (xy 28.105515 -124.928506)
			(xy 27.966265 -124.950359) (xy 27.826002 -124.964299) (xy 27.685174 -124.970282) (xy 27.544234 -124.968287)
			(xy 27.403632 -124.958322) (xy 27.263819 -124.940418) (xy 27.125243 -124.914633) (xy 26.988348 -124.88105)
			(xy 26.853572 -124.839775) (xy 26.721347 -124.790941) (xy 26.592097 -124.734706) (xy 26.466235 -124.671247)
			(xy 26.344165 -124.60077) (xy 26.226278 -124.5235) (xy 26.112951 -124.439683) (xy 26.004547 -124.34959)
			(xy 25.901415 -124.253508) (xy 25.803883 -124.151745) (xy 25.712264 -124.044627) (xy 25.626853 -123.932498)
			(xy 25.547922 -123.815716) (xy 25.475724 -123.694655) (xy 25.410492 -123.569704) (xy 25.352432 -123.441262)
			(xy 25.301732 -123.309742) (xy 25.258555 -123.175563) (xy 25.223037 -123.039157) (xy 25.195294 -122.90096)
			(xy 25.175414 -122.761415) (xy 25.16346 -122.620968) (xy 25.159471 -122.48007) (xy 25.043387 -122.48007)
			(xy 25.043387 -122.570147) (xy 25.035304 -122.750119) (xy 25.019155 -122.929548) (xy 24.994973 -123.108071)
			(xy 24.962805 -123.28533) (xy 24.922717 -123.460967) (xy 24.87479 -123.634628) (xy 24.819119 -123.805965)
			(xy 24.755817 -123.974631) (xy 24.685013 -124.140287) (xy 24.606847 -124.3026) (xy 24.521478 -124.461243)
			(xy 24.429077 -124.615895) (xy 24.329831 -124.766247) (xy 24.223939 -124.911994) (xy 24.111615 -125.052844)
			(xy 23.993085 -125.188513) (xy 23.868587 -125.318727) (xy 23.738373 -125.443225) (xy 23.602704 -125.561755)
			(xy 23.461854 -125.674079) (xy 23.316107 -125.779971) (xy 23.165755 -125.879217) (xy 23.011103 -125.971618)
			(xy 22.85246 -126.056987) (xy 22.690147 -126.135153) (xy 22.524491 -126.205957) (xy 22.355825 -126.269259)
			(xy 22.184488 -126.32493) (xy 22.010827 -126.372857) (xy 21.83519 -126.412945) (xy 21.657931 -126.445113)
			(xy 21.479408 -126.469295) (xy 21.299979 -126.485444) (xy 21.154006 -126.492) (xy 42.020472 -126.492)
			(xy 42.024502 -126.407397) (xy 42.036556 -126.32356) (xy 42.056525 -126.241249) (xy 42.084227 -126.161209)
			(xy 42.119412 -126.084164) (xy 42.161762 -126.010813) (xy 42.210892 -125.941819) (xy 42.266358 -125.877808)
			(xy 42.327658 -125.81936) (xy 42.394236 -125.767002) (xy 42.465489 -125.721211) (xy 42.540773 -125.6824)
			(xy 42.619405 -125.650921) (xy 42.700673 -125.627059) (xy 42.783841 -125.61103) (xy 42.868157 -125.60298)
			(xy 42.910506 -125.602492) (xy 42.956902 -125.603073) (xy 43.04919 -125.612718) (xy 43.139974 -125.631915)
			(xy 43.228267 -125.660454) (xy 43.270932 -125.678692) (xy 43.280874 -125.682498) (xy 43.302138 -125.682498)
			(xy 43.31208 -125.678692) (xy 43.354741 -125.660445) (xy 43.443034 -125.631902) (xy 43.533819 -125.612709)
			(xy 43.62611 -125.603077) (xy 43.672506 -125.602492) (xy 43.714854 -125.602996) (xy 43.799167 -125.611047)
			(xy 43.882333 -125.627077) (xy 43.963599 -125.650939) (xy 44.042229 -125.682418) (xy 44.11751 -125.721229)
			(xy 44.188761 -125.767019) (xy 44.255337 -125.819376) (xy 44.316634 -125.877823) (xy 44.372099 -125.941833)
			(xy 44.421227 -126.010825) (xy 44.463575 -126.084174) (xy 44.49876 -126.161217) (xy 44.526461 -126.241256)
			(xy 44.546429 -126.323565) (xy 44.558482 -126.407399) (xy 44.562513 -126.492) (xy 54.212472 -126.492)
			(xy 54.216502 -126.407397) (xy 54.228556 -126.32356) (xy 54.248525 -126.241249) (xy 54.276227 -126.161209)
			(xy 54.311412 -126.084164) (xy 54.353762 -126.010813) (xy 54.402892 -125.941819) (xy 54.458358 -125.877808)
			(xy 54.519658 -125.81936) (xy 54.586236 -125.767002) (xy 54.657489 -125.721211) (xy 54.732773 -125.6824)
			(xy 54.811405 -125.650921) (xy 54.892673 -125.627059) (xy 54.975841 -125.61103) (xy 55.060157 -125.60298)
			(xy 55.102506 -125.602492) (xy 55.148902 -125.603073) (xy 55.24119 -125.612718) (xy 55.331974 -125.631915)
			(xy 55.420267 -125.660454) (xy 55.462932 -125.678692) (xy 55.472874 -125.682498) (xy 55.494138 -125.682498)
			(xy 55.50408 -125.678692) (xy 55.546741 -125.660445) (xy 55.635034 -125.631902) (xy 55.725819 -125.612709)
			(xy 55.81811 -125.603077) (xy 55.864506 -125.602492) (xy 55.906854 -125.602996) (xy 55.991167 -125.611047)
			(xy 56.074333 -125.627077) (xy 56.155599 -125.650939) (xy 56.234229 -125.682418) (xy 56.30951 -125.721229)
			(xy 56.380761 -125.767019) (xy 56.447337 -125.819376) (xy 56.508634 -125.877823) (xy 56.564099 -125.941833)
			(xy 56.613227 -126.010825) (xy 56.655575 -126.084174) (xy 56.69076 -126.161217) (xy 56.718461 -126.241256)
			(xy 56.738429 -126.323565) (xy 56.750482 -126.407399) (xy 56.754513 -126.492) (xy 66.404472 -126.492)
			(xy 66.408502 -126.407397) (xy 66.420556 -126.32356) (xy 66.440525 -126.241249) (xy 66.468227 -126.161209)
			(xy 66.503412 -126.084164) (xy 66.545762 -126.010813) (xy 66.594892 -125.941819) (xy 66.650358 -125.877808)
			(xy 66.711658 -125.81936) (xy 66.778236 -125.767002) (xy 66.849489 -125.721211) (xy 66.924773 -125.6824)
			(xy 67.003405 -125.650921) (xy 67.084673 -125.627059) (xy 67.167841 -125.61103) (xy 67.252157 -125.60298)
			(xy 67.294506 -125.602492) (xy 67.340902 -125.603073) (xy 67.43319 -125.612718) (xy 67.523974 -125.631915)
			(xy 67.612267 -125.660454) (xy 67.654932 -125.678692) (xy 67.664874 -125.682498) (xy 67.686138 -125.682498)
			(xy 67.69608 -125.678692) (xy 67.738741 -125.660445) (xy 67.827034 -125.631902) (xy 67.917819 -125.612709)
			(xy 68.01011 -125.603077) (xy 68.056506 -125.602492) (xy 68.098854 -125.602996) (xy 68.183167 -125.611047)
			(xy 68.266333 -125.627077) (xy 68.347599 -125.650939) (xy 68.426229 -125.682418) (xy 68.50151 -125.721229)
			(xy 68.572761 -125.767019) (xy 68.639337 -125.819376) (xy 68.700634 -125.877823) (xy 68.756099 -125.941833)
			(xy 68.805227 -126.010825) (xy 68.847575 -126.084174) (xy 68.88276 -126.161217) (xy 68.910461 -126.241256)
			(xy 68.930429 -126.323565) (xy 68.942482 -126.407399) (xy 68.946513 -126.492) (xy 82.020372 -126.492)
			(xy 82.024402 -126.407396) (xy 82.036457 -126.323558) (xy 82.056426 -126.241246) (xy 82.084129 -126.161204)
			(xy 82.119315 -126.084159) (xy 82.161666 -126.010807) (xy 82.210798 -125.941813) (xy 82.266265 -125.877801)
			(xy 82.327566 -125.819352) (xy 82.394146 -125.766995) (xy 82.465401 -125.721204) (xy 82.540686 -125.682394)
			(xy 82.61932 -125.650916) (xy 82.700589 -125.627055) (xy 82.783759 -125.611028) (xy 82.868076 -125.602979)
			(xy 82.910426 -125.602492) (xy 82.956821 -125.603101) (xy 83.049109 -125.612738) (xy 83.139892 -125.631927)
			(xy 83.228187 -125.660458) (xy 83.270852 -125.678692) (xy 83.280794 -125.682498) (xy 83.302058 -125.682498)
			(xy 83.312 -125.678692) (xy 83.354659 -125.660439) (xy 83.442952 -125.631897) (xy 83.533738 -125.612706)
			(xy 83.62603 -125.603076) (xy 83.672426 -125.602492) (xy 83.714774 -125.602997) (xy 83.799085 -125.61105)
			(xy 83.88225 -125.627081) (xy 83.963514 -125.650944) (xy 84.042142 -125.682424) (xy 84.117421 -125.721235)
			(xy 84.188671 -125.767026) (xy 84.255245 -125.819383) (xy 84.316541 -125.87783) (xy 84.372004 -125.941839)
			(xy 84.421131 -126.010831) (xy 84.463478 -126.08418) (xy 84.498661 -126.161222) (xy 84.526362 -126.241259)
			(xy 84.546329 -126.323567) (xy 84.558383 -126.407401) (xy 84.562413 -126.492) (xy 94.212372 -126.492)
			(xy 94.216402 -126.407396) (xy 94.228457 -126.323558) (xy 94.248426 -126.241246) (xy 94.276129 -126.161204)
			(xy 94.311315 -126.084159) (xy 94.353666 -126.010807) (xy 94.402798 -125.941813) (xy 94.458265 -125.877801)
			(xy 94.519566 -125.819352) (xy 94.586146 -125.766995) (xy 94.657401 -125.721204) (xy 94.732686 -125.682394)
			(xy 94.81132 -125.650916) (xy 94.892589 -125.627055) (xy 94.975759 -125.611028) (xy 95.060076 -125.602979)
			(xy 95.102426 -125.602492) (xy 95.148821 -125.603101) (xy 95.241109 -125.612738) (xy 95.331892 -125.631927)
			(xy 95.420187 -125.660458) (xy 95.462852 -125.678692) (xy 95.472794 -125.682498) (xy 95.494058 -125.682498)
			(xy 95.504 -125.678692) (xy 95.546659 -125.660439) (xy 95.634952 -125.631897) (xy 95.725738 -125.612706)
			(xy 95.81803 -125.603076) (xy 95.864426 -125.602492) (xy 95.906774 -125.602997) (xy 95.991085 -125.61105)
			(xy 96.07425 -125.627081) (xy 96.155514 -125.650944) (xy 96.234142 -125.682424) (xy 96.309421 -125.721235)
			(xy 96.380671 -125.767026) (xy 96.447245 -125.819383) (xy 96.508541 -125.87783) (xy 96.564004 -125.941839)
			(xy 96.613131 -126.010831) (xy 96.655478 -126.08418) (xy 96.690661 -126.161222) (xy 96.718362 -126.241259)
			(xy 96.738329 -126.323567) (xy 96.750383 -126.407401) (xy 96.754413 -126.492) (xy 106.404372 -126.492)
			(xy 106.408402 -126.407396) (xy 106.420457 -126.323558) (xy 106.440426 -126.241246) (xy 106.468129 -126.161204)
			(xy 106.503315 -126.084159) (xy 106.545666 -126.010807) (xy 106.594798 -125.941813) (xy 106.650265 -125.877801)
			(xy 106.711566 -125.819352) (xy 106.778146 -125.766995) (xy 106.849401 -125.721204) (xy 106.924686 -125.682394)
			(xy 107.00332 -125.650916) (xy 107.084589 -125.627055) (xy 107.167759 -125.611028) (xy 107.252076 -125.602979)
			(xy 107.294426 -125.602492) (xy 107.340821 -125.603101) (xy 107.433109 -125.612738) (xy 107.523892 -125.631927)
			(xy 107.612187 -125.660458) (xy 107.654852 -125.678692) (xy 107.664794 -125.682498) (xy 107.686058 -125.682498)
			(xy 107.696 -125.678692) (xy 107.738659 -125.660439) (xy 107.826952 -125.631897) (xy 107.917738 -125.612706)
			(xy 108.01003 -125.603076) (xy 108.056426 -125.602492) (xy 108.098774 -125.602997) (xy 108.183085 -125.61105)
			(xy 108.26625 -125.627081) (xy 108.347514 -125.650944) (xy 108.426142 -125.682424) (xy 108.501421 -125.721235)
			(xy 108.572671 -125.767026) (xy 108.639245 -125.819383) (xy 108.700541 -125.87783) (xy 108.756004 -125.941839)
			(xy 108.805131 -126.010831) (xy 108.847478 -126.08418) (xy 108.882661 -126.161222) (xy 108.910362 -126.241259)
			(xy 108.930329 -126.323567) (xy 108.942383 -126.407401) (xy 108.946413 -126.492) (xy 122.020588 -126.492)
			(xy 122.024618 -126.407399) (xy 122.036671 -126.323564) (xy 122.056639 -126.241255) (xy 122.084341 -126.161216)
			(xy 122.119525 -126.084173) (xy 122.161874 -126.010823) (xy 122.211003 -125.941831) (xy 122.266468 -125.877821)
			(xy 122.327766 -125.819373) (xy 122.394342 -125.767017) (xy 122.465594 -125.721227) (xy 122.540875 -125.682416)
			(xy 122.619505 -125.650937) (xy 122.700772 -125.627076) (xy 122.783938 -125.611047) (xy 122.868252 -125.602996)
			(xy 122.9106 -125.602492) (xy 122.956996 -125.603075) (xy 123.049284 -125.61272) (xy 123.140068 -125.631916)
			(xy 123.228361 -125.660454) (xy 123.271026 -125.678692) (xy 123.280968 -125.682498) (xy 123.302232 -125.682498)
			(xy 123.312174 -125.678692) (xy 123.354836 -125.660447) (xy 123.443129 -125.631903) (xy 123.533914 -125.61271)
			(xy 123.626204 -125.603077) (xy 123.6726 -125.602492) (xy 123.714948 -125.602996) (xy 123.799262 -125.611047)
			(xy 123.882428 -125.627076) (xy 123.963695 -125.650937) (xy 124.042325 -125.682416) (xy 124.117606 -125.721227)
			(xy 124.188858 -125.767017) (xy 124.255434 -125.819373) (xy 124.316732 -125.877821) (xy 124.372197 -125.941831)
			(xy 124.421326 -126.010823) (xy 124.463675 -126.084173) (xy 124.498859 -126.161216) (xy 124.526561 -126.241255)
			(xy 124.546529 -126.323564) (xy 124.558582 -126.407399) (xy 124.562613 -126.492) (xy 134.212588 -126.492)
			(xy 134.216618 -126.407399) (xy 134.228671 -126.323564) (xy 134.248639 -126.241255) (xy 134.276341 -126.161216)
			(xy 134.311525 -126.084173) (xy 134.353874 -126.010823) (xy 134.403003 -125.941831) (xy 134.458468 -125.877821)
			(xy 134.519766 -125.819373) (xy 134.586342 -125.767017) (xy 134.657594 -125.721227) (xy 134.732875 -125.682416)
			(xy 134.811505 -125.650937) (xy 134.892772 -125.627076) (xy 134.975938 -125.611047) (xy 135.060252 -125.602996)
			(xy 135.1026 -125.602492) (xy 135.148996 -125.603075) (xy 135.241284 -125.61272) (xy 135.332068 -125.631916)
			(xy 135.420361 -125.660454) (xy 135.463026 -125.678692) (xy 135.472968 -125.682498) (xy 135.494232 -125.682498)
			(xy 135.504174 -125.678692) (xy 135.546836 -125.660447) (xy 135.635129 -125.631903) (xy 135.725914 -125.61271)
			(xy 135.818204 -125.603077) (xy 135.8646 -125.602492) (xy 135.906948 -125.602996) (xy 135.991262 -125.611047)
			(xy 136.074428 -125.627076) (xy 136.155695 -125.650937) (xy 136.234325 -125.682416) (xy 136.309606 -125.721227)
			(xy 136.380858 -125.767017) (xy 136.447434 -125.819373) (xy 136.508732 -125.877821) (xy 136.564197 -125.941831)
			(xy 136.613326 -126.010823) (xy 136.655675 -126.084173) (xy 136.690859 -126.161216) (xy 136.718561 -126.241255)
			(xy 136.738529 -126.323564) (xy 136.750582 -126.407399) (xy 136.754613 -126.492) (xy 146.404588 -126.492)
			(xy 146.408618 -126.407399) (xy 146.420671 -126.323564) (xy 146.440639 -126.241255) (xy 146.468341 -126.161216)
			(xy 146.503525 -126.084173) (xy 146.545874 -126.010823) (xy 146.595003 -125.941831) (xy 146.650468 -125.877821)
			(xy 146.711766 -125.819373) (xy 146.778342 -125.767017) (xy 146.849594 -125.721227) (xy 146.924875 -125.682416)
			(xy 147.003505 -125.650937) (xy 147.084772 -125.627076) (xy 147.167938 -125.611047) (xy 147.252252 -125.602996)
			(xy 147.2946 -125.602492) (xy 147.340996 -125.603075) (xy 147.433284 -125.61272) (xy 147.524068 -125.631916)
			(xy 147.612361 -125.660454) (xy 147.655026 -125.678692) (xy 147.664968 -125.682498) (xy 147.686232 -125.682498)
			(xy 147.696174 -125.678692) (xy 147.738836 -125.660447) (xy 147.827129 -125.631903) (xy 147.917914 -125.61271)
			(xy 148.010204 -125.603077) (xy 148.0566 -125.602492) (xy 148.098948 -125.602996) (xy 148.183262 -125.611047)
			(xy 148.266428 -125.627076) (xy 148.347695 -125.650937) (xy 148.426325 -125.682416) (xy 148.501606 -125.721227)
			(xy 148.572858 -125.767017) (xy 148.639434 -125.819373) (xy 148.700732 -125.877821) (xy 148.756197 -125.941831)
			(xy 148.805326 -126.010823) (xy 148.847675 -126.084173) (xy 148.882859 -126.161216) (xy 148.910561 -126.241255)
			(xy 148.930529 -126.323564) (xy 148.942582 -126.407399) (xy 148.946613 -126.492) (xy 162.020787 -126.492)
			(xy 162.024817 -126.407401) (xy 162.036871 -126.323567) (xy 162.056838 -126.241259) (xy 162.084539 -126.161222)
			(xy 162.119722 -126.08418) (xy 162.162069 -126.010831) (xy 162.211196 -125.941839) (xy 162.266659 -125.87783)
			(xy 162.327955 -125.819383) (xy 162.394529 -125.767026) (xy 162.465779 -125.721235) (xy 162.541058 -125.682424)
			(xy 162.619686 -125.650944) (xy 162.70095 -125.627081) (xy 162.784115 -125.61105) (xy 162.868426 -125.602997)
			(xy 162.910774 -125.602492) (xy 162.957169 -125.603084) (xy 163.049457 -125.612726) (xy 163.140241 -125.63192)
			(xy 163.228535 -125.660455) (xy 163.2712 -125.678692) (xy 163.281142 -125.682498) (xy 163.302406 -125.682498)
			(xy 163.312348 -125.678692) (xy 163.355014 -125.660456) (xy 163.443305 -125.63191) (xy 163.534089 -125.612714)
			(xy 163.626378 -125.603078) (xy 163.672774 -125.602492) (xy 163.715124 -125.602979) (xy 163.799441 -125.611028)
			(xy 163.882611 -125.627055) (xy 163.96388 -125.650916) (xy 164.042514 -125.682394) (xy 164.117799 -125.721204)
			(xy 164.189054 -125.766995) (xy 164.255634 -125.819352) (xy 164.316935 -125.877801) (xy 164.372402 -125.941813)
			(xy 164.421534 -126.010807) (xy 164.463885 -126.084159) (xy 164.499071 -126.161204) (xy 164.526774 -126.241246)
			(xy 164.546743 -126.323558) (xy 164.558798 -126.407396) (xy 164.562828 -126.492) (xy 174.212787 -126.492)
			(xy 174.216817 -126.407401) (xy 174.228871 -126.323567) (xy 174.248838 -126.241259) (xy 174.276539 -126.161222)
			(xy 174.311722 -126.08418) (xy 174.354069 -126.010831) (xy 174.403196 -125.941839) (xy 174.458659 -125.87783)
			(xy 174.519955 -125.819383) (xy 174.586529 -125.767026) (xy 174.657779 -125.721235) (xy 174.733058 -125.682424)
			(xy 174.811686 -125.650944) (xy 174.89295 -125.627081) (xy 174.976115 -125.61105) (xy 175.060426 -125.602997)
			(xy 175.102774 -125.602492) (xy 175.149169 -125.603084) (xy 175.241457 -125.612726) (xy 175.332241 -125.63192)
			(xy 175.420535 -125.660455) (xy 175.4632 -125.678692) (xy 175.473142 -125.682498) (xy 175.494406 -125.682498)
			(xy 175.504348 -125.678692) (xy 175.547014 -125.660456) (xy 175.635305 -125.63191) (xy 175.726089 -125.612714)
			(xy 175.818378 -125.603078) (xy 175.864774 -125.602492) (xy 175.907124 -125.602979) (xy 175.991441 -125.611028)
			(xy 176.074611 -125.627055) (xy 176.15588 -125.650916) (xy 176.234514 -125.682394) (xy 176.309799 -125.721204)
			(xy 176.381054 -125.766995) (xy 176.447634 -125.819352) (xy 176.508935 -125.877801) (xy 176.564402 -125.941813)
			(xy 176.613534 -126.010807) (xy 176.655885 -126.084159) (xy 176.691071 -126.161204) (xy 176.718774 -126.241246)
			(xy 176.738743 -126.323558) (xy 176.750798 -126.407396) (xy 176.754828 -126.492) (xy 186.404787 -126.492)
			(xy 186.408817 -126.407401) (xy 186.420871 -126.323567) (xy 186.440838 -126.241259) (xy 186.468539 -126.161222)
			(xy 186.503722 -126.08418) (xy 186.546069 -126.010831) (xy 186.595196 -125.941839) (xy 186.650659 -125.87783)
			(xy 186.711955 -125.819383) (xy 186.778529 -125.767026) (xy 186.849779 -125.721235) (xy 186.925058 -125.682424)
			(xy 187.003686 -125.650944) (xy 187.08495 -125.627081) (xy 187.168115 -125.61105) (xy 187.252426 -125.602997)
			(xy 187.294774 -125.602492) (xy 187.341169 -125.603084) (xy 187.433457 -125.612726) (xy 187.524241 -125.63192)
			(xy 187.612535 -125.660455) (xy 187.6552 -125.678692) (xy 187.665142 -125.682498) (xy 187.686406 -125.682498)
			(xy 187.696348 -125.678692) (xy 187.739014 -125.660456) (xy 187.827305 -125.63191) (xy 187.918089 -125.612714)
			(xy 188.010378 -125.603078) (xy 188.056774 -125.602492) (xy 188.099124 -125.602979) (xy 188.183441 -125.611028)
			(xy 188.266611 -125.627055) (xy 188.34788 -125.650916) (xy 188.426514 -125.682394) (xy 188.501799 -125.721204)
			(xy 188.573054 -125.766995) (xy 188.639634 -125.819352) (xy 188.700935 -125.877801) (xy 188.756402 -125.941813)
			(xy 188.805534 -126.010807) (xy 188.847885 -126.084159) (xy 188.883071 -126.161204) (xy 188.910774 -126.241246)
			(xy 188.930743 -126.323558) (xy 188.942798 -126.407396) (xy 188.946828 -126.492) (xy 188.942798 -126.576604)
			(xy 188.930743 -126.660442) (xy 188.910774 -126.742754) (xy 188.883071 -126.822796) (xy 188.847885 -126.899841)
			(xy 188.805534 -126.973193) (xy 188.756402 -127.042187) (xy 188.700935 -127.106199) (xy 188.639634 -127.164648)
			(xy 188.573054 -127.217005) (xy 188.501799 -127.262796) (xy 188.426514 -127.301606) (xy 188.34788 -127.333084)
			(xy 188.266611 -127.356945) (xy 188.183441 -127.372972) (xy 188.099124 -127.381021) (xy 188.056774 -127.381508)
			(xy 188.010379 -127.380899) (xy 187.918091 -127.371262) (xy 187.827308 -127.352073) (xy 187.739013 -127.323542)
			(xy 187.696348 -127.305308) (xy 187.686406 -127.301502) (xy 187.665142 -127.301502) (xy 187.6552 -127.305308)
			(xy 187.612541 -127.323561) (xy 187.524248 -127.352103) (xy 187.433462 -127.371294) (xy 187.34117 -127.380924)
			(xy 187.294774 -127.381508) (xy 187.252426 -127.381003) (xy 187.168115 -127.37295) (xy 187.08495 -127.356919)
			(xy 187.003686 -127.333056) (xy 186.925058 -127.301576) (xy 186.849779 -127.262765) (xy 186.778529 -127.216974)
			(xy 186.711955 -127.164617) (xy 186.650659 -127.10617) (xy 186.595196 -127.042161) (xy 186.546069 -126.973169)
			(xy 186.503722 -126.89982) (xy 186.468539 -126.822778) (xy 186.440838 -126.742741) (xy 186.420871 -126.660433)
			(xy 186.408817 -126.576599) (xy 186.404787 -126.492) (xy 176.754828 -126.492) (xy 176.750798 -126.576604)
			(xy 176.738743 -126.660442) (xy 176.718774 -126.742754) (xy 176.691071 -126.822796) (xy 176.655885 -126.899841)
			(xy 176.613534 -126.973193) (xy 176.564402 -127.042187) (xy 176.508935 -127.106199) (xy 176.447634 -127.164648)
			(xy 176.381054 -127.217005) (xy 176.309799 -127.262796) (xy 176.234514 -127.301606) (xy 176.15588 -127.333084)
			(xy 176.074611 -127.356945) (xy 175.991441 -127.372972) (xy 175.907124 -127.381021) (xy 175.864774 -127.381508)
			(xy 175.818379 -127.380899) (xy 175.726091 -127.371262) (xy 175.635308 -127.352073) (xy 175.547013 -127.323542)
			(xy 175.504348 -127.305308) (xy 175.494406 -127.301502) (xy 175.473142 -127.301502) (xy 175.4632 -127.305308)
			(xy 175.420541 -127.323561) (xy 175.332248 -127.352103) (xy 175.241462 -127.371294) (xy 175.14917 -127.380924)
			(xy 175.102774 -127.381508) (xy 175.060426 -127.381003) (xy 174.976115 -127.37295) (xy 174.89295 -127.356919)
			(xy 174.811686 -127.333056) (xy 174.733058 -127.301576) (xy 174.657779 -127.262765) (xy 174.586529 -127.216974)
			(xy 174.519955 -127.164617) (xy 174.458659 -127.10617) (xy 174.403196 -127.042161) (xy 174.354069 -126.973169)
			(xy 174.311722 -126.89982) (xy 174.276539 -126.822778) (xy 174.248838 -126.742741) (xy 174.228871 -126.660433)
			(xy 174.216817 -126.576599) (xy 174.212787 -126.492) (xy 164.562828 -126.492) (xy 164.558798 -126.576604)
			(xy 164.546743 -126.660442) (xy 164.526774 -126.742754) (xy 164.499071 -126.822796) (xy 164.463885 -126.899841)
			(xy 164.421534 -126.973193) (xy 164.372402 -127.042187) (xy 164.316935 -127.106199) (xy 164.255634 -127.164648)
			(xy 164.189054 -127.217005) (xy 164.117799 -127.262796) (xy 164.042514 -127.301606) (xy 163.96388 -127.333084)
			(xy 163.882611 -127.356945) (xy 163.799441 -127.372972) (xy 163.715124 -127.381021) (xy 163.672774 -127.381508)
			(xy 163.626379 -127.380899) (xy 163.534091 -127.371262) (xy 163.443308 -127.352073) (xy 163.355013 -127.323542)
			(xy 163.312348 -127.305308) (xy 163.302406 -127.301502) (xy 163.281142 -127.301502) (xy 163.2712 -127.305308)
			(xy 163.228541 -127.323561) (xy 163.140248 -127.352103) (xy 163.049462 -127.371294) (xy 162.95717 -127.380924)
			(xy 162.910774 -127.381508) (xy 162.868426 -127.381003) (xy 162.784115 -127.37295) (xy 162.70095 -127.356919)
			(xy 162.619686 -127.333056) (xy 162.541058 -127.301576) (xy 162.465779 -127.262765) (xy 162.394529 -127.216974)
			(xy 162.327955 -127.164617) (xy 162.266659 -127.10617) (xy 162.211196 -127.042161) (xy 162.162069 -126.973169)
			(xy 162.119722 -126.89982) (xy 162.084539 -126.822778) (xy 162.056838 -126.742741) (xy 162.036871 -126.660433)
			(xy 162.024817 -126.576599) (xy 162.020787 -126.492) (xy 148.946613 -126.492) (xy 148.942582 -126.576601)
			(xy 148.930529 -126.660436) (xy 148.910561 -126.742745) (xy 148.882859 -126.822784) (xy 148.847675 -126.899827)
			(xy 148.805326 -126.973177) (xy 148.756197 -127.042169) (xy 148.700732 -127.106179) (xy 148.639434 -127.164627)
			(xy 148.572858 -127.216983) (xy 148.501606 -127.262773) (xy 148.426325 -127.301584) (xy 148.347695 -127.333063)
			(xy 148.266428 -127.356924) (xy 148.183262 -127.372953) (xy 148.098948 -127.381004) (xy 148.0566 -127.381508)
			(xy 148.010204 -127.380925) (xy 147.917916 -127.37128) (xy 147.827132 -127.352084) (xy 147.738839 -127.323546)
			(xy 147.696174 -127.305308) (xy 147.686232 -127.301502) (xy 147.664968 -127.301502) (xy 147.655026 -127.305308)
			(xy 147.612364 -127.323553) (xy 147.524071 -127.352097) (xy 147.433286 -127.37129) (xy 147.340996 -127.380923)
			(xy 147.2946 -127.381508) (xy 147.252252 -127.381004) (xy 147.167938 -127.372953) (xy 147.084772 -127.356924)
			(xy 147.003505 -127.333063) (xy 146.924875 -127.301584) (xy 146.849594 -127.262773) (xy 146.778342 -127.216983)
			(xy 146.711766 -127.164627) (xy 146.650468 -127.106179) (xy 146.595003 -127.042169) (xy 146.545874 -126.973177)
			(xy 146.503525 -126.899827) (xy 146.468341 -126.822784) (xy 146.440639 -126.742745) (xy 146.420671 -126.660436)
			(xy 146.408618 -126.576601) (xy 146.404588 -126.492) (xy 136.754613 -126.492) (xy 136.750582 -126.576601)
			(xy 136.738529 -126.660436) (xy 136.718561 -126.742745) (xy 136.690859 -126.822784) (xy 136.655675 -126.899827)
			(xy 136.613326 -126.973177) (xy 136.564197 -127.042169) (xy 136.508732 -127.106179) (xy 136.447434 -127.164627)
			(xy 136.380858 -127.216983) (xy 136.309606 -127.262773) (xy 136.234325 -127.301584) (xy 136.155695 -127.333063)
			(xy 136.074428 -127.356924) (xy 135.991262 -127.372953) (xy 135.906948 -127.381004) (xy 135.8646 -127.381508)
			(xy 135.818204 -127.380925) (xy 135.725916 -127.37128) (xy 135.635132 -127.352084) (xy 135.546839 -127.323546)
			(xy 135.504174 -127.305308) (xy 135.494232 -127.301502) (xy 135.472968 -127.301502) (xy 135.463026 -127.305308)
			(xy 135.420364 -127.323553) (xy 135.332071 -127.352097) (xy 135.241286 -127.37129) (xy 135.148996 -127.380923)
			(xy 135.1026 -127.381508) (xy 135.060252 -127.381004) (xy 134.975938 -127.372953) (xy 134.892772 -127.356924)
			(xy 134.811505 -127.333063) (xy 134.732875 -127.301584) (xy 134.657594 -127.262773) (xy 134.586342 -127.216983)
			(xy 134.519766 -127.164627) (xy 134.458468 -127.106179) (xy 134.403003 -127.042169) (xy 134.353874 -126.973177)
			(xy 134.311525 -126.899827) (xy 134.276341 -126.822784) (xy 134.248639 -126.742745) (xy 134.228671 -126.660436)
			(xy 134.216618 -126.576601) (xy 134.212588 -126.492) (xy 124.562613 -126.492) (xy 124.558582 -126.576601)
			(xy 124.546529 -126.660436) (xy 124.526561 -126.742745) (xy 124.498859 -126.822784) (xy 124.463675 -126.899827)
			(xy 124.421326 -126.973177) (xy 124.372197 -127.042169) (xy 124.316732 -127.106179) (xy 124.255434 -127.164627)
			(xy 124.188858 -127.216983) (xy 124.117606 -127.262773) (xy 124.042325 -127.301584) (xy 123.963695 -127.333063)
			(xy 123.882428 -127.356924) (xy 123.799262 -127.372953) (xy 123.714948 -127.381004) (xy 123.6726 -127.381508)
			(xy 123.626204 -127.380925) (xy 123.533916 -127.37128) (xy 123.443132 -127.352084) (xy 123.354839 -127.323546)
			(xy 123.312174 -127.305308) (xy 123.302232 -127.301502) (xy 123.280968 -127.301502) (xy 123.271026 -127.305308)
			(xy 123.228364 -127.323553) (xy 123.140071 -127.352097) (xy 123.049286 -127.37129) (xy 122.956996 -127.380923)
			(xy 122.9106 -127.381508) (xy 122.868252 -127.381004) (xy 122.783938 -127.372953) (xy 122.700772 -127.356924)
			(xy 122.619505 -127.333063) (xy 122.540875 -127.301584) (xy 122.465594 -127.262773) (xy 122.394342 -127.216983)
			(xy 122.327766 -127.164627) (xy 122.266468 -127.106179) (xy 122.211003 -127.042169) (xy 122.161874 -126.973177)
			(xy 122.119525 -126.899827) (xy 122.084341 -126.822784) (xy 122.056639 -126.742745) (xy 122.036671 -126.660436)
			(xy 122.024618 -126.576601) (xy 122.020588 -126.492) (xy 108.946413 -126.492) (xy 108.942383 -126.576599)
			(xy 108.930329 -126.660433) (xy 108.910362 -126.742741) (xy 108.882661 -126.822778) (xy 108.847478 -126.89982)
			(xy 108.805131 -126.973169) (xy 108.756004 -127.042161) (xy 108.700541 -127.10617) (xy 108.639245 -127.164617)
			(xy 108.572671 -127.216974) (xy 108.501421 -127.262765) (xy 108.426142 -127.301576) (xy 108.347514 -127.333056)
			(xy 108.26625 -127.356919) (xy 108.183085 -127.37295) (xy 108.098774 -127.381003) (xy 108.056426 -127.381508)
			(xy 108.010031 -127.380916) (xy 107.917743 -127.371274) (xy 107.826959 -127.35208) (xy 107.738665 -127.323545)
			(xy 107.696 -127.305308) (xy 107.686058 -127.301502) (xy 107.664794 -127.301502) (xy 107.654852 -127.305308)
			(xy 107.612186 -127.323544) (xy 107.523895 -127.35209) (xy 107.433111 -127.371286) (xy 107.340822 -127.380922)
			(xy 107.294426 -127.381508) (xy 107.252076 -127.381021) (xy 107.167759 -127.372972) (xy 107.084589 -127.356945)
			(xy 107.00332 -127.333084) (xy 106.924686 -127.301606) (xy 106.849401 -127.262796) (xy 106.778146 -127.217005)
			(xy 106.711566 -127.164648) (xy 106.650265 -127.106199) (xy 106.594798 -127.042187) (xy 106.545666 -126.973193)
			(xy 106.503315 -126.899841) (xy 106.468129 -126.822796) (xy 106.440426 -126.742754) (xy 106.420457 -126.660442)
			(xy 106.408402 -126.576604) (xy 106.404372 -126.492) (xy 96.754413 -126.492) (xy 96.750383 -126.576599)
			(xy 96.738329 -126.660433) (xy 96.718362 -126.742741) (xy 96.690661 -126.822778) (xy 96.655478 -126.89982)
			(xy 96.613131 -126.973169) (xy 96.564004 -127.042161) (xy 96.508541 -127.10617) (xy 96.447245 -127.164617)
			(xy 96.380671 -127.216974) (xy 96.309421 -127.262765) (xy 96.234142 -127.301576) (xy 96.155514 -127.333056)
			(xy 96.07425 -127.356919) (xy 95.991085 -127.37295) (xy 95.906774 -127.381003) (xy 95.864426 -127.381508)
			(xy 95.818031 -127.380916) (xy 95.725743 -127.371274) (xy 95.634959 -127.35208) (xy 95.546665 -127.323545)
			(xy 95.504 -127.305308) (xy 95.494058 -127.301502) (xy 95.472794 -127.301502) (xy 95.462852 -127.305308)
			(xy 95.420186 -127.323544) (xy 95.331895 -127.35209) (xy 95.241111 -127.371286) (xy 95.148822 -127.380922)
			(xy 95.102426 -127.381508) (xy 95.060076 -127.381021) (xy 94.975759 -127.372972) (xy 94.892589 -127.356945)
			(xy 94.81132 -127.333084) (xy 94.732686 -127.301606) (xy 94.657401 -127.262796) (xy 94.586146 -127.217005)
			(xy 94.519566 -127.164648) (xy 94.458265 -127.106199) (xy 94.402798 -127.042187) (xy 94.353666 -126.973193)
			(xy 94.311315 -126.899841) (xy 94.276129 -126.822796) (xy 94.248426 -126.742754) (xy 94.228457 -126.660442)
			(xy 94.216402 -126.576604) (xy 94.212372 -126.492) (xy 84.562413 -126.492) (xy 84.558383 -126.576599)
			(xy 84.546329 -126.660433) (xy 84.526362 -126.742741) (xy 84.498661 -126.822778) (xy 84.463478 -126.89982)
			(xy 84.421131 -126.973169) (xy 84.372004 -127.042161) (xy 84.316541 -127.10617) (xy 84.255245 -127.164617)
			(xy 84.188671 -127.216974) (xy 84.117421 -127.262765) (xy 84.042142 -127.301576) (xy 83.963514 -127.333056)
			(xy 83.88225 -127.356919) (xy 83.799085 -127.37295) (xy 83.714774 -127.381003) (xy 83.672426 -127.381508)
			(xy 83.626031 -127.380916) (xy 83.533743 -127.371274) (xy 83.442959 -127.35208) (xy 83.354665 -127.323545)
			(xy 83.312 -127.305308) (xy 83.302058 -127.301502) (xy 83.280794 -127.301502) (xy 83.270852 -127.305308)
			(xy 83.228186 -127.323544) (xy 83.139895 -127.35209) (xy 83.049111 -127.371286) (xy 82.956822 -127.380922)
			(xy 82.910426 -127.381508) (xy 82.868076 -127.381021) (xy 82.783759 -127.372972) (xy 82.700589 -127.356945)
			(xy 82.61932 -127.333084) (xy 82.540686 -127.301606) (xy 82.465401 -127.262796) (xy 82.394146 -127.217005)
			(xy 82.327566 -127.164648) (xy 82.266265 -127.106199) (xy 82.210798 -127.042187) (xy 82.161666 -126.973193)
			(xy 82.119315 -126.899841) (xy 82.084129 -126.822796) (xy 82.056426 -126.742754) (xy 82.036457 -126.660442)
			(xy 82.024402 -126.576604) (xy 82.020372 -126.492) (xy 68.946513 -126.492) (xy 68.942482 -126.576601)
			(xy 68.930429 -126.660435) (xy 68.910461 -126.742744) (xy 68.88276 -126.822783) (xy 68.847575 -126.899826)
			(xy 68.805227 -126.973175) (xy 68.756099 -127.042167) (xy 68.700634 -127.106177) (xy 68.639337 -127.164624)
			(xy 68.572761 -127.216981) (xy 68.50151 -127.262771) (xy 68.426229 -127.301582) (xy 68.347599 -127.333061)
			(xy 68.266333 -127.356923) (xy 68.183167 -127.372953) (xy 68.098854 -127.381004) (xy 68.056506 -127.381508)
			(xy 68.01011 -127.380923) (xy 67.917822 -127.371279) (xy 67.827038 -127.352083) (xy 67.738745 -127.323546)
			(xy 67.69608 -127.305308) (xy 67.686138 -127.301502) (xy 67.664874 -127.301502) (xy 67.654932 -127.305308)
			(xy 67.612269 -127.323551) (xy 67.523977 -127.352095) (xy 67.433192 -127.371289) (xy 67.340902 -127.380923)
			(xy 67.294506 -127.381508) (xy 67.252157 -127.38102) (xy 67.167841 -127.37297) (xy 67.084673 -127.356941)
			(xy 67.003405 -127.333079) (xy 66.924773 -127.3016) (xy 66.849489 -127.262789) (xy 66.778236 -127.216998)
			(xy 66.711658 -127.16464) (xy 66.650358 -127.106192) (xy 66.594892 -127.042181) (xy 66.545762 -126.973187)
			(xy 66.503412 -126.899836) (xy 66.468227 -126.822791) (xy 66.440525 -126.742751) (xy 66.420556 -126.66044)
			(xy 66.408502 -126.576603) (xy 66.404472 -126.492) (xy 56.754513 -126.492) (xy 56.750482 -126.576601)
			(xy 56.738429 -126.660435) (xy 56.718461 -126.742744) (xy 56.69076 -126.822783) (xy 56.655575 -126.899826)
			(xy 56.613227 -126.973175) (xy 56.564099 -127.042167) (xy 56.508634 -127.106177) (xy 56.447337 -127.164624)
			(xy 56.380761 -127.216981) (xy 56.30951 -127.262771) (xy 56.234229 -127.301582) (xy 56.155599 -127.333061)
			(xy 56.074333 -127.356923) (xy 55.991167 -127.372953) (xy 55.906854 -127.381004) (xy 55.864506 -127.381508)
			(xy 55.81811 -127.380923) (xy 55.725822 -127.371279) (xy 55.635038 -127.352083) (xy 55.546745 -127.323546)
			(xy 55.50408 -127.305308) (xy 55.494138 -127.301502) (xy 55.472874 -127.301502) (xy 55.462932 -127.305308)
			(xy 55.420269 -127.323551) (xy 55.331977 -127.352095) (xy 55.241192 -127.371289) (xy 55.148902 -127.380923)
			(xy 55.102506 -127.381508) (xy 55.060157 -127.38102) (xy 54.975841 -127.37297) (xy 54.892673 -127.356941)
			(xy 54.811405 -127.333079) (xy 54.732773 -127.3016) (xy 54.657489 -127.262789) (xy 54.586236 -127.216998)
			(xy 54.519658 -127.16464) (xy 54.458358 -127.106192) (xy 54.402892 -127.042181) (xy 54.353762 -126.973187)
			(xy 54.311412 -126.899836) (xy 54.276227 -126.822791) (xy 54.248525 -126.742751) (xy 54.228556 -126.66044)
			(xy 54.216502 -126.576603) (xy 54.212472 -126.492) (xy 44.562513 -126.492) (xy 44.558482 -126.576601)
			(xy 44.546429 -126.660435) (xy 44.526461 -126.742744) (xy 44.49876 -126.822783) (xy 44.463575 -126.899826)
			(xy 44.421227 -126.973175) (xy 44.372099 -127.042167) (xy 44.316634 -127.106177) (xy 44.255337 -127.164624)
			(xy 44.188761 -127.216981) (xy 44.11751 -127.262771) (xy 44.042229 -127.301582) (xy 43.963599 -127.333061)
			(xy 43.882333 -127.356923) (xy 43.799167 -127.372953) (xy 43.714854 -127.381004) (xy 43.672506 -127.381508)
			(xy 43.62611 -127.380923) (xy 43.533822 -127.371279) (xy 43.443038 -127.352083) (xy 43.354745 -127.323546)
			(xy 43.31208 -127.305308) (xy 43.302138 -127.301502) (xy 43.280874 -127.301502) (xy 43.270932 -127.305308)
			(xy 43.228269 -127.323551) (xy 43.139977 -127.352095) (xy 43.049192 -127.371289) (xy 42.956902 -127.380923)
			(xy 42.910506 -127.381508) (xy 42.868157 -127.38102) (xy 42.783841 -127.37297) (xy 42.700673 -127.356941)
			(xy 42.619405 -127.333079) (xy 42.540773 -127.3016) (xy 42.465489 -127.262789) (xy 42.394236 -127.216998)
			(xy 42.327658 -127.16464) (xy 42.266358 -127.106192) (xy 42.210892 -127.042181) (xy 42.161762 -126.973187)
			(xy 42.119412 -126.899836) (xy 42.084227 -126.822791) (xy 42.056525 -126.742751) (xy 42.036556 -126.66044)
			(xy 42.024502 -126.576603) (xy 42.020472 -126.492) (xy 21.154006 -126.492) (xy 21.120007 -126.493527)
			(xy 21.02993 -126.494032) (xy 20.93918 -126.493524) (xy 20.757865 -126.48532) (xy 20.577106 -126.468929)
			(xy 20.397272 -126.444384) (xy 20.218732 -126.411736) (xy 20.04185 -126.371051) (xy 19.866988 -126.322413)
			(xy 19.694503 -126.265921) (xy 19.524747 -126.20169) (xy 19.358069 -126.129852) (xy 19.194807 -126.050553)
			(xy 19.035297 -125.963956) (xy 18.879864 -125.870238) (xy 18.728826 -125.76959) (xy 18.582492 -125.662218)
			(xy 18.44116 -125.548342) (xy 18.30512 -125.428193) (xy 18.17465 -125.302019) (xy 18.050016 -125.170076)
			(xy 17.931473 -125.032635) (xy 17.819264 -124.889976) (xy 17.713618 -124.742391) (xy 17.61475 -124.590181)
			(xy 17.522864 -124.433659) (xy 17.438146 -124.273143) (xy 17.399 -124.191268) (xy 17.393666 -124.179584)
			(xy 17.3736 -124.164598) (xy 17.264888 -124.148088) (xy 17.241266 -124.156216) (xy 17.232376 -124.165868)
			(xy 17.184455 -124.217229) (xy 17.083658 -124.315088) (xy 16.977503 -124.407108) (xy 16.866328 -124.492995)
			(xy 16.750487 -124.572477) (xy 16.630349 -124.6453) (xy 16.506295 -124.711232) (xy 16.37872 -124.770064)
			(xy 16.248031 -124.821609) (xy 16.114643 -124.865702) (xy 15.978981 -124.902204) (xy 15.841477 -124.930997)
			(xy 15.702568 -124.951991) (xy 15.562696 -124.965118) (xy 15.422307 -124.970337) (xy 15.281846 -124.967632)
			(xy 15.141762 -124.95701) (xy 15.002499 -124.938506) (xy 14.864501 -124.912178) (xy 14.728208 -124.87811)
			(xy 14.594052 -124.836411) (xy 14.462462 -124.787214) (xy 14.333855 -124.730674) (xy 14.208641 -124.666973)
			(xy 14.087218 -124.596312) (xy 13.969973 -124.518916) (xy 13.857279 -124.435032) (xy 13.749494 -124.344927)
			(xy 13.646962 -124.248887) (xy 13.550008 -124.147219) (xy 13.458942 -124.040245) (xy 13.374053 -123.928306)
			(xy 13.295611 -123.811758) (xy 13.223867 -123.690972) (xy 13.159047 -123.566333) (xy 13.101359 -123.438237)
			(xy 13.050986 -123.307092) (xy 13.008088 -123.173315) (xy 12.972802 -123.037332) (xy 12.94524 -122.899576)
			(xy 12.92549 -122.760485) (xy 12.913615 -122.620501) (xy 12.909653 -122.48007) (xy 10.609072 -122.48007)
			(xy 10.609072 -128.230122) (xy 10.608605 -128.27415) (xy 10.60093 -128.361872) (xy 10.585639 -128.448591)
			(xy 10.562848 -128.533648) (xy 10.532731 -128.616394) (xy 10.495516 -128.696201) (xy 10.451487 -128.77246)
			(xy 10.40098 -128.844592) (xy 10.344377 -128.912047) (xy 10.282112 -128.974313) (xy 10.214656 -129.030914)
			(xy 10.142523 -129.081422) (xy 10.066264 -129.12545) (xy 9.986457 -129.162664) (xy 9.90371 -129.192781)
			(xy 9.818654 -129.215571) (xy 9.731934 -129.230861) (xy 9.644212 -129.238536) (xy 9.600184 -129.23901)
			(xy 2.999994 -129.23901) (xy 2.930118 -129.2395) (xy 2.790585 -129.247336) (xy 2.651711 -129.262984)
			(xy 2.513933 -129.286393) (xy 2.377684 -129.317491) (xy 2.243393 -129.35618) (xy 2.111483 -129.402337)
			(xy 1.982368 -129.455818) (xy 1.856456 -129.516454) (xy 1.734141 -129.584055) (xy 1.615809 -129.658408)
			(xy 1.501832 -129.739279) (xy 1.392569 -129.826414) (xy 1.288363 -129.919537) (xy 1.189543 -130.018357)
			(xy 1.09642 -130.122563) (xy 1.009285 -130.231826) (xy 0.928414 -130.345803) (xy 0.854061 -130.464135)
			(xy 0.78646 -130.58645) (xy 0.725824 -130.712362) (xy 0.672343 -130.841477) (xy 0.626186 -130.973387)
			(xy 0.587497 -131.107678) (xy 0.556399 -131.243927) (xy 0.53299 -131.381705) (xy 0.517342 -131.520579)
			(xy 0.514454 -131.572) (xy 42.020472 -131.572) (xy 42.024502 -131.487397) (xy 42.036556 -131.40356)
			(xy 42.056525 -131.321249) (xy 42.084227 -131.241209) (xy 42.119412 -131.164164) (xy 42.161762 -131.090813)
			(xy 42.210892 -131.021819) (xy 42.266358 -130.957808) (xy 42.327658 -130.89936) (xy 42.394236 -130.847002)
			(xy 42.465489 -130.801211) (xy 42.540773 -130.7624) (xy 42.619405 -130.730921) (xy 42.700673 -130.707059)
			(xy 42.783841 -130.69103) (xy 42.868157 -130.68298) (xy 42.910506 -130.682492) (xy 42.956902 -130.683073)
			(xy 43.04919 -130.692718) (xy 43.139974 -130.711915) (xy 43.228267 -130.740454) (xy 43.270932 -130.758692)
			(xy 43.280874 -130.762498) (xy 43.302138 -130.762498) (xy 43.31208 -130.758692) (xy 43.354741 -130.740445)
			(xy 43.443034 -130.711902) (xy 43.533819 -130.692709) (xy 43.62611 -130.683077) (xy 43.672506 -130.682492)
			(xy 43.714854 -130.682996) (xy 43.799167 -130.691047) (xy 43.882333 -130.707077) (xy 43.963599 -130.730939)
			(xy 44.042229 -130.762418) (xy 44.11751 -130.801229) (xy 44.188761 -130.847019) (xy 44.255337 -130.899376)
			(xy 44.316634 -130.957823) (xy 44.372099 -131.021833) (xy 44.421227 -131.090825) (xy 44.463575 -131.164174)
			(xy 44.49876 -131.241217) (xy 44.526461 -131.321256) (xy 44.546429 -131.403565) (xy 44.558482 -131.487399)
			(xy 44.562513 -131.572) (xy 54.212472 -131.572) (xy 54.216502 -131.487397) (xy 54.228556 -131.40356)
			(xy 54.248525 -131.321249) (xy 54.276227 -131.241209) (xy 54.311412 -131.164164) (xy 54.353762 -131.090813)
			(xy 54.402892 -131.021819) (xy 54.458358 -130.957808) (xy 54.519658 -130.89936) (xy 54.586236 -130.847002)
			(xy 54.657489 -130.801211) (xy 54.732773 -130.7624) (xy 54.811405 -130.730921) (xy 54.892673 -130.707059)
			(xy 54.975841 -130.69103) (xy 55.060157 -130.68298) (xy 55.102506 -130.682492) (xy 55.148902 -130.683073)
			(xy 55.24119 -130.692718) (xy 55.331974 -130.711915) (xy 55.420267 -130.740454) (xy 55.462932 -130.758692)
			(xy 55.472874 -130.762498) (xy 55.494138 -130.762498) (xy 55.50408 -130.758692) (xy 55.546741 -130.740445)
			(xy 55.635034 -130.711902) (xy 55.725819 -130.692709) (xy 55.81811 -130.683077) (xy 55.864506 -130.682492)
			(xy 55.906854 -130.682996) (xy 55.991167 -130.691047) (xy 56.074333 -130.707077) (xy 56.155599 -130.730939)
			(xy 56.234229 -130.762418) (xy 56.30951 -130.801229) (xy 56.380761 -130.847019) (xy 56.447337 -130.899376)
			(xy 56.508634 -130.957823) (xy 56.564099 -131.021833) (xy 56.613227 -131.090825) (xy 56.655575 -131.164174)
			(xy 56.69076 -131.241217) (xy 56.718461 -131.321256) (xy 56.738429 -131.403565) (xy 56.750482 -131.487399)
			(xy 56.754513 -131.572) (xy 66.404472 -131.572) (xy 66.408502 -131.487397) (xy 66.420556 -131.40356)
			(xy 66.440525 -131.321249) (xy 66.468227 -131.241209) (xy 66.503412 -131.164164) (xy 66.545762 -131.090813)
			(xy 66.594892 -131.021819) (xy 66.650358 -130.957808) (xy 66.711658 -130.89936) (xy 66.778236 -130.847002)
			(xy 66.849489 -130.801211) (xy 66.924773 -130.7624) (xy 67.003405 -130.730921) (xy 67.084673 -130.707059)
			(xy 67.167841 -130.69103) (xy 67.252157 -130.68298) (xy 67.294506 -130.682492) (xy 67.340902 -130.683073)
			(xy 67.43319 -130.692718) (xy 67.523974 -130.711915) (xy 67.612267 -130.740454) (xy 67.654932 -130.758692)
			(xy 67.664874 -130.762498) (xy 67.686138 -130.762498) (xy 67.69608 -130.758692) (xy 67.738741 -130.740445)
			(xy 67.827034 -130.711902) (xy 67.917819 -130.692709) (xy 68.01011 -130.683077) (xy 68.056506 -130.682492)
			(xy 68.098854 -130.682996) (xy 68.183167 -130.691047) (xy 68.266333 -130.707077) (xy 68.347599 -130.730939)
			(xy 68.426229 -130.762418) (xy 68.50151 -130.801229) (xy 68.572761 -130.847019) (xy 68.639337 -130.899376)
			(xy 68.700634 -130.957823) (xy 68.756099 -131.021833) (xy 68.805227 -131.090825) (xy 68.847575 -131.164174)
			(xy 68.88276 -131.241217) (xy 68.910461 -131.321256) (xy 68.930429 -131.403565) (xy 68.942482 -131.487399)
			(xy 68.946513 -131.572) (xy 82.020372 -131.572) (xy 82.024402 -131.487396) (xy 82.036457 -131.403558)
			(xy 82.056426 -131.321246) (xy 82.084129 -131.241204) (xy 82.119315 -131.164159) (xy 82.161666 -131.090807)
			(xy 82.210798 -131.021813) (xy 82.266265 -130.957801) (xy 82.327566 -130.899352) (xy 82.394146 -130.846995)
			(xy 82.465401 -130.801204) (xy 82.540686 -130.762394) (xy 82.61932 -130.730916) (xy 82.700589 -130.707055)
			(xy 82.783759 -130.691028) (xy 82.868076 -130.682979) (xy 82.910426 -130.682492) (xy 82.956821 -130.683101)
			(xy 83.049109 -130.692738) (xy 83.139892 -130.711927) (xy 83.228187 -130.740458) (xy 83.270852 -130.758692)
			(xy 83.280794 -130.762498) (xy 83.302058 -130.762498) (xy 83.312 -130.758692) (xy 83.354659 -130.740439)
			(xy 83.442952 -130.711897) (xy 83.533738 -130.692706) (xy 83.62603 -130.683076) (xy 83.672426 -130.682492)
			(xy 83.714774 -130.682997) (xy 83.799085 -130.69105) (xy 83.88225 -130.707081) (xy 83.963514 -130.730944)
			(xy 84.042142 -130.762424) (xy 84.117421 -130.801235) (xy 84.188671 -130.847026) (xy 84.255245 -130.899383)
			(xy 84.316541 -130.95783) (xy 84.372004 -131.021839) (xy 84.421131 -131.090831) (xy 84.463478 -131.16418)
			(xy 84.498661 -131.241222) (xy 84.526362 -131.321259) (xy 84.546329 -131.403567) (xy 84.558383 -131.487401)
			(xy 84.562413 -131.572) (xy 94.212372 -131.572) (xy 94.216402 -131.487396) (xy 94.228457 -131.403558)
			(xy 94.248426 -131.321246) (xy 94.276129 -131.241204) (xy 94.311315 -131.164159) (xy 94.353666 -131.090807)
			(xy 94.402798 -131.021813) (xy 94.458265 -130.957801) (xy 94.519566 -130.899352) (xy 94.586146 -130.846995)
			(xy 94.657401 -130.801204) (xy 94.732686 -130.762394) (xy 94.81132 -130.730916) (xy 94.892589 -130.707055)
			(xy 94.975759 -130.691028) (xy 95.060076 -130.682979) (xy 95.102426 -130.682492) (xy 95.148821 -130.683101)
			(xy 95.241109 -130.692738) (xy 95.331892 -130.711927) (xy 95.420187 -130.740458) (xy 95.462852 -130.758692)
			(xy 95.472794 -130.762498) (xy 95.494058 -130.762498) (xy 95.504 -130.758692) (xy 95.546659 -130.740439)
			(xy 95.634952 -130.711897) (xy 95.725738 -130.692706) (xy 95.81803 -130.683076) (xy 95.864426 -130.682492)
			(xy 95.906774 -130.682997) (xy 95.991085 -130.69105) (xy 96.07425 -130.707081) (xy 96.155514 -130.730944)
			(xy 96.234142 -130.762424) (xy 96.309421 -130.801235) (xy 96.380671 -130.847026) (xy 96.447245 -130.899383)
			(xy 96.508541 -130.95783) (xy 96.564004 -131.021839) (xy 96.613131 -131.090831) (xy 96.655478 -131.16418)
			(xy 96.690661 -131.241222) (xy 96.718362 -131.321259) (xy 96.738329 -131.403567) (xy 96.750383 -131.487401)
			(xy 96.754413 -131.572) (xy 106.404372 -131.572) (xy 106.408402 -131.487396) (xy 106.420457 -131.403558)
			(xy 106.440426 -131.321246) (xy 106.468129 -131.241204) (xy 106.503315 -131.164159) (xy 106.545666 -131.090807)
			(xy 106.594798 -131.021813) (xy 106.650265 -130.957801) (xy 106.711566 -130.899352) (xy 106.778146 -130.846995)
			(xy 106.849401 -130.801204) (xy 106.924686 -130.762394) (xy 107.00332 -130.730916) (xy 107.084589 -130.707055)
			(xy 107.167759 -130.691028) (xy 107.252076 -130.682979) (xy 107.294426 -130.682492) (xy 107.340821 -130.683101)
			(xy 107.433109 -130.692738) (xy 107.523892 -130.711927) (xy 107.612187 -130.740458) (xy 107.654852 -130.758692)
			(xy 107.664794 -130.762498) (xy 107.686058 -130.762498) (xy 107.696 -130.758692) (xy 107.738659 -130.740439)
			(xy 107.826952 -130.711897) (xy 107.917738 -130.692706) (xy 108.01003 -130.683076) (xy 108.056426 -130.682492)
			(xy 108.098774 -130.682997) (xy 108.183085 -130.69105) (xy 108.26625 -130.707081) (xy 108.347514 -130.730944)
			(xy 108.426142 -130.762424) (xy 108.501421 -130.801235) (xy 108.572671 -130.847026) (xy 108.639245 -130.899383)
			(xy 108.700541 -130.95783) (xy 108.756004 -131.021839) (xy 108.805131 -131.090831) (xy 108.847478 -131.16418)
			(xy 108.882661 -131.241222) (xy 108.910362 -131.321259) (xy 108.930329 -131.403567) (xy 108.942383 -131.487401)
			(xy 108.946413 -131.572) (xy 122.020588 -131.572) (xy 122.024618 -131.487399) (xy 122.036671 -131.403564)
			(xy 122.056639 -131.321255) (xy 122.084341 -131.241216) (xy 122.119525 -131.164173) (xy 122.161874 -131.090823)
			(xy 122.211003 -131.021831) (xy 122.266468 -130.957821) (xy 122.327766 -130.899373) (xy 122.394342 -130.847017)
			(xy 122.465594 -130.801227) (xy 122.540875 -130.762416) (xy 122.619505 -130.730937) (xy 122.700772 -130.707076)
			(xy 122.783938 -130.691047) (xy 122.868252 -130.682996) (xy 122.9106 -130.682492) (xy 122.956996 -130.683075)
			(xy 123.049284 -130.69272) (xy 123.140068 -130.711916) (xy 123.228361 -130.740454) (xy 123.271026 -130.758692)
			(xy 123.280968 -130.762498) (xy 123.302232 -130.762498) (xy 123.312174 -130.758692) (xy 123.354836 -130.740447)
			(xy 123.443129 -130.711903) (xy 123.533914 -130.69271) (xy 123.626204 -130.683077) (xy 123.6726 -130.682492)
			(xy 123.714948 -130.682996) (xy 123.799262 -130.691047) (xy 123.882428 -130.707076) (xy 123.963695 -130.730937)
			(xy 124.042325 -130.762416) (xy 124.117606 -130.801227) (xy 124.188858 -130.847017) (xy 124.255434 -130.899373)
			(xy 124.316732 -130.957821) (xy 124.372197 -131.021831) (xy 124.421326 -131.090823) (xy 124.463675 -131.164173)
			(xy 124.498859 -131.241216) (xy 124.526561 -131.321255) (xy 124.546529 -131.403564) (xy 124.558582 -131.487399)
			(xy 124.562613 -131.572) (xy 134.212588 -131.572) (xy 134.216618 -131.487399) (xy 134.228671 -131.403564)
			(xy 134.248639 -131.321255) (xy 134.276341 -131.241216) (xy 134.311525 -131.164173) (xy 134.353874 -131.090823)
			(xy 134.403003 -131.021831) (xy 134.458468 -130.957821) (xy 134.519766 -130.899373) (xy 134.586342 -130.847017)
			(xy 134.657594 -130.801227) (xy 134.732875 -130.762416) (xy 134.811505 -130.730937) (xy 134.892772 -130.707076)
			(xy 134.975938 -130.691047) (xy 135.060252 -130.682996) (xy 135.1026 -130.682492) (xy 135.148996 -130.683075)
			(xy 135.241284 -130.69272) (xy 135.332068 -130.711916) (xy 135.420361 -130.740454) (xy 135.463026 -130.758692)
			(xy 135.472968 -130.762498) (xy 135.494232 -130.762498) (xy 135.504174 -130.758692) (xy 135.546836 -130.740447)
			(xy 135.635129 -130.711903) (xy 135.725914 -130.69271) (xy 135.818204 -130.683077) (xy 135.8646 -130.682492)
			(xy 135.906948 -130.682996) (xy 135.991262 -130.691047) (xy 136.074428 -130.707076) (xy 136.155695 -130.730937)
			(xy 136.234325 -130.762416) (xy 136.309606 -130.801227) (xy 136.380858 -130.847017) (xy 136.447434 -130.899373)
			(xy 136.508732 -130.957821) (xy 136.564197 -131.021831) (xy 136.613326 -131.090823) (xy 136.655675 -131.164173)
			(xy 136.690859 -131.241216) (xy 136.718561 -131.321255) (xy 136.738529 -131.403564) (xy 136.750582 -131.487399)
			(xy 136.754613 -131.572) (xy 146.404588 -131.572) (xy 146.408618 -131.487399) (xy 146.420671 -131.403564)
			(xy 146.440639 -131.321255) (xy 146.468341 -131.241216) (xy 146.503525 -131.164173) (xy 146.545874 -131.090823)
			(xy 146.595003 -131.021831) (xy 146.650468 -130.957821) (xy 146.711766 -130.899373) (xy 146.778342 -130.847017)
			(xy 146.849594 -130.801227) (xy 146.924875 -130.762416) (xy 147.003505 -130.730937) (xy 147.084772 -130.707076)
			(xy 147.167938 -130.691047) (xy 147.252252 -130.682996) (xy 147.2946 -130.682492) (xy 147.340996 -130.683075)
			(xy 147.433284 -130.69272) (xy 147.524068 -130.711916) (xy 147.612361 -130.740454) (xy 147.655026 -130.758692)
			(xy 147.664968 -130.762498) (xy 147.686232 -130.762498) (xy 147.696174 -130.758692) (xy 147.738836 -130.740447)
			(xy 147.827129 -130.711903) (xy 147.917914 -130.69271) (xy 148.010204 -130.683077) (xy 148.0566 -130.682492)
			(xy 148.098948 -130.682996) (xy 148.183262 -130.691047) (xy 148.266428 -130.707076) (xy 148.347695 -130.730937)
			(xy 148.426325 -130.762416) (xy 148.501606 -130.801227) (xy 148.572858 -130.847017) (xy 148.639434 -130.899373)
			(xy 148.700732 -130.957821) (xy 148.756197 -131.021831) (xy 148.805326 -131.090823) (xy 148.847675 -131.164173)
			(xy 148.882859 -131.241216) (xy 148.910561 -131.321255) (xy 148.930529 -131.403564) (xy 148.942582 -131.487399)
			(xy 148.946613 -131.572) (xy 162.020787 -131.572) (xy 162.024817 -131.487401) (xy 162.036871 -131.403567)
			(xy 162.056838 -131.321259) (xy 162.084539 -131.241222) (xy 162.119722 -131.16418) (xy 162.162069 -131.090831)
			(xy 162.211196 -131.021839) (xy 162.266659 -130.95783) (xy 162.327955 -130.899383) (xy 162.394529 -130.847026)
			(xy 162.465779 -130.801235) (xy 162.541058 -130.762424) (xy 162.619686 -130.730944) (xy 162.70095 -130.707081)
			(xy 162.784115 -130.69105) (xy 162.868426 -130.682997) (xy 162.910774 -130.682492) (xy 162.957169 -130.683084)
			(xy 163.049457 -130.692726) (xy 163.140241 -130.71192) (xy 163.228535 -130.740455) (xy 163.2712 -130.758692)
			(xy 163.281142 -130.762498) (xy 163.302406 -130.762498) (xy 163.312348 -130.758692) (xy 163.355014 -130.740456)
			(xy 163.443305 -130.71191) (xy 163.534089 -130.692714) (xy 163.626378 -130.683078) (xy 163.672774 -130.682492)
			(xy 163.715124 -130.682979) (xy 163.799441 -130.691028) (xy 163.882611 -130.707055) (xy 163.96388 -130.730916)
			(xy 164.042514 -130.762394) (xy 164.117799 -130.801204) (xy 164.189054 -130.846995) (xy 164.255634 -130.899352)
			(xy 164.316935 -130.957801) (xy 164.372402 -131.021813) (xy 164.421534 -131.090807) (xy 164.463885 -131.164159)
			(xy 164.499071 -131.241204) (xy 164.526774 -131.321246) (xy 164.546743 -131.403558) (xy 164.558798 -131.487396)
			(xy 164.562828 -131.572) (xy 174.212787 -131.572) (xy 174.216817 -131.487401) (xy 174.228871 -131.403567)
			(xy 174.248838 -131.321259) (xy 174.276539 -131.241222) (xy 174.311722 -131.16418) (xy 174.354069 -131.090831)
			(xy 174.403196 -131.021839) (xy 174.458659 -130.95783) (xy 174.519955 -130.899383) (xy 174.586529 -130.847026)
			(xy 174.657779 -130.801235) (xy 174.733058 -130.762424) (xy 174.811686 -130.730944) (xy 174.89295 -130.707081)
			(xy 174.976115 -130.69105) (xy 175.060426 -130.682997) (xy 175.102774 -130.682492) (xy 175.149169 -130.683084)
			(xy 175.241457 -130.692726) (xy 175.332241 -130.71192) (xy 175.420535 -130.740455) (xy 175.4632 -130.758692)
			(xy 175.473142 -130.762498) (xy 175.494406 -130.762498) (xy 175.504348 -130.758692) (xy 175.547014 -130.740456)
			(xy 175.635305 -130.71191) (xy 175.726089 -130.692714) (xy 175.818378 -130.683078) (xy 175.864774 -130.682492)
			(xy 175.907124 -130.682979) (xy 175.991441 -130.691028) (xy 176.074611 -130.707055) (xy 176.15588 -130.730916)
			(xy 176.234514 -130.762394) (xy 176.309799 -130.801204) (xy 176.381054 -130.846995) (xy 176.447634 -130.899352)
			(xy 176.508935 -130.957801) (xy 176.564402 -131.021813) (xy 176.613534 -131.090807) (xy 176.655885 -131.164159)
			(xy 176.691071 -131.241204) (xy 176.718774 -131.321246) (xy 176.738743 -131.403558) (xy 176.750798 -131.487396)
			(xy 176.754828 -131.572) (xy 186.404787 -131.572) (xy 186.408817 -131.487401) (xy 186.420871 -131.403567)
			(xy 186.440838 -131.321259) (xy 186.468539 -131.241222) (xy 186.503722 -131.16418) (xy 186.546069 -131.090831)
			(xy 186.595196 -131.021839) (xy 186.650659 -130.95783) (xy 186.711955 -130.899383) (xy 186.778529 -130.847026)
			(xy 186.849779 -130.801235) (xy 186.925058 -130.762424) (xy 187.003686 -130.730944) (xy 187.08495 -130.707081)
			(xy 187.168115 -130.69105) (xy 187.252426 -130.682997) (xy 187.294774 -130.682492) (xy 187.341169 -130.683084)
			(xy 187.433457 -130.692726) (xy 187.524241 -130.71192) (xy 187.612535 -130.740455) (xy 187.6552 -130.758692)
			(xy 187.665142 -130.762498) (xy 187.686406 -130.762498) (xy 187.696348 -130.758692) (xy 187.739014 -130.740456)
			(xy 187.827305 -130.71191) (xy 187.918089 -130.692714) (xy 188.010378 -130.683078) (xy 188.056774 -130.682492)
			(xy 188.099124 -130.682979) (xy 188.183441 -130.691028) (xy 188.266611 -130.707055) (xy 188.34788 -130.730916)
			(xy 188.426514 -130.762394) (xy 188.501799 -130.801204) (xy 188.573054 -130.846995) (xy 188.639634 -130.899352)
			(xy 188.700935 -130.957801) (xy 188.756402 -131.021813) (xy 188.805534 -131.090807) (xy 188.847885 -131.164159)
			(xy 188.883071 -131.241204) (xy 188.910774 -131.321246) (xy 188.930743 -131.403558) (xy 188.942798 -131.487396)
			(xy 188.946828 -131.572) (xy 188.942798 -131.656604) (xy 188.930743 -131.740442) (xy 188.910774 -131.822754)
			(xy 188.883071 -131.902796) (xy 188.847885 -131.979841) (xy 188.805534 -132.053193) (xy 188.756402 -132.122187)
			(xy 188.700935 -132.186199) (xy 188.639634 -132.244648) (xy 188.573054 -132.297005) (xy 188.501799 -132.342796)
			(xy 188.426514 -132.381606) (xy 188.34788 -132.413084) (xy 188.266611 -132.436945) (xy 188.183441 -132.452972)
			(xy 188.099124 -132.461021) (xy 188.056774 -132.461508) (xy 188.010379 -132.460899) (xy 187.918091 -132.451262)
			(xy 187.827308 -132.432073) (xy 187.739013 -132.403542) (xy 187.696348 -132.385308) (xy 187.686406 -132.381502)
			(xy 187.665142 -132.381502) (xy 187.6552 -132.385308) (xy 187.612541 -132.403561) (xy 187.524248 -132.432103)
			(xy 187.433462 -132.451294) (xy 187.34117 -132.460924) (xy 187.294774 -132.461508) (xy 187.252426 -132.461003)
			(xy 187.168115 -132.45295) (xy 187.08495 -132.436919) (xy 187.003686 -132.413056) (xy 186.925058 -132.381576)
			(xy 186.849779 -132.342765) (xy 186.778529 -132.296974) (xy 186.711955 -132.244617) (xy 186.650659 -132.18617)
			(xy 186.595196 -132.122161) (xy 186.546069 -132.053169) (xy 186.503722 -131.97982) (xy 186.468539 -131.902778)
			(xy 186.440838 -131.822741) (xy 186.420871 -131.740433) (xy 186.408817 -131.656599) (xy 186.404787 -131.572)
			(xy 176.754828 -131.572) (xy 176.750798 -131.656604) (xy 176.738743 -131.740442) (xy 176.718774 -131.822754)
			(xy 176.691071 -131.902796) (xy 176.655885 -131.979841) (xy 176.613534 -132.053193) (xy 176.564402 -132.122187)
			(xy 176.508935 -132.186199) (xy 176.447634 -132.244648) (xy 176.381054 -132.297005) (xy 176.309799 -132.342796)
			(xy 176.234514 -132.381606) (xy 176.15588 -132.413084) (xy 176.074611 -132.436945) (xy 175.991441 -132.452972)
			(xy 175.907124 -132.461021) (xy 175.864774 -132.461508) (xy 175.818379 -132.460899) (xy 175.726091 -132.451262)
			(xy 175.635308 -132.432073) (xy 175.547013 -132.403542) (xy 175.504348 -132.385308) (xy 175.494406 -132.381502)
			(xy 175.473142 -132.381502) (xy 175.4632 -132.385308) (xy 175.420541 -132.403561) (xy 175.332248 -132.432103)
			(xy 175.241462 -132.451294) (xy 175.14917 -132.460924) (xy 175.102774 -132.461508) (xy 175.060426 -132.461003)
			(xy 174.976115 -132.45295) (xy 174.89295 -132.436919) (xy 174.811686 -132.413056) (xy 174.733058 -132.381576)
			(xy 174.657779 -132.342765) (xy 174.586529 -132.296974) (xy 174.519955 -132.244617) (xy 174.458659 -132.18617)
			(xy 174.403196 -132.122161) (xy 174.354069 -132.053169) (xy 174.311722 -131.97982) (xy 174.276539 -131.902778)
			(xy 174.248838 -131.822741) (xy 174.228871 -131.740433) (xy 174.216817 -131.656599) (xy 174.212787 -131.572)
			(xy 164.562828 -131.572) (xy 164.558798 -131.656604) (xy 164.546743 -131.740442) (xy 164.526774 -131.822754)
			(xy 164.499071 -131.902796) (xy 164.463885 -131.979841) (xy 164.421534 -132.053193) (xy 164.372402 -132.122187)
			(xy 164.316935 -132.186199) (xy 164.255634 -132.244648) (xy 164.189054 -132.297005) (xy 164.117799 -132.342796)
			(xy 164.042514 -132.381606) (xy 163.96388 -132.413084) (xy 163.882611 -132.436945) (xy 163.799441 -132.452972)
			(xy 163.715124 -132.461021) (xy 163.672774 -132.461508) (xy 163.626379 -132.460899) (xy 163.534091 -132.451262)
			(xy 163.443308 -132.432073) (xy 163.355013 -132.403542) (xy 163.312348 -132.385308) (xy 163.302406 -132.381502)
			(xy 163.281142 -132.381502) (xy 163.2712 -132.385308) (xy 163.228541 -132.403561) (xy 163.140248 -132.432103)
			(xy 163.049462 -132.451294) (xy 162.95717 -132.460924) (xy 162.910774 -132.461508) (xy 162.868426 -132.461003)
			(xy 162.784115 -132.45295) (xy 162.70095 -132.436919) (xy 162.619686 -132.413056) (xy 162.541058 -132.381576)
			(xy 162.465779 -132.342765) (xy 162.394529 -132.296974) (xy 162.327955 -132.244617) (xy 162.266659 -132.18617)
			(xy 162.211196 -132.122161) (xy 162.162069 -132.053169) (xy 162.119722 -131.97982) (xy 162.084539 -131.902778)
			(xy 162.056838 -131.822741) (xy 162.036871 -131.740433) (xy 162.024817 -131.656599) (xy 162.020787 -131.572)
			(xy 148.946613 -131.572) (xy 148.942582 -131.656601) (xy 148.930529 -131.740436) (xy 148.910561 -131.822745)
			(xy 148.882859 -131.902784) (xy 148.847675 -131.979827) (xy 148.805326 -132.053177) (xy 148.756197 -132.122169)
			(xy 148.700732 -132.186179) (xy 148.639434 -132.244627) (xy 148.572858 -132.296983) (xy 148.501606 -132.342773)
			(xy 148.426325 -132.381584) (xy 148.347695 -132.413063) (xy 148.266428 -132.436924) (xy 148.183262 -132.452953)
			(xy 148.098948 -132.461004) (xy 148.0566 -132.461508) (xy 148.010204 -132.460925) (xy 147.917916 -132.45128)
			(xy 147.827132 -132.432084) (xy 147.738839 -132.403546) (xy 147.696174 -132.385308) (xy 147.686232 -132.381502)
			(xy 147.664968 -132.381502) (xy 147.655026 -132.385308) (xy 147.612364 -132.403553) (xy 147.524071 -132.432097)
			(xy 147.433286 -132.45129) (xy 147.340996 -132.460923) (xy 147.2946 -132.461508) (xy 147.252252 -132.461004)
			(xy 147.167938 -132.452953) (xy 147.084772 -132.436924) (xy 147.003505 -132.413063) (xy 146.924875 -132.381584)
			(xy 146.849594 -132.342773) (xy 146.778342 -132.296983) (xy 146.711766 -132.244627) (xy 146.650468 -132.186179)
			(xy 146.595003 -132.122169) (xy 146.545874 -132.053177) (xy 146.503525 -131.979827) (xy 146.468341 -131.902784)
			(xy 146.440639 -131.822745) (xy 146.420671 -131.740436) (xy 146.408618 -131.656601) (xy 146.404588 -131.572)
			(xy 136.754613 -131.572) (xy 136.750582 -131.656601) (xy 136.738529 -131.740436) (xy 136.718561 -131.822745)
			(xy 136.690859 -131.902784) (xy 136.655675 -131.979827) (xy 136.613326 -132.053177) (xy 136.564197 -132.122169)
			(xy 136.508732 -132.186179) (xy 136.447434 -132.244627) (xy 136.380858 -132.296983) (xy 136.309606 -132.342773)
			(xy 136.234325 -132.381584) (xy 136.155695 -132.413063) (xy 136.074428 -132.436924) (xy 135.991262 -132.452953)
			(xy 135.906948 -132.461004) (xy 135.8646 -132.461508) (xy 135.818204 -132.460925) (xy 135.725916 -132.45128)
			(xy 135.635132 -132.432084) (xy 135.546839 -132.403546) (xy 135.504174 -132.385308) (xy 135.494232 -132.381502)
			(xy 135.472968 -132.381502) (xy 135.463026 -132.385308) (xy 135.420364 -132.403553) (xy 135.332071 -132.432097)
			(xy 135.241286 -132.45129) (xy 135.148996 -132.460923) (xy 135.1026 -132.461508) (xy 135.060252 -132.461004)
			(xy 134.975938 -132.452953) (xy 134.892772 -132.436924) (xy 134.811505 -132.413063) (xy 134.732875 -132.381584)
			(xy 134.657594 -132.342773) (xy 134.586342 -132.296983) (xy 134.519766 -132.244627) (xy 134.458468 -132.186179)
			(xy 134.403003 -132.122169) (xy 134.353874 -132.053177) (xy 134.311525 -131.979827) (xy 134.276341 -131.902784)
			(xy 134.248639 -131.822745) (xy 134.228671 -131.740436) (xy 134.216618 -131.656601) (xy 134.212588 -131.572)
			(xy 124.562613 -131.572) (xy 124.558582 -131.656601) (xy 124.546529 -131.740436) (xy 124.526561 -131.822745)
			(xy 124.498859 -131.902784) (xy 124.463675 -131.979827) (xy 124.421326 -132.053177) (xy 124.372197 -132.122169)
			(xy 124.316732 -132.186179) (xy 124.255434 -132.244627) (xy 124.188858 -132.296983) (xy 124.117606 -132.342773)
			(xy 124.042325 -132.381584) (xy 123.963695 -132.413063) (xy 123.882428 -132.436924) (xy 123.799262 -132.452953)
			(xy 123.714948 -132.461004) (xy 123.6726 -132.461508) (xy 123.626204 -132.460925) (xy 123.533916 -132.45128)
			(xy 123.443132 -132.432084) (xy 123.354839 -132.403546) (xy 123.312174 -132.385308) (xy 123.302232 -132.381502)
			(xy 123.280968 -132.381502) (xy 123.271026 -132.385308) (xy 123.228364 -132.403553) (xy 123.140071 -132.432097)
			(xy 123.049286 -132.45129) (xy 122.956996 -132.460923) (xy 122.9106 -132.461508) (xy 122.868252 -132.461004)
			(xy 122.783938 -132.452953) (xy 122.700772 -132.436924) (xy 122.619505 -132.413063) (xy 122.540875 -132.381584)
			(xy 122.465594 -132.342773) (xy 122.394342 -132.296983) (xy 122.327766 -132.244627) (xy 122.266468 -132.186179)
			(xy 122.211003 -132.122169) (xy 122.161874 -132.053177) (xy 122.119525 -131.979827) (xy 122.084341 -131.902784)
			(xy 122.056639 -131.822745) (xy 122.036671 -131.740436) (xy 122.024618 -131.656601) (xy 122.020588 -131.572)
			(xy 108.946413 -131.572) (xy 108.942383 -131.656599) (xy 108.930329 -131.740433) (xy 108.910362 -131.822741)
			(xy 108.882661 -131.902778) (xy 108.847478 -131.97982) (xy 108.805131 -132.053169) (xy 108.756004 -132.122161)
			(xy 108.700541 -132.18617) (xy 108.639245 -132.244617) (xy 108.572671 -132.296974) (xy 108.501421 -132.342765)
			(xy 108.426142 -132.381576) (xy 108.347514 -132.413056) (xy 108.26625 -132.436919) (xy 108.183085 -132.45295)
			(xy 108.098774 -132.461003) (xy 108.056426 -132.461508) (xy 108.010031 -132.460916) (xy 107.917743 -132.451274)
			(xy 107.826959 -132.43208) (xy 107.738665 -132.403545) (xy 107.696 -132.385308) (xy 107.686058 -132.381502)
			(xy 107.664794 -132.381502) (xy 107.654852 -132.385308) (xy 107.612186 -132.403544) (xy 107.523895 -132.43209)
			(xy 107.433111 -132.451286) (xy 107.340822 -132.460922) (xy 107.294426 -132.461508) (xy 107.252076 -132.461021)
			(xy 107.167759 -132.452972) (xy 107.084589 -132.436945) (xy 107.00332 -132.413084) (xy 106.924686 -132.381606)
			(xy 106.849401 -132.342796) (xy 106.778146 -132.297005) (xy 106.711566 -132.244648) (xy 106.650265 -132.186199)
			(xy 106.594798 -132.122187) (xy 106.545666 -132.053193) (xy 106.503315 -131.979841) (xy 106.468129 -131.902796)
			(xy 106.440426 -131.822754) (xy 106.420457 -131.740442) (xy 106.408402 -131.656604) (xy 106.404372 -131.572)
			(xy 96.754413 -131.572) (xy 96.750383 -131.656599) (xy 96.738329 -131.740433) (xy 96.718362 -131.822741)
			(xy 96.690661 -131.902778) (xy 96.655478 -131.97982) (xy 96.613131 -132.053169) (xy 96.564004 -132.122161)
			(xy 96.508541 -132.18617) (xy 96.447245 -132.244617) (xy 96.380671 -132.296974) (xy 96.309421 -132.342765)
			(xy 96.234142 -132.381576) (xy 96.155514 -132.413056) (xy 96.07425 -132.436919) (xy 95.991085 -132.45295)
			(xy 95.906774 -132.461003) (xy 95.864426 -132.461508) (xy 95.818031 -132.460916) (xy 95.725743 -132.451274)
			(xy 95.634959 -132.43208) (xy 95.546665 -132.403545) (xy 95.504 -132.385308) (xy 95.494058 -132.381502)
			(xy 95.472794 -132.381502) (xy 95.462852 -132.385308) (xy 95.420186 -132.403544) (xy 95.331895 -132.43209)
			(xy 95.241111 -132.451286) (xy 95.148822 -132.460922) (xy 95.102426 -132.461508) (xy 95.060076 -132.461021)
			(xy 94.975759 -132.452972) (xy 94.892589 -132.436945) (xy 94.81132 -132.413084) (xy 94.732686 -132.381606)
			(xy 94.657401 -132.342796) (xy 94.586146 -132.297005) (xy 94.519566 -132.244648) (xy 94.458265 -132.186199)
			(xy 94.402798 -132.122187) (xy 94.353666 -132.053193) (xy 94.311315 -131.979841) (xy 94.276129 -131.902796)
			(xy 94.248426 -131.822754) (xy 94.228457 -131.740442) (xy 94.216402 -131.656604) (xy 94.212372 -131.572)
			(xy 84.562413 -131.572) (xy 84.558383 -131.656599) (xy 84.546329 -131.740433) (xy 84.526362 -131.822741)
			(xy 84.498661 -131.902778) (xy 84.463478 -131.97982) (xy 84.421131 -132.053169) (xy 84.372004 -132.122161)
			(xy 84.316541 -132.18617) (xy 84.255245 -132.244617) (xy 84.188671 -132.296974) (xy 84.117421 -132.342765)
			(xy 84.042142 -132.381576) (xy 83.963514 -132.413056) (xy 83.88225 -132.436919) (xy 83.799085 -132.45295)
			(xy 83.714774 -132.461003) (xy 83.672426 -132.461508) (xy 83.626031 -132.460916) (xy 83.533743 -132.451274)
			(xy 83.442959 -132.43208) (xy 83.354665 -132.403545) (xy 83.312 -132.385308) (xy 83.302058 -132.381502)
			(xy 83.280794 -132.381502) (xy 83.270852 -132.385308) (xy 83.228186 -132.403544) (xy 83.139895 -132.43209)
			(xy 83.049111 -132.451286) (xy 82.956822 -132.460922) (xy 82.910426 -132.461508) (xy 82.868076 -132.461021)
			(xy 82.783759 -132.452972) (xy 82.700589 -132.436945) (xy 82.61932 -132.413084) (xy 82.540686 -132.381606)
			(xy 82.465401 -132.342796) (xy 82.394146 -132.297005) (xy 82.327566 -132.244648) (xy 82.266265 -132.186199)
			(xy 82.210798 -132.122187) (xy 82.161666 -132.053193) (xy 82.119315 -131.979841) (xy 82.084129 -131.902796)
			(xy 82.056426 -131.822754) (xy 82.036457 -131.740442) (xy 82.024402 -131.656604) (xy 82.020372 -131.572)
			(xy 68.946513 -131.572) (xy 68.942482 -131.656601) (xy 68.930429 -131.740435) (xy 68.910461 -131.822744)
			(xy 68.88276 -131.902783) (xy 68.847575 -131.979826) (xy 68.805227 -132.053175) (xy 68.756099 -132.122167)
			(xy 68.700634 -132.186177) (xy 68.639337 -132.244624) (xy 68.572761 -132.296981) (xy 68.50151 -132.342771)
			(xy 68.426229 -132.381582) (xy 68.347599 -132.413061) (xy 68.266333 -132.436923) (xy 68.183167 -132.452953)
			(xy 68.098854 -132.461004) (xy 68.056506 -132.461508) (xy 68.01011 -132.460923) (xy 67.917822 -132.451279)
			(xy 67.827038 -132.432083) (xy 67.738745 -132.403546) (xy 67.69608 -132.385308) (xy 67.686138 -132.381502)
			(xy 67.664874 -132.381502) (xy 67.654932 -132.385308) (xy 67.612269 -132.403551) (xy 67.523977 -132.432095)
			(xy 67.433192 -132.451289) (xy 67.340902 -132.460923) (xy 67.294506 -132.461508) (xy 67.252157 -132.46102)
			(xy 67.167841 -132.45297) (xy 67.084673 -132.436941) (xy 67.003405 -132.413079) (xy 66.924773 -132.3816)
			(xy 66.849489 -132.342789) (xy 66.778236 -132.296998) (xy 66.711658 -132.24464) (xy 66.650358 -132.186192)
			(xy 66.594892 -132.122181) (xy 66.545762 -132.053187) (xy 66.503412 -131.979836) (xy 66.468227 -131.902791)
			(xy 66.440525 -131.822751) (xy 66.420556 -131.74044) (xy 66.408502 -131.656603) (xy 66.404472 -131.572)
			(xy 56.754513 -131.572) (xy 56.750482 -131.656601) (xy 56.738429 -131.740435) (xy 56.718461 -131.822744)
			(xy 56.69076 -131.902783) (xy 56.655575 -131.979826) (xy 56.613227 -132.053175) (xy 56.564099 -132.122167)
			(xy 56.508634 -132.186177) (xy 56.447337 -132.244624) (xy 56.380761 -132.296981) (xy 56.30951 -132.342771)
			(xy 56.234229 -132.381582) (xy 56.155599 -132.413061) (xy 56.074333 -132.436923) (xy 55.991167 -132.452953)
			(xy 55.906854 -132.461004) (xy 55.864506 -132.461508) (xy 55.81811 -132.460923) (xy 55.725822 -132.451279)
			(xy 55.635038 -132.432083) (xy 55.546745 -132.403546) (xy 55.50408 -132.385308) (xy 55.494138 -132.381502)
			(xy 55.472874 -132.381502) (xy 55.462932 -132.385308) (xy 55.420269 -132.403551) (xy 55.331977 -132.432095)
			(xy 55.241192 -132.451289) (xy 55.148902 -132.460923) (xy 55.102506 -132.461508) (xy 55.060157 -132.46102)
			(xy 54.975841 -132.45297) (xy 54.892673 -132.436941) (xy 54.811405 -132.413079) (xy 54.732773 -132.3816)
			(xy 54.657489 -132.342789) (xy 54.586236 -132.296998) (xy 54.519658 -132.24464) (xy 54.458358 -132.186192)
			(xy 54.402892 -132.122181) (xy 54.353762 -132.053187) (xy 54.311412 -131.979836) (xy 54.276227 -131.902791)
			(xy 54.248525 -131.822751) (xy 54.228556 -131.74044) (xy 54.216502 -131.656603) (xy 54.212472 -131.572)
			(xy 44.562513 -131.572) (xy 44.558482 -131.656601) (xy 44.546429 -131.740435) (xy 44.526461 -131.822744)
			(xy 44.49876 -131.902783) (xy 44.463575 -131.979826) (xy 44.421227 -132.053175) (xy 44.372099 -132.122167)
			(xy 44.316634 -132.186177) (xy 44.255337 -132.244624) (xy 44.188761 -132.296981) (xy 44.11751 -132.342771)
			(xy 44.042229 -132.381582) (xy 43.963599 -132.413061) (xy 43.882333 -132.436923) (xy 43.799167 -132.452953)
			(xy 43.714854 -132.461004) (xy 43.672506 -132.461508) (xy 43.62611 -132.460923) (xy 43.533822 -132.451279)
			(xy 43.443038 -132.432083) (xy 43.354745 -132.403546) (xy 43.31208 -132.385308) (xy 43.302138 -132.381502)
			(xy 43.280874 -132.381502) (xy 43.270932 -132.385308) (xy 43.228269 -132.403551) (xy 43.139977 -132.432095)
			(xy 43.049192 -132.451289) (xy 42.956902 -132.460923) (xy 42.910506 -132.461508) (xy 42.868157 -132.46102)
			(xy 42.783841 -132.45297) (xy 42.700673 -132.436941) (xy 42.619405 -132.413079) (xy 42.540773 -132.3816)
			(xy 42.465489 -132.342789) (xy 42.394236 -132.296998) (xy 42.327658 -132.24464) (xy 42.266358 -132.186192)
			(xy 42.210892 -132.122181) (xy 42.161762 -132.053187) (xy 42.119412 -131.979836) (xy 42.084227 -131.902791)
			(xy 42.056525 -131.822751) (xy 42.036556 -131.74044) (xy 42.024502 -131.656603) (xy 42.020472 -131.572)
			(xy 0.514454 -131.572) (xy 0.509506 -131.660112) (xy 0.509016 -131.729988) (xy 0.509016 -132.959856)
			(xy 213.088728 -132.959856) (xy 213.089328 -132.913461) (xy 213.098967 -132.821173) (xy 213.118158 -132.730389)
			(xy 213.146692 -132.642095) (xy 213.164928 -132.59943) (xy 213.168758 -132.589495) (xy 213.168741 -132.568225)
			(xy 213.164928 -132.558282) (xy 213.146671 -132.515625) (xy 213.11813 -132.427331) (xy 213.09894 -132.336544)
			(xy 213.089311 -132.244253) (xy 213.088728 -132.197856) (xy 213.089328 -132.151461) (xy 213.098967 -132.059173)
			(xy 213.118158 -131.968389) (xy 213.146692 -131.880095) (xy 213.164928 -131.83743) (xy 213.168758 -131.827495)
			(xy 213.168741 -131.806225) (xy 213.164928 -131.796282) (xy 213.146671 -131.753625) (xy 213.11813 -131.665331)
			(xy 213.09894 -131.574544) (xy 213.089311 -131.482253) (xy 213.088728 -131.435856) (xy 213.089328 -131.389461)
			(xy 213.098967 -131.297173) (xy 213.118158 -131.206389) (xy 213.146692 -131.118095) (xy 213.164928 -131.07543)
			(xy 213.168758 -131.065495) (xy 213.168741 -131.044225) (xy 213.164928 -131.034282) (xy 213.146671 -130.991625)
			(xy 213.11813 -130.903331) (xy 213.09894 -130.812544) (xy 213.089311 -130.720253) (xy 213.088728 -130.673856)
			(xy 213.089328 -130.627461) (xy 213.098967 -130.535173) (xy 213.118158 -130.444389) (xy 213.146692 -130.356095)
			(xy 213.164928 -130.31343) (xy 213.168758 -130.303495) (xy 213.168741 -130.282225) (xy 213.164928 -130.272282)
			(xy 213.146671 -130.229625) (xy 213.11813 -130.141331) (xy 213.09894 -130.050544) (xy 213.089311 -129.958253)
			(xy 213.088728 -129.911856) (xy 213.089328 -129.865461) (xy 213.098967 -129.773173) (xy 213.118158 -129.682389)
			(xy 213.146692 -129.594095) (xy 213.164928 -129.55143) (xy 213.168758 -129.541495) (xy 213.168741 -129.520225)
			(xy 213.164928 -129.510282) (xy 213.146671 -129.467625) (xy 213.11813 -129.379331) (xy 213.09894 -129.288544)
			(xy 213.089311 -129.196253) (xy 213.088728 -129.149856) (xy 213.089328 -129.103461) (xy 213.098967 -129.011173)
			(xy 213.118158 -128.920389) (xy 213.146692 -128.832095) (xy 213.164928 -128.78943) (xy 213.168758 -128.779495)
			(xy 213.168741 -128.758225) (xy 213.164928 -128.748282) (xy 213.146671 -128.705625) (xy 213.11813 -128.617331)
			(xy 213.09894 -128.526544) (xy 213.089311 -128.434253) (xy 213.088728 -128.387856) (xy 213.089328 -128.341461)
			(xy 213.098967 -128.249173) (xy 213.118158 -128.158389) (xy 213.146692 -128.070095) (xy 213.164928 -128.02743)
			(xy 213.168758 -128.017495) (xy 213.168741 -127.996225) (xy 213.164928 -127.986282) (xy 213.146671 -127.943625)
			(xy 213.11813 -127.855331) (xy 213.09894 -127.764544) (xy 213.089311 -127.672253) (xy 213.088728 -127.625856)
			(xy 213.089125 -127.584752) (xy 213.096714 -127.502894) (xy 213.111824 -127.422086) (xy 213.134325 -127.343017)
			(xy 213.164026 -127.266361) (xy 213.200673 -127.192773) (xy 213.243953 -127.12288) (xy 213.293498 -127.057278)
			(xy 213.348884 -126.996528) (xy 213.40964 -126.941147) (xy 213.475246 -126.891608) (xy 213.545143 -126.848334)
			(xy 213.618734 -126.811693) (xy 213.695393 -126.781999) (xy 213.774464 -126.759505) (xy 213.855273 -126.744403)
			(xy 213.937132 -126.736821) (xy 213.978236 -126.736348) (xy 214.019707 -126.736821) (xy 214.102292 -126.744496)
			(xy 214.183804 -126.759823) (xy 214.263536 -126.782669) (xy 214.30234 -126.797308) (xy 214.311828 -126.800522)
			(xy 214.331839 -126.800112) (xy 214.341202 -126.796546) (xy 214.383373 -126.778847) (xy 214.47054 -126.751148)
			(xy 214.560087 -126.732532) (xy 214.651071 -126.723195) (xy 214.696802 -126.722632) (xy 214.743198 -126.723211)
			(xy 214.835486 -126.732857) (xy 214.92627 -126.752054) (xy 215.014563 -126.780593) (xy 215.057228 -126.798832)
			(xy 215.06717 -126.802638) (xy 215.088434 -126.802638) (xy 215.098376 -126.798832) (xy 215.141039 -126.780589)
			(xy 215.229331 -126.752044) (xy 215.320116 -126.73285) (xy 215.412406 -126.723217) (xy 215.458802 -126.722632)
			(xy 215.502226 -126.723118) (xy 215.588665 -126.731536) (xy 215.673869 -126.748349) (xy 215.757026 -126.773398)
			(xy 215.797384 -126.789434) (xy 215.806818 -126.792777) (xy 215.826812 -126.792777) (xy 215.836246 -126.789434)
			(xy 215.87661 -126.77342) (xy 215.959771 -126.748397) (xy 216.044973 -126.731586) (xy 216.131406 -126.723147)
			(xy 216.174828 -126.722632) (xy 216.221223 -126.723237) (xy 216.313511 -126.732875) (xy 216.404295 -126.752064)
			(xy 216.492589 -126.780597) (xy 216.535254 -126.798832) (xy 216.545196 -126.802638) (xy 216.56646 -126.802638)
			(xy 216.576402 -126.798832) (xy 216.619061 -126.78058) (xy 216.707355 -126.752038) (xy 216.798141 -126.732846)
			(xy 216.890432 -126.723215) (xy 216.936828 -126.722632) (xy 216.977933 -126.723025) (xy 217.059791 -126.730613)
			(xy 217.140601 -126.745722) (xy 217.219671 -126.768223) (xy 217.296329 -126.797923) (xy 217.369918 -126.834569)
			(xy 217.439813 -126.87785) (xy 217.505416 -126.927394) (xy 217.566167 -126.982781) (xy 217.621549 -127.043537)
			(xy 217.671089 -127.109143) (xy 217.714364 -127.179041) (xy 217.751005 -127.252634) (xy 217.780699 -127.329293)
			(xy 217.803193 -127.408365) (xy 217.818296 -127.489176) (xy 217.825878 -127.571035) (xy 217.826336 -127.61214)
			(xy 217.82573 -127.658535) (xy 217.816091 -127.750823) (xy 217.796902 -127.841606) (xy 217.76837 -127.929901)
			(xy 217.750136 -127.972566) (xy 217.746305 -127.982501) (xy 217.746321 -128.003772) (xy 217.750136 -128.013714)
			(xy 217.768396 -128.05637) (xy 217.796935 -128.144665) (xy 217.816124 -128.235452) (xy 217.825753 -128.327743)
			(xy 217.826336 -128.37414) (xy 217.82573 -128.420535) (xy 217.816091 -128.512823) (xy 217.796902 -128.603606)
			(xy 217.76837 -128.691901) (xy 217.750136 -128.734566) (xy 217.746305 -128.744501) (xy 217.746321 -128.765772)
			(xy 217.750136 -128.775714) (xy 217.768396 -128.81837) (xy 217.796935 -128.906665) (xy 217.816124 -128.997452)
			(xy 217.825753 -129.089743) (xy 217.826336 -129.13614) (xy 217.82573 -129.182535) (xy 217.816091 -129.274823)
			(xy 217.796902 -129.365606) (xy 217.76837 -129.453901) (xy 217.750136 -129.496566) (xy 217.746305 -129.506501)
			(xy 217.746321 -129.527772) (xy 217.750136 -129.537714) (xy 217.768396 -129.58037) (xy 217.796935 -129.668665)
			(xy 217.816124 -129.759452) (xy 217.825753 -129.851743) (xy 217.826336 -129.89814) (xy 217.82573 -129.944535)
			(xy 217.816091 -130.036823) (xy 217.796902 -130.127606) (xy 217.76837 -130.215901) (xy 217.750136 -130.258566)
			(xy 217.746305 -130.268501) (xy 217.746321 -130.289772) (xy 217.750136 -130.299714) (xy 217.768396 -130.34237)
			(xy 217.796935 -130.430665) (xy 217.816124 -130.521452) (xy 217.825753 -130.613743) (xy 217.826336 -130.66014)
			(xy 217.82573 -130.706535) (xy 217.816091 -130.798823) (xy 217.796902 -130.889606) (xy 217.76837 -130.977901)
			(xy 217.750136 -131.020566) (xy 217.746305 -131.030501) (xy 217.746321 -131.051772) (xy 217.750136 -131.061714)
			(xy 217.768396 -131.10437) (xy 217.770454 -131.110736) (xy 230.701596 -131.110736) (xy 230.702191 -131.064341)
			(xy 230.711833 -130.972053) (xy 230.731025 -130.881269) (xy 230.75956 -130.792975) (xy 230.777796 -130.75031)
			(xy 230.78158 -130.740361) (xy 230.781594 -130.719104) (xy 230.777796 -130.709162) (xy 230.759563 -130.666495)
			(xy 230.731016 -130.578204) (xy 230.71182 -130.487421) (xy 230.702183 -130.395132) (xy 230.701596 -130.348736)
			(xy 230.702191 -130.302341) (xy 230.711833 -130.210053) (xy 230.731025 -130.119269) (xy 230.75956 -130.030975)
			(xy 230.777796 -129.98831) (xy 230.78158 -129.978361) (xy 230.781594 -129.957104) (xy 230.777796 -129.947162)
			(xy 230.759563 -129.904495) (xy 230.731016 -129.816204) (xy 230.71182 -129.725421) (xy 230.702183 -129.633132)
			(xy 230.701596 -129.586736) (xy 230.702191 -129.540341) (xy 230.711833 -129.448053) (xy 230.731025 -129.357269)
			(xy 230.75956 -129.268975) (xy 230.777796 -129.22631) (xy 230.78158 -129.216361) (xy 230.781594 -129.195104)
			(xy 230.777796 -129.185162) (xy 230.759563 -129.142495) (xy 230.731016 -129.054204) (xy 230.71182 -128.963421)
			(xy 230.702183 -128.871132) (xy 230.701596 -128.824736) (xy 230.702191 -128.778341) (xy 230.711833 -128.686053)
			(xy 230.731025 -128.595269) (xy 230.75956 -128.506975) (xy 230.777796 -128.46431) (xy 230.78158 -128.454361)
			(xy 230.781594 -128.433104) (xy 230.777796 -128.423162) (xy 230.759563 -128.380495) (xy 230.731016 -128.292204)
			(xy 230.71182 -128.201421) (xy 230.702183 -128.109132) (xy 230.701596 -128.062736) (xy 230.702191 -128.016341)
			(xy 230.711833 -127.924053) (xy 230.731025 -127.833269) (xy 230.75956 -127.744975) (xy 230.777796 -127.70231)
			(xy 230.78158 -127.692361) (xy 230.781594 -127.671104) (xy 230.777796 -127.661162) (xy 230.759563 -127.618495)
			(xy 230.731016 -127.530204) (xy 230.71182 -127.439421) (xy 230.702183 -127.347132) (xy 230.701596 -127.300736)
			(xy 230.702147 -127.256691) (xy 230.710849 -127.169033) (xy 230.72817 -127.082663) (xy 230.753941 -126.998427)
			(xy 230.77043 -126.957582) (xy 230.773801 -126.948582) (xy 230.774177 -126.92938) (xy 230.771192 -126.920244)
			(xy 230.757686 -126.882861) (xy 230.736583 -126.806223) (xy 230.722406 -126.728008) (xy 230.715266 -126.648839)
			(xy 230.714804 -126.609094) (xy 230.715307 -126.567981) (xy 230.722894 -126.486105) (xy 230.738004 -126.405278)
			(xy 230.760506 -126.326191) (xy 230.790209 -126.249516) (xy 230.82686 -126.17591) (xy 230.870147 -126.105999)
			(xy 230.919698 -126.04038) (xy 230.975093 -125.979613) (xy 231.035859 -125.924216) (xy 231.101476 -125.874662)
			(xy 231.171385 -125.831374) (xy 231.244991 -125.794721) (xy 231.321664 -125.765015) (xy 231.400751 -125.74251)
			(xy 231.481577 -125.727398) (xy 231.563453 -125.719808) (xy 231.604566 -125.719332) (xy 231.650969 -125.719939)
			(xy 231.743266 -125.729636) (xy 231.834052 -125.748895) (xy 231.922336 -125.777508) (xy 231.964992 -125.795786)
			(xy 231.974934 -125.799592) (xy 231.996198 -125.799592) (xy 232.00614 -125.795786) (xy 232.048804 -125.777532)
			(xy 232.137091 -125.748938) (xy 232.227873 -125.729678) (xy 232.320165 -125.719963) (xy 232.366566 -125.719332)
			(xy 232.409139 -125.719856) (xy 232.493893 -125.728015) (xy 232.577478 -125.744243) (xy 232.659128 -125.768389)
			(xy 232.698798 -125.783848) (xy 232.70805 -125.787101) (xy 232.727646 -125.787101) (xy 232.736898 -125.783848)
			(xy 232.776567 -125.768388) (xy 232.858222 -125.74426) (xy 232.941806 -125.728033) (xy 233.026558 -125.719855)
			(xy 233.06913 -125.719332) (xy 233.115532 -125.719952) (xy 233.20783 -125.729645) (xy 233.298615 -125.7489)
			(xy 233.3869 -125.77751) (xy 233.429556 -125.795786) (xy 233.439498 -125.799592) (xy 233.460762 -125.799592)
			(xy 233.470704 -125.795786) (xy 233.51336 -125.777511) (xy 233.60165 -125.748922) (xy 233.692434 -125.729668)
			(xy 233.784729 -125.719959) (xy 233.83113 -125.719332) (xy 233.877532 -125.719952) (xy 233.96983 -125.729645)
			(xy 234.060615 -125.7489) (xy 234.1489 -125.77751) (xy 234.191556 -125.795786) (xy 234.201498 -125.799592)
			(xy 234.222762 -125.799592) (xy 234.232704 -125.795786) (xy 234.27536 -125.777511) (xy 234.36365 -125.748922)
			(xy 234.454434 -125.729668) (xy 234.546729 -125.719959) (xy 234.59313 -125.719332) (xy 234.634245 -125.719784)
			(xy 234.716123 -125.727374) (xy 234.796951 -125.742486) (xy 234.876041 -125.764991) (xy 234.952716 -125.794697)
			(xy 235.026324 -125.831352) (xy 235.067746 -125.857) (xy 268.350492 -125.857) (xy 268.351075 -125.810604)
			(xy 268.36072 -125.718316) (xy 268.379916 -125.627532) (xy 268.408454 -125.539239) (xy 268.426692 -125.496574)
			(xy 268.430498 -125.486632) (xy 268.430498 -125.465368) (xy 268.426692 -125.455426) (xy 268.408447 -125.412764)
			(xy 268.379903 -125.324471) (xy 268.36071 -125.233686) (xy 268.351077 -125.141396) (xy 268.350492 -125.095)
			(xy 268.351075 -125.048604) (xy 268.36072 -124.956316) (xy 268.379916 -124.865532) (xy 268.408454 -124.777239)
			(xy 268.426692 -124.734574) (xy 268.430498 -124.724632) (xy 268.430498 -124.703368) (xy 268.426692 -124.693426)
			(xy 268.408447 -124.650764) (xy 268.379903 -124.562471) (xy 268.36071 -124.471686) (xy 268.351077 -124.379396)
			(xy 268.350492 -124.333) (xy 268.351075 -124.286604) (xy 268.36072 -124.194316) (xy 268.379916 -124.103532)
			(xy 268.408454 -124.015239) (xy 268.426692 -123.972574) (xy 268.430498 -123.962632) (xy 268.430498 -123.941368)
			(xy 268.426692 -123.931426) (xy 268.408447 -123.888764) (xy 268.379903 -123.800471) (xy 268.36071 -123.709686)
			(xy 268.351077 -123.617396) (xy 268.350492 -123.571) (xy 268.351075 -123.524604) (xy 268.36072 -123.432316)
			(xy 268.379916 -123.341532) (xy 268.408454 -123.253239) (xy 268.426692 -123.210574) (xy 268.430498 -123.200632)
			(xy 268.430498 -123.179368) (xy 268.426692 -123.169426) (xy 268.408447 -123.126764) (xy 268.379903 -123.038471)
			(xy 268.36071 -122.947686) (xy 268.351077 -122.855396) (xy 268.350492 -122.809) (xy 268.351075 -122.762604)
			(xy 268.36072 -122.670316) (xy 268.379916 -122.579532) (xy 268.408454 -122.491239) (xy 268.426692 -122.448574)
			(xy 268.430498 -122.438632) (xy 268.430498 -122.417368) (xy 268.426692 -122.407426) (xy 268.408447 -122.364764)
			(xy 268.379903 -122.276471) (xy 268.36071 -122.185686) (xy 268.351077 -122.093396) (xy 268.350492 -122.047)
			(xy 268.350967 -122.005898) (xy 268.358552 -121.924043) (xy 268.373657 -121.843238) (xy 268.396153 -121.764171)
			(xy 268.425849 -121.687517) (xy 268.462491 -121.61393) (xy 268.505766 -121.544038) (xy 268.555306 -121.478437)
			(xy 268.610687 -121.417687) (xy 268.671437 -121.362306) (xy 268.737038 -121.312766) (xy 268.80693 -121.269491)
			(xy 268.880517 -121.232849) (xy 268.957171 -121.203153) (xy 269.036238 -121.180657) (xy 269.117043 -121.165552)
			(xy 269.198898 -121.157967) (xy 269.24 -121.157492) (xy 269.286396 -121.158075) (xy 269.378684 -121.16772)
			(xy 269.469468 -121.186916) (xy 269.557761 -121.215454) (xy 269.600426 -121.233692) (xy 269.610368 -121.237498)
			(xy 269.631632 -121.237498) (xy 269.641574 -121.233692) (xy 269.684236 -121.215447) (xy 269.772529 -121.186903)
			(xy 269.863314 -121.16771) (xy 269.955604 -121.158077) (xy 270.002 -121.157492) (xy 270.048396 -121.158075)
			(xy 270.140684 -121.16772) (xy 270.231468 -121.186916) (xy 270.319761 -121.215454) (xy 270.362426 -121.233692)
			(xy 270.372368 -121.237498) (xy 270.393632 -121.237498) (xy 270.403574 -121.233692) (xy 270.446236 -121.215447)
			(xy 270.534529 -121.186903) (xy 270.625314 -121.16771) (xy 270.717604 -121.158077) (xy 270.764 -121.157492)
			(xy 270.810396 -121.158075) (xy 270.902684 -121.16772) (xy 270.993468 -121.186916) (xy 271.081761 -121.215454)
			(xy 271.124426 -121.233692) (xy 271.134368 -121.237498) (xy 271.155632 -121.237498) (xy 271.165574 -121.233692)
			(xy 271.208236 -121.215447) (xy 271.296529 -121.186903) (xy 271.387314 -121.16771) (xy 271.479604 -121.158077)
			(xy 271.526 -121.157492) (xy 271.572396 -121.158075) (xy 271.664684 -121.16772) (xy 271.755468 -121.186916)
			(xy 271.843761 -121.215454) (xy 271.886426 -121.233692) (xy 271.896368 -121.237498) (xy 271.917632 -121.237498)
			(xy 271.927574 -121.233692) (xy 271.970236 -121.215447) (xy 272.058529 -121.186903) (xy 272.149314 -121.16771)
			(xy 272.241604 -121.158077) (xy 272.288 -121.157492) (xy 272.329102 -121.157967) (xy 272.410957 -121.165552)
			(xy 272.491762 -121.180657) (xy 272.570829 -121.203153) (xy 272.647483 -121.232849) (xy 272.72107 -121.269491)
			(xy 272.790962 -121.312766) (xy 272.856563 -121.362306) (xy 272.917313 -121.417687) (xy 272.972694 -121.478437)
			(xy 273.022234 -121.544038) (xy 273.065509 -121.61393) (xy 273.102151 -121.687517) (xy 273.131847 -121.764171)
			(xy 273.154343 -121.843238) (xy 273.169448 -121.924043) (xy 273.177033 -122.005898) (xy 273.177508 -122.047)
			(xy 273.176925 -122.093396) (xy 273.16728 -122.185684) (xy 273.148084 -122.276468) (xy 273.119546 -122.364761)
			(xy 273.101308 -122.407426) (xy 273.097502 -122.417368) (xy 273.097502 -122.438632) (xy 273.101308 -122.448574)
			(xy 273.119553 -122.491236) (xy 273.148097 -122.579529) (xy 273.16729 -122.670314) (xy 273.176923 -122.762604)
			(xy 273.177508 -122.809) (xy 273.177033 -122.850102) (xy 273.169448 -122.931957) (xy 273.154343 -123.012762)
			(xy 273.131847 -123.091829) (xy 273.102151 -123.168483) (xy 273.065509 -123.24207) (xy 273.022234 -123.311962)
			(xy 272.972694 -123.377563) (xy 272.917313 -123.438313) (xy 272.856563 -123.493694) (xy 272.790962 -123.543234)
			(xy 272.72107 -123.586509) (xy 272.647483 -123.623151) (xy 272.570829 -123.652847) (xy 272.491762 -123.675343)
			(xy 272.410957 -123.690448) (xy 272.329102 -123.698033) (xy 272.288 -123.698508) (xy 272.241604 -123.697925)
			(xy 272.149316 -123.68828) (xy 272.058532 -123.669084) (xy 271.970239 -123.640546) (xy 271.927574 -123.622308)
			(xy 271.917632 -123.618502) (xy 271.896368 -123.618502) (xy 271.886426 -123.622308) (xy 271.853507 -123.636537)
			(xy 271.785822 -123.660257) (xy 271.716442 -123.678437) (xy 271.681194 -123.685046) (xy 271.67107 -123.687344)
			(xy 271.653749 -123.698749) (xy 271.642344 -123.71607) (xy 271.640046 -123.726194) (xy 271.633416 -123.761437)
			(xy 271.61522 -123.83081) (xy 271.591513 -123.898498) (xy 271.577308 -123.931426) (xy 271.573502 -123.941368)
			(xy 271.573502 -123.962632) (xy 271.577308 -123.972574) (xy 271.591537 -124.005493) (xy 271.615257 -124.073178)
			(xy 271.633437 -124.142558) (xy 271.640046 -124.177806) (xy 271.642344 -124.18793) (xy 271.653749 -124.205251)
			(xy 271.67107 -124.216656) (xy 271.681194 -124.218954) (xy 271.716437 -124.225584) (xy 271.78581 -124.24378)
			(xy 271.853498 -124.267487) (xy 271.886426 -124.281692) (xy 271.896368 -124.285498) (xy 271.917632 -124.285498)
			(xy 271.927574 -124.281692) (xy 271.970236 -124.263447) (xy 272.058529 -124.234903) (xy 272.149314 -124.21571)
			(xy 272.241604 -124.206077) (xy 272.288 -124.205492) (xy 272.329102 -124.205967) (xy 272.410957 -124.213552)
			(xy 272.491762 -124.228657) (xy 272.570829 -124.251153) (xy 272.647483 -124.280849) (xy 272.72107 -124.317491)
			(xy 272.790962 -124.360766) (xy 272.856563 -124.410306) (xy 272.917313 -124.465687) (xy 272.972694 -124.526437)
			(xy 273.022234 -124.592038) (xy 273.065509 -124.66193) (xy 273.102151 -124.735517) (xy 273.131847 -124.812171)
			(xy 273.154343 -124.891238) (xy 273.169448 -124.972043) (xy 273.177033 -125.053898) (xy 273.177508 -125.095)
			(xy 273.176925 -125.141396) (xy 273.16728 -125.233684) (xy 273.148084 -125.324468) (xy 273.119546 -125.412761)
			(xy 273.101308 -125.455426) (xy 273.097502 -125.465368) (xy 273.097502 -125.486632) (xy 273.101308 -125.496574)
			(xy 273.119553 -125.539236) (xy 273.148097 -125.627529) (xy 273.16729 -125.718314) (xy 273.176923 -125.810604)
			(xy 273.177508 -125.857) (xy 273.177033 -125.898102) (xy 273.169448 -125.979957) (xy 273.154343 -126.060762)
			(xy 273.131847 -126.139829) (xy 273.102151 -126.216483) (xy 273.065509 -126.29007) (xy 273.022234 -126.359962)
			(xy 272.972694 -126.425563) (xy 272.917313 -126.486313) (xy 272.856563 -126.541694) (xy 272.790962 -126.591234)
			(xy 272.72107 -126.634509) (xy 272.647483 -126.671151) (xy 272.570829 -126.700847) (xy 272.491762 -126.723343)
			(xy 272.410957 -126.738448) (xy 272.329102 -126.746033) (xy 272.288 -126.746508) (xy 272.241604 -126.745925)
			(xy 272.149316 -126.73628) (xy 272.058532 -126.717084) (xy 271.970239 -126.688546) (xy 271.927574 -126.670308)
			(xy 271.917632 -126.666502) (xy 271.896368 -126.666502) (xy 271.886426 -126.670308) (xy 271.843764 -126.688553)
			(xy 271.755471 -126.717097) (xy 271.664686 -126.73629) (xy 271.572396 -126.745923) (xy 271.526 -126.746508)
			(xy 271.479604 -126.745925) (xy 271.387316 -126.73628) (xy 271.296532 -126.717084) (xy 271.208239 -126.688546)
			(xy 271.165574 -126.670308) (xy 271.155632 -126.666502) (xy 271.134368 -126.666502) (xy 271.124426 -126.670308)
			(xy 271.081764 -126.688553) (xy 270.993471 -126.717097) (xy 270.902686 -126.73629) (xy 270.810396 -126.745923)
			(xy 270.764 -126.746508) (xy 270.717604 -126.745925) (xy 270.625316 -126.73628) (xy 270.534532 -126.717084)
			(xy 270.446239 -126.688546) (xy 270.403574 -126.670308) (xy 270.393632 -126.666502) (xy 270.372368 -126.666502)
			(xy 270.362426 -126.670308) (xy 270.319764 -126.688553) (xy 270.231471 -126.717097) (xy 270.140686 -126.73629)
			(xy 270.048396 -126.745923) (xy 270.002 -126.746508) (xy 269.955604 -126.745925) (xy 269.863316 -126.73628)
			(xy 269.772532 -126.717084) (xy 269.684239 -126.688546) (xy 269.641574 -126.670308) (xy 269.631632 -126.666502)
			(xy 269.610368 -126.666502) (xy 269.600426 -126.670308) (xy 269.557764 -126.688553) (xy 269.469471 -126.717097)
			(xy 269.378686 -126.73629) (xy 269.286396 -126.745923) (xy 269.24 -126.746508) (xy 269.198898 -126.746033)
			(xy 269.117043 -126.738448) (xy 269.036238 -126.723343) (xy 268.957171 -126.700847) (xy 268.880517 -126.671151)
			(xy 268.80693 -126.634509) (xy 268.737038 -126.591234) (xy 268.671437 -126.541694) (xy 268.610687 -126.486313)
			(xy 268.555306 -126.425563) (xy 268.505766 -126.359962) (xy 268.462491 -126.29007) (xy 268.425849 -126.216483)
			(xy 268.396153 -126.139829) (xy 268.373657 -126.060762) (xy 268.358552 -125.979957) (xy 268.350967 -125.898102)
			(xy 268.350492 -125.857) (xy 235.067746 -125.857) (xy 235.096236 -125.874641) (xy 235.161855 -125.924196)
			(xy 235.222622 -125.979595) (xy 235.278019 -126.040363) (xy 235.327572 -126.105984) (xy 235.37086 -126.175897)
			(xy 235.407512 -126.249506) (xy 235.437217 -126.326182) (xy 235.45972 -126.405272) (xy 235.474829 -126.486101)
			(xy 235.482417 -126.567979) (xy 235.482892 -126.609094) (xy 235.482318 -126.653145) (xy 235.473542 -126.740808)
			(xy 235.456153 -126.827177) (xy 235.430321 -126.911407) (xy 235.413804 -126.952248) (xy 235.410474 -126.961259)
			(xy 235.410073 -126.98045) (xy 235.413042 -126.989586) (xy 235.426531 -127.026969) (xy 235.447571 -127.103614)
			(xy 235.461682 -127.181831) (xy 235.46875 -127.260996) (xy 235.469176 -127.300736) (xy 235.468573 -127.347131)
			(xy 235.458934 -127.439419) (xy 235.439744 -127.530203) (xy 235.411211 -127.618497) (xy 235.392976 -127.661162)
			(xy 235.389151 -127.671098) (xy 235.389165 -127.692367) (xy 235.392976 -127.70231) (xy 235.411231 -127.744968)
			(xy 235.439773 -127.833262) (xy 235.458963 -127.924048) (xy 235.468593 -128.01634) (xy 235.469176 -128.062736)
			(xy 235.468573 -128.109131) (xy 235.458934 -128.201419) (xy 235.439744 -128.292203) (xy 235.411211 -128.380497)
			(xy 235.392976 -128.423162) (xy 235.389151 -128.433098) (xy 235.389165 -128.454367) (xy 235.392976 -128.46431)
			(xy 235.411231 -128.506968) (xy 235.439773 -128.595262) (xy 235.458963 -128.686048) (xy 235.468593 -128.77834)
			(xy 235.469176 -128.824736) (xy 235.468573 -128.871131) (xy 235.458934 -128.963419) (xy 235.455402 -128.980127)
			(xy 270.348706 -128.980127) (xy 270.348706 -128.895405) (xy 270.356759 -128.811068) (xy 270.372793 -128.727878)
			(xy 270.396661 -128.646588) (xy 270.428149 -128.567936) (xy 270.466971 -128.492633) (xy 270.512774 -128.421361)
			(xy 270.565145 -128.354765) (xy 270.62361 -128.29345) (xy 270.687638 -128.237969) (xy 270.75665 -128.188826)
			(xy 270.83002 -128.146466) (xy 270.907085 -128.111271) (xy 270.987147 -128.083562) (xy 271.06948 -128.063588)
			(xy 271.153339 -128.051531) (xy 271.237964 -128.0475) (xy 271.322589 -128.051531) (xy 271.406448 -128.063588)
			(xy 271.488781 -128.083562) (xy 271.568843 -128.111271) (xy 271.645908 -128.146466) (xy 271.719278 -128.188826)
			(xy 271.78829 -128.237969) (xy 271.852318 -128.29345) (xy 271.910783 -128.354765) (xy 271.963154 -128.421361)
			(xy 272.008957 -128.492633) (xy 272.047779 -128.567936) (xy 272.079267 -128.646588) (xy 272.103135 -128.727878)
			(xy 272.119169 -128.811068) (xy 272.127222 -128.895405) (xy 272.127726 -128.937766) (xy 272.127222 -128.980127)
			(xy 272.119169 -129.064464) (xy 272.103135 -129.147654) (xy 272.079267 -129.228944) (xy 272.047779 -129.307596)
			(xy 272.008957 -129.382899) (xy 271.963154 -129.454171) (xy 271.910783 -129.520767) (xy 271.852318 -129.582082)
			(xy 271.78829 -129.637563) (xy 271.719278 -129.686706) (xy 271.645908 -129.729066) (xy 271.568843 -129.764261)
			(xy 271.488781 -129.79197) (xy 271.406448 -129.811944) (xy 271.322589 -129.824001) (xy 271.237964 -129.828033)
			(xy 271.153339 -129.824001) (xy 271.06948 -129.811944) (xy 270.987147 -129.79197) (xy 270.907085 -129.764261)
			(xy 270.83002 -129.729066) (xy 270.75665 -129.686706) (xy 270.687638 -129.637563) (xy 270.62361 -129.582082)
			(xy 270.565145 -129.520767) (xy 270.512774 -129.454171) (xy 270.466971 -129.382899) (xy 270.428149 -129.307596)
			(xy 270.396661 -129.228944) (xy 270.372793 -129.147654) (xy 270.356759 -129.064464) (xy 270.348706 -128.980127)
			(xy 235.455402 -128.980127) (xy 235.439744 -129.054203) (xy 235.411211 -129.142497) (xy 235.392976 -129.185162)
			(xy 235.389151 -129.195098) (xy 235.389165 -129.216367) (xy 235.392976 -129.22631) (xy 235.411231 -129.268968)
			(xy 235.439773 -129.357262) (xy 235.458963 -129.448048) (xy 235.468593 -129.54034) (xy 235.469176 -129.586736)
			(xy 235.468573 -129.633131) (xy 235.458934 -129.725419) (xy 235.439744 -129.816203) (xy 235.411211 -129.904497)
			(xy 235.392976 -129.947162) (xy 235.389151 -129.957098) (xy 235.389165 -129.978367) (xy 235.392976 -129.98831)
			(xy 235.411231 -130.030968) (xy 235.439773 -130.119262) (xy 235.458963 -130.210048) (xy 235.468593 -130.30234)
			(xy 235.469176 -130.348736) (xy 235.468573 -130.395131) (xy 235.458934 -130.487419) (xy 235.449335 -130.532829)
			(xy 268.757142 -130.532829) (xy 268.757142 -130.448107) (xy 268.765195 -130.36377) (xy 268.781229 -130.28058)
			(xy 268.805097 -130.19929) (xy 268.836585 -130.120638) (xy 268.875407 -130.045335) (xy 268.92121 -129.974063)
			(xy 268.973581 -129.907467) (xy 269.032046 -129.846152) (xy 269.096074 -129.790671) (xy 269.165086 -129.741528)
			(xy 269.238456 -129.699168) (xy 269.315521 -129.663973) (xy 269.395583 -129.636264) (xy 269.477916 -129.61629)
			(xy 269.561775 -129.604233) (xy 269.6464 -129.600202) (xy 269.731025 -129.604233) (xy 269.814884 -129.61629)
			(xy 269.897217 -129.636264) (xy 269.977279 -129.663973) (xy 270.054344 -129.699168) (xy 270.127714 -129.741528)
			(xy 270.196726 -129.790671) (xy 270.260754 -129.846152) (xy 270.319219 -129.907467) (xy 270.37159 -129.974063)
			(xy 270.417393 -130.045335) (xy 270.456215 -130.120638) (xy 270.487703 -130.19929) (xy 270.511571 -130.28058)
			(xy 270.527605 -130.36377) (xy 270.535658 -130.448107) (xy 270.536162 -130.490468) (xy 270.535658 -130.532829)
			(xy 270.527605 -130.617166) (xy 270.511571 -130.700356) (xy 270.487703 -130.781646) (xy 270.456215 -130.860298)
			(xy 270.417393 -130.935601) (xy 270.37159 -131.006873) (xy 270.319219 -131.073469) (xy 270.260754 -131.134784)
			(xy 270.196726 -131.190265) (xy 270.127714 -131.239408) (xy 270.054344 -131.281768) (xy 269.977279 -131.316963)
			(xy 269.897217 -131.344672) (xy 269.814884 -131.364646) (xy 269.731025 -131.376703) (xy 269.6464 -131.380735)
			(xy 269.561775 -131.376703) (xy 269.477916 -131.364646) (xy 269.395583 -131.344672) (xy 269.315521 -131.316963)
			(xy 269.238456 -131.281768) (xy 269.165086 -131.239408) (xy 269.096074 -131.190265) (xy 269.032046 -131.134784)
			(xy 268.973581 -131.073469) (xy 268.92121 -131.006873) (xy 268.875407 -130.935601) (xy 268.836585 -130.860298)
			(xy 268.805097 -130.781646) (xy 268.781229 -130.700356) (xy 268.765195 -130.617166) (xy 268.757142 -130.532829)
			(xy 235.449335 -130.532829) (xy 235.439744 -130.578203) (xy 235.411211 -130.666497) (xy 235.392976 -130.709162)
			(xy 235.389151 -130.719098) (xy 235.389165 -130.740367) (xy 235.392976 -130.75031) (xy 235.411231 -130.792968)
			(xy 235.439773 -130.881262) (xy 235.458963 -130.972048) (xy 235.468593 -131.06434) (xy 235.469176 -131.110736)
			(xy 235.4687 -131.152245) (xy 235.460981 -131.234903) (xy 235.445588 -131.316482) (xy 235.422653 -131.396269)
			(xy 235.407962 -131.435094) (xy 235.404787 -131.444591) (xy 235.405179 -131.464591) (xy 235.408724 -131.473956)
			(xy 235.42646 -131.51612) (xy 235.451388 -131.594352) (xy 277.69185 -131.594352) (xy 277.69185 -52.12715)
			(xy 277.692343 -52.093889) (xy 277.701036 -52.027937) (xy 277.718266 -51.963685) (xy 277.743739 -51.902233)
			(xy 277.777018 -51.844633) (xy 277.817533 -51.791872) (xy 277.840694 -51.767994) (xy 280.996644 -48.612044)
			(xy 281.020529 -48.588892) (xy 281.073289 -48.548379) (xy 281.130888 -48.515103) (xy 281.192339 -48.489634)
			(xy 281.25659 -48.472409) (xy 281.32254 -48.463721) (xy 281.3558 -48.4632) (xy 288.2392 -48.4632)
			(xy 288.272459 -48.463739) (xy 288.338409 -48.472425) (xy 288.40266 -48.489647) (xy 288.464111 -48.515111)
			(xy 288.521712 -48.548382) (xy 288.574476 -48.588888) (xy 288.598356 -48.612044) (xy 290.66871 -50.682398)
			(xy 290.676113 -50.689235) (xy 290.69471 -50.696956) (xy 290.704778 -50.697384) (xy 295.751758 -50.697384)
			(xy 295.760531 -50.697053) (xy 295.777068 -50.691205) (xy 295.790635 -50.680088) (xy 295.795446 -50.672746)
			(xy 295.847008 -50.586386) (xy 295.84777 -50.55997) (xy 295.84142 -50.548032) (xy 295.83447 -50.534031)
			(xy 295.826892 -50.503713) (xy 295.826434 -50.488088) (xy 295.826434 -47.710598) (xy 295.826902 -47.694875)
			(xy 295.834601 -47.664385) (xy 295.849508 -47.636695) (xy 295.870721 -47.613481) (xy 295.883584 -47.604426)
			(xy 295.892982 -47.59833) (xy 295.904666 -47.579788) (xy 295.91762 -47.48149) (xy 295.91127 -47.460662)
			(xy 295.903904 -47.45228) (xy 295.877568 -47.421825) (xy 295.829911 -47.356921) (xy 295.788317 -47.287975)
			(xy 295.753126 -47.215551) (xy 295.724627 -47.140242) (xy 295.703053 -47.062664) (xy 295.688581 -46.983455)
			(xy 295.681328 -46.903261) (xy 295.680892 -46.863) (xy 295.681389 -46.820692) (xy 295.689392 -46.736456)
			(xy 295.705353 -46.65336) (xy 295.72913 -46.572154) (xy 295.760506 -46.493571) (xy 295.799199 -46.418321)
			(xy 295.821608 -46.382432) (xy 295.826488 -46.374042) (xy 295.830156 -46.355) (xy 295.826488 -46.335958)
			(xy 295.821608 -46.327568) (xy 295.799176 -46.291691) (xy 295.760465 -46.216446) (xy 295.729079 -46.137863)
			(xy 295.705303 -46.056653) (xy 295.68935 -45.973551) (xy 295.681366 -45.88931) (xy 295.680892 -45.847)
			(xy 295.681417 -45.801657) (xy 295.690578 -45.711437) (xy 295.69918 -45.666914) (xy 295.701974 -45.653706)
			(xy 295.693846 -45.628306) (xy 295.61028 -45.55109) (xy 295.584626 -45.544994) (xy 295.571672 -45.54855)
			(xy 295.531633 -45.559591) (xy 295.450025 -45.575055) (xy 295.36733 -45.582845) (xy 295.3258 -45.583348)
			(xy 295.275639 -45.58264) (xy 295.175958 -45.571313) (xy 295.126918 -45.560742) (xy 295.116758 -45.558456)
			(xy 295.096438 -45.562012) (xy 295.017952 -45.612812) (xy 295.006522 -45.62983) (xy 295.00449 -45.639736)
			(xy 294.995423 -45.682457) (xy 294.970051 -45.766028) (xy 294.936612 -45.84671) (xy 294.895425 -45.923726)
			(xy 294.846889 -45.996335) (xy 294.79147 -46.063838) (xy 294.729702 -46.125584) (xy 294.66218 -46.180979)
			(xy 294.589554 -46.229489) (xy 294.512523 -46.270648) (xy 294.431829 -46.304058) (xy 294.348248 -46.3294)
			(xy 294.262587 -46.346427) (xy 294.175669 -46.354977) (xy 294.132 -46.355508) (xy 294.090898 -46.355033)
			(xy 294.009043 -46.347448) (xy 293.928238 -46.332343) (xy 293.849171 -46.309847) (xy 293.772517 -46.280151)
			(xy 293.69893 -46.243509) (xy 293.629038 -46.200234) (xy 293.563437 -46.150694) (xy 293.502687 -46.095313)
			(xy 293.447306 -46.034563) (xy 293.397766 -45.968962) (xy 293.354491 -45.89907) (xy 293.317849 -45.825483)
			(xy 293.288153 -45.748829) (xy 293.265657 -45.669762) (xy 293.250552 -45.588957) (xy 293.242967 -45.507102)
			(xy 293.242492 -45.466) (xy 293.242987 -45.423046) (xy 293.251252 -45.337536) (xy 293.267725 -45.253222)
			(xy 293.292251 -45.170889) (xy 293.324602 -45.091305) (xy 293.364476 -45.015211) (xy 293.411503 -44.943317)
			(xy 293.465243 -44.876293) (xy 293.525197 -44.814764) (xy 293.590803 -44.759303) (xy 293.661453 -44.710426)
			(xy 293.736486 -44.668591) (xy 293.775638 -44.650914) (xy 293.783674 -44.646948) (xy 293.796551 -44.634501)
			(xy 293.804365 -44.618386) (xy 293.80561 -44.609512) (xy 293.810549 -44.566203) (xy 293.827823 -44.48076)
			(xy 293.853371 -44.397415) (xy 293.886947 -44.316968) (xy 293.928229 -44.240191) (xy 293.976821 -44.167818)
			(xy 294.032259 -44.100545) (xy 294.094009 -44.039015) (xy 294.161481 -43.98382) (xy 294.234027 -43.935487)
			(xy 294.310952 -43.89448) (xy 294.391519 -43.861193) (xy 294.474954 -43.835944) (xy 294.560459 -43.818976)
			(xy 294.647214 -43.810451) (xy 294.6908 -43.80992) (xy 294.72807 -43.810301) (xy 294.802353 -43.816489)
			(xy 294.875858 -43.828865) (xy 294.948072 -43.84734) (xy 294.983408 -43.859196) (xy 294.991804 -43.861751)
			(xy 295.009341 -43.861622) (xy 295.017698 -43.858942) (xy 295.054748 -43.845723) (xy 295.130664 -43.825091)
			(xy 295.208104 -43.811237) (xy 295.286465 -43.80427) (xy 295.3258 -43.803824) (xy 295.366912 -43.804252)
			(xy 295.448784 -43.811841) (xy 295.529606 -43.826952) (xy 295.608689 -43.849458) (xy 295.685358 -43.879166)
			(xy 295.758958 -43.915823) (xy 295.82886 -43.959116) (xy 295.894469 -44.008675) (xy 295.955224 -44.064078)
			(xy 296.010607 -44.124851) (xy 296.060146 -44.190476) (xy 296.103416 -44.260392) (xy 296.140049 -44.334004)
			(xy 296.169733 -44.410682) (xy 296.192213 -44.489772) (xy 296.207299 -44.5706) (xy 296.214861 -44.652474)
			(xy 296.215308 -44.693586) (xy 296.214781 -44.738929) (xy 296.205621 -44.829149) (xy 296.19702 -44.873672)
			(xy 296.194226 -44.88688) (xy 296.202354 -44.91228) (xy 296.28592 -44.989496) (xy 296.311574 -44.995592)
			(xy 296.324528 -44.992036) (xy 296.364572 -44.981036) (xy 296.446183 -44.965647) (xy 296.528875 -44.957947)
			(xy 296.5704 -44.957492) (xy 296.611502 -44.957967) (xy 296.693357 -44.965552) (xy 296.774162 -44.980657)
			(xy 296.853229 -45.003153) (xy 296.929883 -45.032849) (xy 297.00347 -45.069491) (xy 297.073362 -45.112766)
			(xy 297.138963 -45.162306) (xy 297.199713 -45.217687) (xy 297.255094 -45.278437) (xy 297.304634 -45.344038)
			(xy 297.347909 -45.41393) (xy 297.384551 -45.487517) (xy 297.414247 -45.564171) (xy 297.436743 -45.643238)
			(xy 297.451848 -45.724043) (xy 297.459433 -45.805898) (xy 297.459908 -45.847) (xy 297.459411 -45.889308)
			(xy 297.451408 -45.973544) (xy 297.435447 -46.05664) (xy 297.41167 -46.137846) (xy 297.380294 -46.216429)
			(xy 297.341601 -46.291679) (xy 297.319192 -46.327568) (xy 297.314312 -46.335958) (xy 297.310644 -46.355)
			(xy 297.314312 -46.374042) (xy 297.319192 -46.382432) (xy 297.341624 -46.418309) (xy 297.380335 -46.493554)
			(xy 297.411721 -46.572137) (xy 297.421175 -46.604428) (xy 297.75277 -46.604428) (xy 297.75277 -38.218364)
			(xy 297.753266 -38.185103) (xy 297.761957 -38.119151) (xy 297.779187 -38.054899) (xy 297.804659 -37.993446)
			(xy 297.837938 -37.935847) (xy 297.878453 -37.883086) (xy 297.901614 -37.859208) (xy 298.15155 -37.609272)
			(xy 298.17542 -37.586104) (xy 298.228185 -37.545595) (xy 298.285787 -37.512323) (xy 298.347241 -37.486857)
			(xy 298.411494 -37.469634) (xy 298.477445 -37.460949) (xy 298.510706 -37.460428) (xy 302.50257 -37.460428)
			(xy 302.535829 -37.460978) (xy 302.601778 -37.469661) (xy 302.666029 -37.48688) (xy 302.727481 -37.512342)
			(xy 302.785082 -37.545611) (xy 302.837846 -37.586116) (xy 302.861726 -37.609272) (xy 303.217326 -37.964872)
			(xy 303.240504 -37.988733) (xy 303.281012 -38.041499) (xy 303.314283 -38.099104) (xy 303.339747 -38.160559)
			(xy 303.356968 -38.224814) (xy 303.365651 -38.290767) (xy 303.36617 -38.324028) (xy 303.36617 -44.390144)
			(xy 307.777633 -44.390144) (xy 307.777633 -44.219788) (xy 307.785618 -44.04962) (xy 307.80157 -43.880013)
			(xy 307.825455 -43.711341) (xy 307.857219 -43.543973) (xy 307.896794 -43.378278) (xy 307.944091 -43.21462)
			(xy 307.999008 -43.053359) (xy 308.061423 -42.894849) (xy 308.131199 -42.739439) (xy 308.208182 -42.587471)
			(xy 308.292204 -42.439277) (xy 308.38308 -42.295185) (xy 308.48061 -42.155511) (xy 308.58458 -42.020562)
			(xy 308.694761 -41.890634) (xy 308.81091 -41.766014) (xy 308.932774 -41.646975) (xy 309.060082 -41.533779)
			(xy 309.192557 -41.426674) (xy 309.329907 -41.325897) (xy 309.471829 -41.231668) (xy 309.618011 -41.144195)
			(xy 309.768134 -41.06367) (xy 309.921865 -40.99027) (xy 310.078868 -40.924156) (xy 310.238798 -40.865474)
			(xy 310.401302 -40.814353) (xy 310.566023 -40.770905) (xy 310.732601 -40.735226) (xy 310.900667 -40.707394)
			(xy 311.069853 -40.68747) (xy 311.239787 -40.675498) (xy 311.410096 -40.671505) (xy 311.580405 -40.675498)
			(xy 311.750339 -40.68747) (xy 311.919525 -40.707394) (xy 312.087591 -40.735226) (xy 312.254169 -40.770905)
			(xy 312.41889 -40.814353) (xy 312.581394 -40.865474) (xy 312.741324 -40.924156) (xy 312.898327 -40.99027)
			(xy 313.052058 -41.06367) (xy 313.202181 -41.144195) (xy 313.348363 -41.231668) (xy 313.490285 -41.325897)
			(xy 313.627635 -41.426674) (xy 313.76011 -41.533779) (xy 313.887418 -41.646975) (xy 314.009282 -41.766014)
			(xy 314.125431 -41.890634) (xy 314.235612 -42.020562) (xy 314.339582 -42.155511) (xy 314.437112 -42.295185)
			(xy 314.527988 -42.439277) (xy 314.61201 -42.587471) (xy 314.688993 -42.739439) (xy 314.758769 -42.894849)
			(xy 314.821184 -43.053359) (xy 314.876101 -43.21462) (xy 314.923398 -43.378278) (xy 314.962973 -43.543973)
			(xy 314.994737 -43.711341) (xy 315.018622 -43.880013) (xy 315.034574 -44.04962) (xy 315.042559 -44.219788)
			(xy 315.043058 -44.304966) (xy 315.042559 -44.390144) (xy 315.034574 -44.560312) (xy 315.018622 -44.729919)
			(xy 314.994737 -44.898591) (xy 314.962973 -45.065959) (xy 314.923398 -45.231654) (xy 314.876101 -45.395312)
			(xy 314.821184 -45.556573) (xy 314.758769 -45.715083) (xy 314.688993 -45.870493) (xy 314.61201 -46.022461)
			(xy 314.527988 -46.170655) (xy 314.437112 -46.314747) (xy 314.339582 -46.454421) (xy 314.235612 -46.58937)
			(xy 314.125431 -46.719298) (xy 314.009282 -46.843918) (xy 313.887418 -46.962957) (xy 313.76011 -47.076153)
			(xy 313.627635 -47.183258) (xy 313.490285 -47.284035) (xy 313.348363 -47.378264) (xy 313.202181 -47.465737)
			(xy 313.052058 -47.546262) (xy 312.898327 -47.619662) (xy 312.741324 -47.685776) (xy 312.581394 -47.744458)
			(xy 312.41889 -47.795579) (xy 312.254169 -47.839027) (xy 312.087591 -47.874706) (xy 311.919525 -47.902538)
			(xy 311.750339 -47.922462) (xy 311.580405 -47.934434) (xy 311.410096 -47.938428) (xy 311.239787 -47.934434)
			(xy 311.069853 -47.922462) (xy 310.900667 -47.902538) (xy 310.732601 -47.874706) (xy 310.566023 -47.839027)
			(xy 310.401302 -47.795579) (xy 310.238798 -47.744458) (xy 310.078868 -47.685776) (xy 309.921865 -47.619662)
			(xy 309.768134 -47.546262) (xy 309.618011 -47.465737) (xy 309.471829 -47.378264) (xy 309.329907 -47.284035)
			(xy 309.192557 -47.183258) (xy 309.060082 -47.076153) (xy 308.932774 -46.962957) (xy 308.81091 -46.843918)
			(xy 308.694761 -46.719298) (xy 308.58458 -46.58937) (xy 308.48061 -46.454421) (xy 308.38308 -46.314747)
			(xy 308.292204 -46.170655) (xy 308.208182 -46.022461) (xy 308.131199 -45.870493) (xy 308.061423 -45.715083)
			(xy 307.999008 -45.556573) (xy 307.944091 -45.395312) (xy 307.896794 -45.231654) (xy 307.857219 -45.065959)
			(xy 307.825455 -44.898591) (xy 307.80157 -44.729919) (xy 307.785618 -44.560312) (xy 307.777633 -44.390144)
			(xy 303.36617 -44.390144) (xy 303.36617 -46.579028) (xy 303.365657 -46.612288) (xy 303.356968 -46.678239)
			(xy 303.339741 -46.742491) (xy 303.314272 -46.803943) (xy 303.280996 -46.861543) (xy 303.240485 -46.914305)
			(xy 303.217326 -46.938184) (xy 302.810926 -47.344584) (xy 302.787059 -47.367755) (xy 302.734295 -47.408265)
			(xy 302.676692 -47.441538) (xy 302.615237 -47.467003) (xy 302.550984 -47.484225) (xy 302.485031 -47.492909)
			(xy 302.45177 -47.493428) (xy 298.64177 -47.493428) (xy 298.608509 -47.492929) (xy 298.542557 -47.484238)
			(xy 298.478305 -47.467009) (xy 298.416853 -47.441538) (xy 298.359253 -47.40826) (xy 298.306492 -47.367744)
			(xy 298.282614 -47.344584) (xy 297.901614 -46.963584) (xy 297.87847 -46.939691) (xy 297.837957 -46.886933)
			(xy 297.804681 -46.829335) (xy 297.779211 -46.767886) (xy 297.761983 -46.703636) (xy 297.753293 -46.637687)
			(xy 297.75277 -46.604428) (xy 297.421175 -46.604428) (xy 297.435497 -46.653347) (xy 297.45145 -46.736449)
			(xy 297.459434 -46.82069) (xy 297.459908 -46.863) (xy 297.459446 -46.903899) (xy 297.451939 -46.985353)
			(xy 297.436989 -47.065774) (xy 297.414721 -47.144483) (xy 297.385324 -47.220817) (xy 297.349046 -47.29413)
			(xy 297.306193 -47.363806) (xy 297.257126 -47.429254) (xy 297.230038 -47.4599) (xy 297.222926 -47.467774)
			(xy 297.216068 -47.488094) (xy 297.225212 -47.584106) (xy 297.235626 -47.602648) (xy 297.244262 -47.609252)
			(xy 297.255779 -47.618387) (xy 297.274571 -47.640984) (xy 297.287678 -47.667291) (xy 297.294399 -47.695902)
			(xy 297.294808 -47.710598) (xy 297.294808 -50.488088) (xy 297.294361 -50.503716) (xy 297.286791 -50.534038)
			(xy 297.279822 -50.548032) (xy 297.273472 -50.55997) (xy 297.274234 -50.586386) (xy 297.325796 -50.672746)
			(xy 297.330639 -50.680054) (xy 297.344223 -50.69112) (xy 297.360724 -50.697012) (xy 297.369484 -50.697384)
			(xy 301.995332 -50.697384) (xy 302.028593 -50.697878) (xy 302.094545 -50.70657) (xy 302.158798 -50.723799)
			(xy 302.22025 -50.749271) (xy 302.27785 -50.782551) (xy 302.33061 -50.823067) (xy 302.354488 -50.846228)
			(xy 306.810156 -55.301896) (xy 306.833333 -55.325758) (xy 306.873843 -55.378523) (xy 306.907116 -55.436126)
			(xy 306.932581 -55.497582) (xy 306.949801 -55.561837) (xy 306.958482 -55.627791) (xy 306.959 -55.661052)
			(xy 306.959 -72.879966) (xy 310.009801 -72.879966) (xy 310.013811 -72.774063) (xy 310.025819 -72.668767)
			(xy 310.045756 -72.564681) (xy 310.073508 -72.462401) (xy 310.108916 -72.362512) (xy 310.151777 -72.265588)
			(xy 310.201845 -72.172182) (xy 310.258835 -72.082831) (xy 310.322418 -71.998045) (xy 310.392232 -71.918311)
			(xy 310.467876 -71.844086) (xy 310.548916 -71.775793) (xy 310.63489 -71.713826) (xy 310.725304 -71.658538)
			(xy 310.81964 -71.610246) (xy 310.917359 -71.569227) (xy 311.017899 -71.535716) (xy 311.120687 -71.509904)
			(xy 311.225131 -71.49194) (xy 311.330636 -71.481927) (xy 311.436595 -71.479921) (xy 311.542403 -71.485935)
			(xy 311.647453 -71.499934) (xy 311.751143 -71.521837) (xy 311.85288 -71.55152) (xy 311.952081 -71.588811)
			(xy 312.048177 -71.633499) (xy 312.140618 -71.685326) (xy 312.228875 -71.743996) (xy 312.312442 -71.809173)
			(xy 312.390841 -71.880483) (xy 312.463622 -71.957517) (xy 312.530368 -72.039836) (xy 312.590698 -72.126967)
			(xy 312.644265 -72.218411) (xy 312.690763 -72.313644) (xy 312.729925 -72.412121) (xy 312.761528 -72.513278)
			(xy 312.785389 -72.616536) (xy 312.801374 -72.721302) (xy 312.809389 -72.826977) (xy 312.80989 -72.879966)
			(xy 312.809389 -72.932955) (xy 312.801374 -73.03863) (xy 312.785389 -73.143396) (xy 312.761528 -73.246654)
			(xy 312.729925 -73.347811) (xy 312.690763 -73.446288) (xy 312.644265 -73.541521) (xy 312.590698 -73.632965)
			(xy 312.530368 -73.720096) (xy 312.463622 -73.802415) (xy 312.390841 -73.879449) (xy 312.312442 -73.950759)
			(xy 312.228875 -74.015936) (xy 312.140618 -74.074606) (xy 312.048177 -74.126433) (xy 311.952081 -74.171121)
			(xy 311.85288 -74.208412) (xy 311.751143 -74.238095) (xy 311.647453 -74.259998) (xy 311.542403 -74.273997)
			(xy 311.436595 -74.280011) (xy 311.330636 -74.278005) (xy 311.225131 -74.267992) (xy 311.120687 -74.250028)
			(xy 311.017899 -74.224216) (xy 310.917359 -74.190705) (xy 310.81964 -74.149686) (xy 310.725304 -74.101394)
			(xy 310.63489 -74.046106) (xy 310.548916 -73.984139) (xy 310.467876 -73.915846) (xy 310.392232 -73.841621)
			(xy 310.322418 -73.761887) (xy 310.258835 -73.677101) (xy 310.201845 -73.58775) (xy 310.151777 -73.494344)
			(xy 310.108916 -73.39742) (xy 310.073508 -73.297531) (xy 310.045756 -73.195251) (xy 310.025819 -73.091165)
			(xy 310.013811 -72.985869) (xy 310.009801 -72.879966) (xy 306.959 -72.879966) (xy 306.959 -73.377806)
			(xy 306.959396 -73.387879) (xy 306.967134 -73.406478) (xy 306.973986 -73.413874) (xy 308.856126 -75.296014)
			(xy 308.863521 -75.30286) (xy 308.882124 -75.310576) (xy 308.892194 -75.311) (xy 319.8876 -75.311)
			(xy 319.920859 -75.311539) (xy 319.986809 -75.320225) (xy 320.05106 -75.337447) (xy 320.112511 -75.362911)
			(xy 320.170112 -75.396182) (xy 320.222876 -75.436688) (xy 320.246756 -75.459844) (xy 321.288156 -76.501244)
			(xy 321.311308 -76.525129) (xy 321.351821 -76.577889) (xy 321.385097 -76.635488) (xy 321.410566 -76.696939)
			(xy 321.427791 -76.76119) (xy 321.436479 -76.82714) (xy 321.437 -76.8604) (xy 321.437 -120.904) (xy 321.436461 -120.937259)
			(xy 321.427775 -121.003209) (xy 321.410553 -121.06746) (xy 321.385089 -121.128911) (xy 321.351818 -121.186512)
			(xy 321.311312 -121.239276) (xy 321.288156 -121.263156) (xy 319.992756 -122.558556) (xy 319.968871 -122.581708)
			(xy 319.916111 -122.622221) (xy 319.858512 -122.655497) (xy 319.797061 -122.680966) (xy 319.73281 -122.698191)
			(xy 319.66686 -122.706879) (xy 319.6336 -122.7074) (xy 304.015394 -122.7074) (xy 304.005321 -122.707796)
			(xy 303.986722 -122.715534) (xy 303.979326 -122.722386) (xy 300.28642 -126.415292) (xy 300.279594 -126.422703)
			(xy 300.271865 -126.441294) (xy 300.271434 -126.45136) (xy 300.271434 -131.730496) (xy 300.270911 -131.763756)
			(xy 300.262225 -131.829707) (xy 300.245001 -131.893959) (xy 300.219534 -131.955411) (xy 300.18626 -132.013011)
			(xy 300.145749 -132.065773) (xy 300.12259 -132.089652) (xy 298.892722 -133.31952) (xy 298.868863 -133.3427)
			(xy 298.816096 -133.383208) (xy 298.758492 -133.416478) (xy 298.697036 -133.441942) (xy 298.632781 -133.459163)
			(xy 298.566827 -133.467845) (xy 298.533566 -133.468364) (xy 279.565862 -133.468364) (xy 279.532601 -133.46786)
			(xy 279.46665 -133.459168) (xy 279.402398 -133.44194) (xy 279.340946 -133.416469) (xy 279.283346 -133.383193)
			(xy 279.230585 -133.342679) (xy 279.206706 -133.31952) (xy 277.840694 -131.953508) (xy 277.81751 -131.929653)
			(xy 277.777002 -131.876886) (xy 277.743731 -131.81928) (xy 277.718269 -131.757823) (xy 277.701049 -131.693568)
			(xy 277.692368 -131.627614) (xy 277.69185 -131.594352) (xy 235.451388 -131.594352) (xy 235.454232 -131.603278)
			(xy 235.472912 -131.692826) (xy 235.482304 -131.783818) (xy 235.482892 -131.829556) (xy 235.482406 -131.870659)
			(xy 235.474825 -131.952514) (xy 235.459723 -132.033321) (xy 235.437229 -132.11239) (xy 235.407535 -132.189045)
			(xy 235.370895 -132.262634) (xy 235.327621 -132.332528) (xy 235.278083 -132.39813) (xy 235.222702 -132.458882)
			(xy 235.161952 -132.514265) (xy 235.096351 -132.563805) (xy 235.026458 -132.607082) (xy 234.952871 -132.643724)
			(xy 234.876216 -132.67342) (xy 234.797148 -132.695916) (xy 234.716342 -132.711021) (xy 234.634487 -132.718605)
			(xy 234.593384 -132.719064) (xy 234.546988 -132.718491) (xy 234.454699 -132.708843) (xy 234.363916 -132.689645)
			(xy 234.275622 -132.661103) (xy 234.232958 -132.642864) (xy 234.223016 -132.639058) (xy 234.201752 -132.639058)
			(xy 234.19181 -132.642864) (xy 234.149149 -132.661111) (xy 234.060856 -132.689655) (xy 233.970071 -132.708848)
			(xy 233.87778 -132.71848) (xy 233.831384 -132.719064) (xy 233.784988 -132.718491) (xy 233.692699 -132.708843)
			(xy 233.601916 -132.689645) (xy 233.513622 -132.661103) (xy 233.470958 -132.642864) (xy 233.461016 -132.639058)
			(xy 233.439752 -132.639058) (xy 233.42981 -132.642864) (xy 233.387149 -132.661111) (xy 233.298856 -132.689655)
			(xy 233.208071 -132.708848) (xy 233.11578 -132.71848) (xy 233.069384 -132.719064) (xy 233.026817 -132.718594)
			(xy 232.942069 -132.710485) (xy 232.858485 -132.694314) (xy 232.776829 -132.670229) (xy 232.737152 -132.654802)
			(xy 232.7279 -132.651549) (xy 232.708304 -132.651549) (xy 232.699052 -132.654802) (xy 232.65938 -132.670239)
			(xy 232.57772 -132.694311) (xy 232.494134 -132.710474) (xy 232.409387 -132.718579) (xy 232.36682 -132.719064)
			(xy 232.320424 -132.718478) (xy 232.228136 -132.708834) (xy 232.137352 -132.689639) (xy 232.049059 -132.661102)
			(xy 232.006394 -132.642864) (xy 231.996452 -132.639058) (xy 231.975188 -132.639058) (xy 231.965246 -132.642864)
			(xy 231.92258 -132.661099) (xy 231.834289 -132.689647) (xy 231.743505 -132.708842) (xy 231.651216 -132.718478)
			(xy 231.60482 -132.719064) (xy 231.563716 -132.718629) (xy 231.481858 -132.711045) (xy 231.401049 -132.69594)
			(xy 231.321979 -132.673444) (xy 231.245322 -132.643747) (xy 231.171732 -132.607104) (xy 231.101838 -132.563827)
			(xy 231.036234 -132.514285) (xy 230.975482 -132.458901) (xy 230.9201 -132.398147) (xy 230.87056 -132.332543)
			(xy 230.827284 -132.262647) (xy 230.790643 -132.189056) (xy 230.760949 -132.112398) (xy 230.738454 -132.033327)
			(xy 230.723352 -131.952518) (xy 230.71577 -131.87066) (xy 230.715312 -131.829556) (xy 230.715787 -131.788047)
			(xy 230.723505 -131.705388) (xy 230.7389 -131.62381) (xy 230.761835 -131.544023) (xy 230.776526 -131.505198)
			(xy 230.779706 -131.495702) (xy 230.779312 -131.475701) (xy 230.775764 -131.466336) (xy 230.758025 -131.424174)
			(xy 230.730254 -131.337015) (xy 230.711574 -131.247467) (xy 230.702183 -131.156474) (xy 230.701596 -131.110736)
			(xy 217.770454 -131.110736) (xy 217.796935 -131.192665) (xy 217.816124 -131.283452) (xy 217.825753 -131.375743)
			(xy 217.826336 -131.42214) (xy 217.82573 -131.468535) (xy 217.816091 -131.560823) (xy 217.796902 -131.651606)
			(xy 217.76837 -131.739901) (xy 217.750136 -131.782566) (xy 217.746305 -131.792501) (xy 217.746321 -131.813772)
			(xy 217.750136 -131.823714) (xy 217.768396 -131.86637) (xy 217.796935 -131.954665) (xy 217.816124 -132.045452)
			(xy 217.825753 -132.137743) (xy 217.826336 -132.18414) (xy 217.82573 -132.230535) (xy 217.816091 -132.322823)
			(xy 217.796902 -132.413606) (xy 217.76837 -132.501901) (xy 217.750136 -132.544566) (xy 217.746305 -132.554501)
			(xy 217.746321 -132.575772) (xy 217.750136 -132.585714) (xy 217.768396 -132.62837) (xy 217.796935 -132.716665)
			(xy 217.816124 -132.807452) (xy 217.825753 -132.899743) (xy 217.826336 -132.94614) (xy 217.825872 -132.987242)
			(xy 217.818283 -133.069096) (xy 217.803175 -133.1499) (xy 217.780677 -133.228966) (xy 217.750979 -133.305619)
			(xy 217.714335 -133.379205) (xy 217.671059 -133.449096) (xy 217.621519 -133.514696) (xy 217.566137 -133.575446)
			(xy 217.505387 -133.630826) (xy 217.439786 -133.680366) (xy 217.369894 -133.723641) (xy 217.296308 -133.760284)
			(xy 217.219655 -133.78998) (xy 217.140589 -133.812478) (xy 217.059784 -133.827585) (xy 216.97793 -133.835172)
			(xy 216.936828 -133.835648) (xy 216.890433 -133.83506) (xy 216.798144 -133.825417) (xy 216.70736 -133.806223)
			(xy 216.619067 -133.777686) (xy 216.576402 -133.759448) (xy 216.56646 -133.755642) (xy 216.545196 -133.755642)
			(xy 216.535254 -133.759448) (xy 216.492589 -133.777686) (xy 216.404298 -133.806231) (xy 216.313513 -133.825426)
			(xy 216.221224 -133.835062) (xy 216.174828 -133.835648) (xy 216.131404 -133.835154) (xy 216.044966 -133.826739)
			(xy 215.959761 -133.809928) (xy 215.876604 -133.784881) (xy 215.836246 -133.768846) (xy 215.826836 -133.765374)
			(xy 215.806794 -133.765374) (xy 215.797384 -133.768846) (xy 215.757016 -133.78485) (xy 215.673856 -133.809876)
			(xy 215.588656 -133.826689) (xy 215.502224 -133.835131) (xy 215.458802 -133.835648) (xy 215.412406 -133.835069)
			(xy 215.320118 -133.825424) (xy 215.229334 -133.806227) (xy 215.141041 -133.777687) (xy 215.098376 -133.759448)
			(xy 215.088434 -133.755642) (xy 215.06717 -133.755642) (xy 215.057228 -133.759448) (xy 215.014567 -133.777695)
			(xy 214.926274 -133.806238) (xy 214.835489 -133.82543) (xy 214.743198 -133.835063) (xy 214.696802 -133.835648)
			(xy 214.655331 -133.835195) (xy 214.572745 -133.827514) (xy 214.491233 -133.812181) (xy 214.411501 -133.78933)
			(xy 214.372698 -133.774688) (xy 214.363204 -133.771495) (xy 214.343199 -133.771892) (xy 214.333836 -133.77545)
			(xy 214.291673 -133.793169) (xy 214.204503 -133.820863) (xy 214.114954 -133.839474) (xy 214.023968 -133.848804)
			(xy 213.978236 -133.849364) (xy 213.937132 -133.848913) (xy 213.855275 -133.841331) (xy 213.774466 -133.826228)
			(xy 213.695396 -133.803733) (xy 213.618739 -133.774037) (xy 213.54515 -133.737395) (xy 213.475255 -133.694119)
			(xy 213.409651 -133.644578) (xy 213.348899 -133.589195) (xy 213.293517 -133.528442) (xy 213.243976 -133.462839)
			(xy 213.200701 -133.392943) (xy 213.164059 -133.319353) (xy 213.134365 -133.242696) (xy 213.11187 -133.163626)
			(xy 213.096768 -133.082817) (xy 213.089186 -133.00096) (xy 213.088728 -132.959856) (xy 0.509016 -132.959856)
			(xy 0.509016 -136.959232) (xy 40.624242 -136.959232) (xy 40.624242 -136.852768) (xy 40.632198 -136.746601)
			(xy 40.648065 -136.641325) (xy 40.671756 -136.53753) (xy 40.703137 -136.435795) (xy 40.742033 -136.33669)
			(xy 40.788226 -136.240768) (xy 40.841459 -136.148567) (xy 40.901432 -136.060602) (xy 40.967812 -135.977365)
			(xy 41.040226 -135.89932) (xy 41.118271 -135.826906) (xy 41.201508 -135.760526) (xy 41.289473 -135.700553)
			(xy 41.381674 -135.64732) (xy 41.477596 -135.601127) (xy 41.576701 -135.562231) (xy 41.678436 -135.53085)
			(xy 41.782231 -135.507159) (xy 41.887507 -135.491292) (xy 41.993674 -135.483336) (xy 42.100138 -135.483336)
			(xy 42.206305 -135.491292) (xy 42.311581 -135.507159) (xy 42.415376 -135.53085) (xy 42.517111 -135.562231)
			(xy 42.616216 -135.601127) (xy 42.712138 -135.64732) (xy 42.804339 -135.700553) (xy 42.892304 -135.760526)
			(xy 42.975541 -135.826906) (xy 43.053586 -135.89932) (xy 43.126 -135.977365) (xy 43.19238 -136.060602)
			(xy 43.252353 -136.148567) (xy 43.305586 -136.240768) (xy 43.351779 -136.33669) (xy 43.390675 -136.435795)
			(xy 43.422056 -136.53753) (xy 43.445747 -136.641325) (xy 43.461614 -136.746601) (xy 43.46957 -136.852768)
			(xy 43.470068 -136.906) (xy 43.46957 -136.959232) (xy 52.816242 -136.959232) (xy 52.816242 -136.852768)
			(xy 52.824198 -136.746601) (xy 52.840065 -136.641325) (xy 52.863756 -136.53753) (xy 52.895137 -136.435795)
			(xy 52.934033 -136.33669) (xy 52.980226 -136.240768) (xy 53.033459 -136.148567) (xy 53.093432 -136.060602)
			(xy 53.159812 -135.977365) (xy 53.232226 -135.89932) (xy 53.310271 -135.826906) (xy 53.393508 -135.760526)
			(xy 53.481473 -135.700553) (xy 53.573674 -135.64732) (xy 53.669596 -135.601127) (xy 53.768701 -135.562231)
			(xy 53.870436 -135.53085) (xy 53.974231 -135.507159) (xy 54.079507 -135.491292) (xy 54.185674 -135.483336)
			(xy 54.292138 -135.483336) (xy 54.398305 -135.491292) (xy 54.503581 -135.507159) (xy 54.607376 -135.53085)
			(xy 54.709111 -135.562231) (xy 54.808216 -135.601127) (xy 54.904138 -135.64732) (xy 54.996339 -135.700553)
			(xy 55.084304 -135.760526) (xy 55.167541 -135.826906) (xy 55.245586 -135.89932) (xy 55.318 -135.977365)
			(xy 55.38438 -136.060602) (xy 55.444353 -136.148567) (xy 55.497586 -136.240768) (xy 55.543779 -136.33669)
			(xy 55.582675 -136.435795) (xy 55.614056 -136.53753) (xy 55.637747 -136.641325) (xy 55.653614 -136.746601)
			(xy 55.66157 -136.852768) (xy 55.662068 -136.906) (xy 55.66157 -136.959232) (xy 65.008242 -136.959232)
			(xy 65.008242 -136.852768) (xy 65.016198 -136.746601) (xy 65.032065 -136.641325) (xy 65.055756 -136.53753)
			(xy 65.087137 -136.435795) (xy 65.126033 -136.33669) (xy 65.172226 -136.240768) (xy 65.225459 -136.148567)
			(xy 65.285432 -136.060602) (xy 65.351812 -135.977365) (xy 65.424226 -135.89932) (xy 65.502271 -135.826906)
			(xy 65.585508 -135.760526) (xy 65.673473 -135.700553) (xy 65.765674 -135.64732) (xy 65.861596 -135.601127)
			(xy 65.960701 -135.562231) (xy 66.062436 -135.53085) (xy 66.166231 -135.507159) (xy 66.271507 -135.491292)
			(xy 66.377674 -135.483336) (xy 66.484138 -135.483336) (xy 66.590305 -135.491292) (xy 66.695581 -135.507159)
			(xy 66.799376 -135.53085) (xy 66.901111 -135.562231) (xy 67.000216 -135.601127) (xy 67.096138 -135.64732)
			(xy 67.188339 -135.700553) (xy 67.276304 -135.760526) (xy 67.359541 -135.826906) (xy 67.437586 -135.89932)
			(xy 67.51 -135.977365) (xy 67.57638 -136.060602) (xy 67.636353 -136.148567) (xy 67.689586 -136.240768)
			(xy 67.735779 -136.33669) (xy 67.774675 -136.435795) (xy 67.806056 -136.53753) (xy 67.829747 -136.641325)
			(xy 67.845614 -136.746601) (xy 67.85357 -136.852768) (xy 67.854068 -136.906) (xy 67.85357 -136.959232)
			(xy 80.624162 -136.959232) (xy 80.624162 -136.852768) (xy 80.632118 -136.746601) (xy 80.647985 -136.641325)
			(xy 80.671676 -136.53753) (xy 80.703057 -136.435795) (xy 80.741953 -136.33669) (xy 80.788146 -136.240768)
			(xy 80.841379 -136.148567) (xy 80.901352 -136.060602) (xy 80.967732 -135.977365) (xy 81.040146 -135.89932)
			(xy 81.118191 -135.826906) (xy 81.201428 -135.760526) (xy 81.289393 -135.700553) (xy 81.381594 -135.64732)
			(xy 81.477516 -135.601127) (xy 81.576621 -135.562231) (xy 81.678356 -135.53085) (xy 81.782151 -135.507159)
			(xy 81.887427 -135.491292) (xy 81.993594 -135.483336) (xy 82.100058 -135.483336) (xy 82.206225 -135.491292)
			(xy 82.311501 -135.507159) (xy 82.415296 -135.53085) (xy 82.517031 -135.562231) (xy 82.616136 -135.601127)
			(xy 82.712058 -135.64732) (xy 82.804259 -135.700553) (xy 82.892224 -135.760526) (xy 82.975461 -135.826906)
			(xy 83.053506 -135.89932) (xy 83.12592 -135.977365) (xy 83.1923 -136.060602) (xy 83.252273 -136.148567)
			(xy 83.305506 -136.240768) (xy 83.351699 -136.33669) (xy 83.390595 -136.435795) (xy 83.421976 -136.53753)
			(xy 83.445667 -136.641325) (xy 83.461534 -136.746601) (xy 83.46949 -136.852768) (xy 83.469988 -136.906)
			(xy 83.46949 -136.959232) (xy 92.816162 -136.959232) (xy 92.816162 -136.852768) (xy 92.824118 -136.746601)
			(xy 92.839985 -136.641325) (xy 92.863676 -136.53753) (xy 92.895057 -136.435795) (xy 92.933953 -136.33669)
			(xy 92.980146 -136.240768) (xy 93.033379 -136.148567) (xy 93.093352 -136.060602) (xy 93.159732 -135.977365)
			(xy 93.232146 -135.89932) (xy 93.310191 -135.826906) (xy 93.393428 -135.760526) (xy 93.481393 -135.700553)
			(xy 93.573594 -135.64732) (xy 93.669516 -135.601127) (xy 93.768621 -135.562231) (xy 93.870356 -135.53085)
			(xy 93.974151 -135.507159) (xy 94.079427 -135.491292) (xy 94.185594 -135.483336) (xy 94.292058 -135.483336)
			(xy 94.398225 -135.491292) (xy 94.503501 -135.507159) (xy 94.607296 -135.53085) (xy 94.709031 -135.562231)
			(xy 94.808136 -135.601127) (xy 94.904058 -135.64732) (xy 94.996259 -135.700553) (xy 95.084224 -135.760526)
			(xy 95.167461 -135.826906) (xy 95.245506 -135.89932) (xy 95.31792 -135.977365) (xy 95.3843 -136.060602)
			(xy 95.444273 -136.148567) (xy 95.497506 -136.240768) (xy 95.543699 -136.33669) (xy 95.582595 -136.435795)
			(xy 95.613976 -136.53753) (xy 95.637667 -136.641325) (xy 95.653534 -136.746601) (xy 95.66149 -136.852768)
			(xy 95.661988 -136.906) (xy 95.66149 -136.959232) (xy 105.008162 -136.959232) (xy 105.008162 -136.852768)
			(xy 105.016118 -136.746601) (xy 105.031985 -136.641325) (xy 105.055676 -136.53753) (xy 105.087057 -136.435795)
			(xy 105.125953 -136.33669) (xy 105.172146 -136.240768) (xy 105.225379 -136.148567) (xy 105.285352 -136.060602)
			(xy 105.351732 -135.977365) (xy 105.424146 -135.89932) (xy 105.502191 -135.826906) (xy 105.585428 -135.760526)
			(xy 105.673393 -135.700553) (xy 105.765594 -135.64732) (xy 105.861516 -135.601127) (xy 105.960621 -135.562231)
			(xy 106.062356 -135.53085) (xy 106.166151 -135.507159) (xy 106.271427 -135.491292) (xy 106.377594 -135.483336)
			(xy 106.484058 -135.483336) (xy 106.590225 -135.491292) (xy 106.695501 -135.507159) (xy 106.799296 -135.53085)
			(xy 106.901031 -135.562231) (xy 107.000136 -135.601127) (xy 107.096058 -135.64732) (xy 107.188259 -135.700553)
			(xy 107.276224 -135.760526) (xy 107.359461 -135.826906) (xy 107.437506 -135.89932) (xy 107.50992 -135.977365)
			(xy 107.5763 -136.060602) (xy 107.636273 -136.148567) (xy 107.689506 -136.240768) (xy 107.735699 -136.33669)
			(xy 107.774595 -136.435795) (xy 107.805976 -136.53753) (xy 107.829667 -136.641325) (xy 107.845534 -136.746601)
			(xy 107.85349 -136.852768) (xy 107.853988 -136.906) (xy 107.85349 -136.959232) (xy 120.624336 -136.959232)
			(xy 120.624336 -136.852768) (xy 120.632292 -136.746601) (xy 120.648159 -136.641325) (xy 120.67185 -136.53753)
			(xy 120.703231 -136.435795) (xy 120.742127 -136.33669) (xy 120.78832 -136.240768) (xy 120.841553 -136.148567)
			(xy 120.901526 -136.060602) (xy 120.967906 -135.977365) (xy 121.04032 -135.89932) (xy 121.118365 -135.826906)
			(xy 121.201602 -135.760526) (xy 121.289567 -135.700553) (xy 121.381768 -135.64732) (xy 121.47769 -135.601127)
			(xy 121.576795 -135.562231) (xy 121.67853 -135.53085) (xy 121.782325 -135.507159) (xy 121.887601 -135.491292)
			(xy 121.993768 -135.483336) (xy 122.100232 -135.483336) (xy 122.206399 -135.491292) (xy 122.311675 -135.507159)
			(xy 122.41547 -135.53085) (xy 122.517205 -135.562231) (xy 122.61631 -135.601127) (xy 122.712232 -135.64732)
			(xy 122.804433 -135.700553) (xy 122.892398 -135.760526) (xy 122.975635 -135.826906) (xy 123.05368 -135.89932)
			(xy 123.126094 -135.977365) (xy 123.192474 -136.060602) (xy 123.252447 -136.148567) (xy 123.30568 -136.240768)
			(xy 123.351873 -136.33669) (xy 123.390769 -136.435795) (xy 123.42215 -136.53753) (xy 123.445841 -136.641325)
			(xy 123.461708 -136.746601) (xy 123.469664 -136.852768) (xy 123.470162 -136.906) (xy 123.469664 -136.959232)
			(xy 132.816336 -136.959232) (xy 132.816336 -136.852768) (xy 132.824292 -136.746601) (xy 132.840159 -136.641325)
			(xy 132.86385 -136.53753) (xy 132.895231 -136.435795) (xy 132.934127 -136.33669) (xy 132.98032 -136.240768)
			(xy 133.033553 -136.148567) (xy 133.093526 -136.060602) (xy 133.159906 -135.977365) (xy 133.23232 -135.89932)
			(xy 133.310365 -135.826906) (xy 133.393602 -135.760526) (xy 133.481567 -135.700553) (xy 133.573768 -135.64732)
			(xy 133.66969 -135.601127) (xy 133.768795 -135.562231) (xy 133.87053 -135.53085) (xy 133.974325 -135.507159)
			(xy 134.079601 -135.491292) (xy 134.185768 -135.483336) (xy 134.292232 -135.483336) (xy 134.398399 -135.491292)
			(xy 134.503675 -135.507159) (xy 134.60747 -135.53085) (xy 134.709205 -135.562231) (xy 134.80831 -135.601127)
			(xy 134.904232 -135.64732) (xy 134.996433 -135.700553) (xy 135.084398 -135.760526) (xy 135.167635 -135.826906)
			(xy 135.24568 -135.89932) (xy 135.318094 -135.977365) (xy 135.384474 -136.060602) (xy 135.444447 -136.148567)
			(xy 135.49768 -136.240768) (xy 135.543873 -136.33669) (xy 135.582769 -136.435795) (xy 135.61415 -136.53753)
			(xy 135.637841 -136.641325) (xy 135.653708 -136.746601) (xy 135.661664 -136.852768) (xy 135.662162 -136.906)
			(xy 135.661664 -136.959232) (xy 145.008336 -136.959232) (xy 145.008336 -136.852768) (xy 145.016292 -136.746601)
			(xy 145.032159 -136.641325) (xy 145.05585 -136.53753) (xy 145.087231 -136.435795) (xy 145.126127 -136.33669)
			(xy 145.17232 -136.240768) (xy 145.225553 -136.148567) (xy 145.285526 -136.060602) (xy 145.351906 -135.977365)
			(xy 145.42432 -135.89932) (xy 145.502365 -135.826906) (xy 145.585602 -135.760526) (xy 145.673567 -135.700553)
			(xy 145.765768 -135.64732) (xy 145.86169 -135.601127) (xy 145.960795 -135.562231) (xy 146.06253 -135.53085)
			(xy 146.166325 -135.507159) (xy 146.271601 -135.491292) (xy 146.377768 -135.483336) (xy 146.484232 -135.483336)
			(xy 146.590399 -135.491292) (xy 146.695675 -135.507159) (xy 146.79947 -135.53085) (xy 146.901205 -135.562231)
			(xy 147.00031 -135.601127) (xy 147.096232 -135.64732) (xy 147.188433 -135.700553) (xy 147.276398 -135.760526)
			(xy 147.359635 -135.826906) (xy 147.43768 -135.89932) (xy 147.510094 -135.977365) (xy 147.576474 -136.060602)
			(xy 147.636447 -136.148567) (xy 147.68968 -136.240768) (xy 147.735873 -136.33669) (xy 147.774769 -136.435795)
			(xy 147.80615 -136.53753) (xy 147.829841 -136.641325) (xy 147.845708 -136.746601) (xy 147.853664 -136.852768)
			(xy 147.854162 -136.906) (xy 147.853664 -136.959232) (xy 160.62451 -136.959232) (xy 160.62451 -136.852768)
			(xy 160.632466 -136.746601) (xy 160.648333 -136.641325) (xy 160.672024 -136.53753) (xy 160.703405 -136.435795)
			(xy 160.742301 -136.33669) (xy 160.788494 -136.240768) (xy 160.841727 -136.148567) (xy 160.9017 -136.060602)
			(xy 160.96808 -135.977365) (xy 161.040494 -135.89932) (xy 161.118539 -135.826906) (xy 161.201776 -135.760526)
			(xy 161.289741 -135.700553) (xy 161.381942 -135.64732) (xy 161.477864 -135.601127) (xy 161.576969 -135.562231)
			(xy 161.678704 -135.53085) (xy 161.782499 -135.507159) (xy 161.887775 -135.491292) (xy 161.993942 -135.483336)
			(xy 162.100406 -135.483336) (xy 162.206573 -135.491292) (xy 162.311849 -135.507159) (xy 162.415644 -135.53085)
			(xy 162.517379 -135.562231) (xy 162.616484 -135.601127) (xy 162.712406 -135.64732) (xy 162.804607 -135.700553)
			(xy 162.892572 -135.760526) (xy 162.975809 -135.826906) (xy 163.053854 -135.89932) (xy 163.126268 -135.977365)
			(xy 163.192648 -136.060602) (xy 163.252621 -136.148567) (xy 163.305854 -136.240768) (xy 163.352047 -136.33669)
			(xy 163.390943 -136.435795) (xy 163.422324 -136.53753) (xy 163.446015 -136.641325) (xy 163.461882 -136.746601)
			(xy 163.469838 -136.852768) (xy 163.470336 -136.906) (xy 163.469838 -136.959232) (xy 172.81651 -136.959232)
			(xy 172.81651 -136.852768) (xy 172.824466 -136.746601) (xy 172.840333 -136.641325) (xy 172.864024 -136.53753)
			(xy 172.895405 -136.435795) (xy 172.934301 -136.33669) (xy 172.980494 -136.240768) (xy 173.033727 -136.148567)
			(xy 173.0937 -136.060602) (xy 173.16008 -135.977365) (xy 173.232494 -135.89932) (xy 173.310539 -135.826906)
			(xy 173.393776 -135.760526) (xy 173.481741 -135.700553) (xy 173.573942 -135.64732) (xy 173.669864 -135.601127)
			(xy 173.768969 -135.562231) (xy 173.870704 -135.53085) (xy 173.974499 -135.507159) (xy 174.079775 -135.491292)
			(xy 174.185942 -135.483336) (xy 174.292406 -135.483336) (xy 174.398573 -135.491292) (xy 174.503849 -135.507159)
			(xy 174.607644 -135.53085) (xy 174.709379 -135.562231) (xy 174.808484 -135.601127) (xy 174.904406 -135.64732)
			(xy 174.996607 -135.700553) (xy 175.084572 -135.760526) (xy 175.167809 -135.826906) (xy 175.245854 -135.89932)
			(xy 175.318268 -135.977365) (xy 175.384648 -136.060602) (xy 175.444621 -136.148567) (xy 175.497854 -136.240768)
			(xy 175.544047 -136.33669) (xy 175.582943 -136.435795) (xy 175.614324 -136.53753) (xy 175.638015 -136.641325)
			(xy 175.653882 -136.746601) (xy 175.661838 -136.852768) (xy 175.662336 -136.906) (xy 175.661838 -136.959232)
			(xy 185.00851 -136.959232) (xy 185.00851 -136.852768) (xy 185.016466 -136.746601) (xy 185.032333 -136.641325)
			(xy 185.056024 -136.53753) (xy 185.087405 -136.435795) (xy 185.126301 -136.33669) (xy 185.172494 -136.240768)
			(xy 185.225727 -136.148567) (xy 185.2857 -136.060602) (xy 185.35208 -135.977365) (xy 185.424494 -135.89932)
			(xy 185.502539 -135.826906) (xy 185.585776 -135.760526) (xy 185.673741 -135.700553) (xy 185.765942 -135.64732)
			(xy 185.861864 -135.601127) (xy 185.960969 -135.562231) (xy 186.062704 -135.53085) (xy 186.166499 -135.507159)
			(xy 186.271775 -135.491292) (xy 186.377942 -135.483336) (xy 186.484406 -135.483336) (xy 186.590573 -135.491292)
			(xy 186.695849 -135.507159) (xy 186.799644 -135.53085) (xy 186.901379 -135.562231) (xy 187.000484 -135.601127)
			(xy 187.096406 -135.64732) (xy 187.188607 -135.700553) (xy 187.276572 -135.760526) (xy 187.359809 -135.826906)
			(xy 187.437854 -135.89932) (xy 187.510268 -135.977365) (xy 187.576648 -136.060602) (xy 187.636621 -136.148567)
			(xy 187.689854 -136.240768) (xy 187.736047 -136.33669) (xy 187.774943 -136.435795) (xy 187.806324 -136.53753)
			(xy 187.830015 -136.641325) (xy 187.845882 -136.746601) (xy 187.853838 -136.852768) (xy 187.854336 -136.906)
			(xy 187.853838 -136.959232) (xy 187.845882 -137.065399) (xy 187.830015 -137.170675) (xy 187.806324 -137.27447)
			(xy 187.774943 -137.376205) (xy 187.736047 -137.47531) (xy 187.689854 -137.571232) (xy 187.636621 -137.663433)
			(xy 187.576648 -137.751398) (xy 187.510268 -137.834635) (xy 187.437854 -137.91268) (xy 187.359809 -137.985094)
			(xy 187.276572 -138.051474) (xy 187.188607 -138.111447) (xy 187.096406 -138.16468) (xy 187.000484 -138.210873)
			(xy 186.901379 -138.249769) (xy 186.799644 -138.28115) (xy 186.695849 -138.304841) (xy 186.590573 -138.320708)
			(xy 186.484406 -138.328664) (xy 186.377942 -138.328664) (xy 186.271775 -138.320708) (xy 186.166499 -138.304841)
			(xy 186.062704 -138.28115) (xy 185.960969 -138.249769) (xy 185.861864 -138.210873) (xy 185.765942 -138.16468)
			(xy 185.673741 -138.111447) (xy 185.585776 -138.051474) (xy 185.502539 -137.985094) (xy 185.424494 -137.91268)
			(xy 185.35208 -137.834635) (xy 185.2857 -137.751398) (xy 185.225727 -137.663433) (xy 185.172494 -137.571232)
			(xy 185.126301 -137.47531) (xy 185.087405 -137.376205) (xy 185.056024 -137.27447) (xy 185.032333 -137.170675)
			(xy 185.016466 -137.065399) (xy 185.00851 -136.959232) (xy 175.661838 -136.959232) (xy 175.653882 -137.065399)
			(xy 175.638015 -137.170675) (xy 175.614324 -137.27447) (xy 175.582943 -137.376205) (xy 175.544047 -137.47531)
			(xy 175.497854 -137.571232) (xy 175.444621 -137.663433) (xy 175.384648 -137.751398) (xy 175.318268 -137.834635)
			(xy 175.245854 -137.91268) (xy 175.167809 -137.985094) (xy 175.084572 -138.051474) (xy 174.996607 -138.111447)
			(xy 174.904406 -138.16468) (xy 174.808484 -138.210873) (xy 174.709379 -138.249769) (xy 174.607644 -138.28115)
			(xy 174.503849 -138.304841) (xy 174.398573 -138.320708) (xy 174.292406 -138.328664) (xy 174.185942 -138.328664)
			(xy 174.079775 -138.320708) (xy 173.974499 -138.304841) (xy 173.870704 -138.28115) (xy 173.768969 -138.249769)
			(xy 173.669864 -138.210873) (xy 173.573942 -138.16468) (xy 173.481741 -138.111447) (xy 173.393776 -138.051474)
			(xy 173.310539 -137.985094) (xy 173.232494 -137.91268) (xy 173.16008 -137.834635) (xy 173.0937 -137.751398)
			(xy 173.033727 -137.663433) (xy 172.980494 -137.571232) (xy 172.934301 -137.47531) (xy 172.895405 -137.376205)
			(xy 172.864024 -137.27447) (xy 172.840333 -137.170675) (xy 172.824466 -137.065399) (xy 172.81651 -136.959232)
			(xy 163.469838 -136.959232) (xy 163.461882 -137.065399) (xy 163.446015 -137.170675) (xy 163.422324 -137.27447)
			(xy 163.390943 -137.376205) (xy 163.352047 -137.47531) (xy 163.305854 -137.571232) (xy 163.252621 -137.663433)
			(xy 163.192648 -137.751398) (xy 163.126268 -137.834635) (xy 163.053854 -137.91268) (xy 162.975809 -137.985094)
			(xy 162.892572 -138.051474) (xy 162.804607 -138.111447) (xy 162.712406 -138.16468) (xy 162.616484 -138.210873)
			(xy 162.517379 -138.249769) (xy 162.415644 -138.28115) (xy 162.311849 -138.304841) (xy 162.206573 -138.320708)
			(xy 162.100406 -138.328664) (xy 161.993942 -138.328664) (xy 161.887775 -138.320708) (xy 161.782499 -138.304841)
			(xy 161.678704 -138.28115) (xy 161.576969 -138.249769) (xy 161.477864 -138.210873) (xy 161.381942 -138.16468)
			(xy 161.289741 -138.111447) (xy 161.201776 -138.051474) (xy 161.118539 -137.985094) (xy 161.040494 -137.91268)
			(xy 160.96808 -137.834635) (xy 160.9017 -137.751398) (xy 160.841727 -137.663433) (xy 160.788494 -137.571232)
			(xy 160.742301 -137.47531) (xy 160.703405 -137.376205) (xy 160.672024 -137.27447) (xy 160.648333 -137.170675)
			(xy 160.632466 -137.065399) (xy 160.62451 -136.959232) (xy 147.853664 -136.959232) (xy 147.845708 -137.065399)
			(xy 147.829841 -137.170675) (xy 147.80615 -137.27447) (xy 147.774769 -137.376205) (xy 147.735873 -137.47531)
			(xy 147.68968 -137.571232) (xy 147.636447 -137.663433) (xy 147.576474 -137.751398) (xy 147.510094 -137.834635)
			(xy 147.43768 -137.91268) (xy 147.359635 -137.985094) (xy 147.276398 -138.051474) (xy 147.188433 -138.111447)
			(xy 147.096232 -138.16468) (xy 147.00031 -138.210873) (xy 146.901205 -138.249769) (xy 146.79947 -138.28115)
			(xy 146.695675 -138.304841) (xy 146.590399 -138.320708) (xy 146.484232 -138.328664) (xy 146.377768 -138.328664)
			(xy 146.271601 -138.320708) (xy 146.166325 -138.304841) (xy 146.06253 -138.28115) (xy 145.960795 -138.249769)
			(xy 145.86169 -138.210873) (xy 145.765768 -138.16468) (xy 145.673567 -138.111447) (xy 145.585602 -138.051474)
			(xy 145.502365 -137.985094) (xy 145.42432 -137.91268) (xy 145.351906 -137.834635) (xy 145.285526 -137.751398)
			(xy 145.225553 -137.663433) (xy 145.17232 -137.571232) (xy 145.126127 -137.47531) (xy 145.087231 -137.376205)
			(xy 145.05585 -137.27447) (xy 145.032159 -137.170675) (xy 145.016292 -137.065399) (xy 145.008336 -136.959232)
			(xy 135.661664 -136.959232) (xy 135.653708 -137.065399) (xy 135.637841 -137.170675) (xy 135.61415 -137.27447)
			(xy 135.582769 -137.376205) (xy 135.543873 -137.47531) (xy 135.49768 -137.571232) (xy 135.444447 -137.663433)
			(xy 135.384474 -137.751398) (xy 135.318094 -137.834635) (xy 135.24568 -137.91268) (xy 135.167635 -137.985094)
			(xy 135.084398 -138.051474) (xy 134.996433 -138.111447) (xy 134.904232 -138.16468) (xy 134.80831 -138.210873)
			(xy 134.709205 -138.249769) (xy 134.60747 -138.28115) (xy 134.503675 -138.304841) (xy 134.398399 -138.320708)
			(xy 134.292232 -138.328664) (xy 134.185768 -138.328664) (xy 134.079601 -138.320708) (xy 133.974325 -138.304841)
			(xy 133.87053 -138.28115) (xy 133.768795 -138.249769) (xy 133.66969 -138.210873) (xy 133.573768 -138.16468)
			(xy 133.481567 -138.111447) (xy 133.393602 -138.051474) (xy 133.310365 -137.985094) (xy 133.23232 -137.91268)
			(xy 133.159906 -137.834635) (xy 133.093526 -137.751398) (xy 133.033553 -137.663433) (xy 132.98032 -137.571232)
			(xy 132.934127 -137.47531) (xy 132.895231 -137.376205) (xy 132.86385 -137.27447) (xy 132.840159 -137.170675)
			(xy 132.824292 -137.065399) (xy 132.816336 -136.959232) (xy 123.469664 -136.959232) (xy 123.461708 -137.065399)
			(xy 123.445841 -137.170675) (xy 123.42215 -137.27447) (xy 123.390769 -137.376205) (xy 123.351873 -137.47531)
			(xy 123.30568 -137.571232) (xy 123.252447 -137.663433) (xy 123.192474 -137.751398) (xy 123.126094 -137.834635)
			(xy 123.05368 -137.91268) (xy 122.975635 -137.985094) (xy 122.892398 -138.051474) (xy 122.804433 -138.111447)
			(xy 122.712232 -138.16468) (xy 122.61631 -138.210873) (xy 122.517205 -138.249769) (xy 122.41547 -138.28115)
			(xy 122.311675 -138.304841) (xy 122.206399 -138.320708) (xy 122.100232 -138.328664) (xy 121.993768 -138.328664)
			(xy 121.887601 -138.320708) (xy 121.782325 -138.304841) (xy 121.67853 -138.28115) (xy 121.576795 -138.249769)
			(xy 121.47769 -138.210873) (xy 121.381768 -138.16468) (xy 121.289567 -138.111447) (xy 121.201602 -138.051474)
			(xy 121.118365 -137.985094) (xy 121.04032 -137.91268) (xy 120.967906 -137.834635) (xy 120.901526 -137.751398)
			(xy 120.841553 -137.663433) (xy 120.78832 -137.571232) (xy 120.742127 -137.47531) (xy 120.703231 -137.376205)
			(xy 120.67185 -137.27447) (xy 120.648159 -137.170675) (xy 120.632292 -137.065399) (xy 120.624336 -136.959232)
			(xy 107.85349 -136.959232) (xy 107.845534 -137.065399) (xy 107.829667 -137.170675) (xy 107.805976 -137.27447)
			(xy 107.774595 -137.376205) (xy 107.735699 -137.47531) (xy 107.689506 -137.571232) (xy 107.636273 -137.663433)
			(xy 107.5763 -137.751398) (xy 107.50992 -137.834635) (xy 107.437506 -137.91268) (xy 107.359461 -137.985094)
			(xy 107.276224 -138.051474) (xy 107.188259 -138.111447) (xy 107.096058 -138.16468) (xy 107.000136 -138.210873)
			(xy 106.901031 -138.249769) (xy 106.799296 -138.28115) (xy 106.695501 -138.304841) (xy 106.590225 -138.320708)
			(xy 106.484058 -138.328664) (xy 106.377594 -138.328664) (xy 106.271427 -138.320708) (xy 106.166151 -138.304841)
			(xy 106.062356 -138.28115) (xy 105.960621 -138.249769) (xy 105.861516 -138.210873) (xy 105.765594 -138.16468)
			(xy 105.673393 -138.111447) (xy 105.585428 -138.051474) (xy 105.502191 -137.985094) (xy 105.424146 -137.91268)
			(xy 105.351732 -137.834635) (xy 105.285352 -137.751398) (xy 105.225379 -137.663433) (xy 105.172146 -137.571232)
			(xy 105.125953 -137.47531) (xy 105.087057 -137.376205) (xy 105.055676 -137.27447) (xy 105.031985 -137.170675)
			(xy 105.016118 -137.065399) (xy 105.008162 -136.959232) (xy 95.66149 -136.959232) (xy 95.653534 -137.065399)
			(xy 95.637667 -137.170675) (xy 95.613976 -137.27447) (xy 95.582595 -137.376205) (xy 95.543699 -137.47531)
			(xy 95.497506 -137.571232) (xy 95.444273 -137.663433) (xy 95.3843 -137.751398) (xy 95.31792 -137.834635)
			(xy 95.245506 -137.91268) (xy 95.167461 -137.985094) (xy 95.084224 -138.051474) (xy 94.996259 -138.111447)
			(xy 94.904058 -138.16468) (xy 94.808136 -138.210873) (xy 94.709031 -138.249769) (xy 94.607296 -138.28115)
			(xy 94.503501 -138.304841) (xy 94.398225 -138.320708) (xy 94.292058 -138.328664) (xy 94.185594 -138.328664)
			(xy 94.079427 -138.320708) (xy 93.974151 -138.304841) (xy 93.870356 -138.28115) (xy 93.768621 -138.249769)
			(xy 93.669516 -138.210873) (xy 93.573594 -138.16468) (xy 93.481393 -138.111447) (xy 93.393428 -138.051474)
			(xy 93.310191 -137.985094) (xy 93.232146 -137.91268) (xy 93.159732 -137.834635) (xy 93.093352 -137.751398)
			(xy 93.033379 -137.663433) (xy 92.980146 -137.571232) (xy 92.933953 -137.47531) (xy 92.895057 -137.376205)
			(xy 92.863676 -137.27447) (xy 92.839985 -137.170675) (xy 92.824118 -137.065399) (xy 92.816162 -136.959232)
			(xy 83.46949 -136.959232) (xy 83.461534 -137.065399) (xy 83.445667 -137.170675) (xy 83.421976 -137.27447)
			(xy 83.390595 -137.376205) (xy 83.351699 -137.47531) (xy 83.305506 -137.571232) (xy 83.252273 -137.663433)
			(xy 83.1923 -137.751398) (xy 83.12592 -137.834635) (xy 83.053506 -137.91268) (xy 82.975461 -137.985094)
			(xy 82.892224 -138.051474) (xy 82.804259 -138.111447) (xy 82.712058 -138.16468) (xy 82.616136 -138.210873)
			(xy 82.517031 -138.249769) (xy 82.415296 -138.28115) (xy 82.311501 -138.304841) (xy 82.206225 -138.320708)
			(xy 82.100058 -138.328664) (xy 81.993594 -138.328664) (xy 81.887427 -138.320708) (xy 81.782151 -138.304841)
			(xy 81.678356 -138.28115) (xy 81.576621 -138.249769) (xy 81.477516 -138.210873) (xy 81.381594 -138.16468)
			(xy 81.289393 -138.111447) (xy 81.201428 -138.051474) (xy 81.118191 -137.985094) (xy 81.040146 -137.91268)
			(xy 80.967732 -137.834635) (xy 80.901352 -137.751398) (xy 80.841379 -137.663433) (xy 80.788146 -137.571232)
			(xy 80.741953 -137.47531) (xy 80.703057 -137.376205) (xy 80.671676 -137.27447) (xy 80.647985 -137.170675)
			(xy 80.632118 -137.065399) (xy 80.624162 -136.959232) (xy 67.85357 -136.959232) (xy 67.845614 -137.065399)
			(xy 67.829747 -137.170675) (xy 67.806056 -137.27447) (xy 67.774675 -137.376205) (xy 67.735779 -137.47531)
			(xy 67.689586 -137.571232) (xy 67.636353 -137.663433) (xy 67.57638 -137.751398) (xy 67.51 -137.834635)
			(xy 67.437586 -137.91268) (xy 67.359541 -137.985094) (xy 67.276304 -138.051474) (xy 67.188339 -138.111447)
			(xy 67.096138 -138.16468) (xy 67.000216 -138.210873) (xy 66.901111 -138.249769) (xy 66.799376 -138.28115)
			(xy 66.695581 -138.304841) (xy 66.590305 -138.320708) (xy 66.484138 -138.328664) (xy 66.377674 -138.328664)
			(xy 66.271507 -138.320708) (xy 66.166231 -138.304841) (xy 66.062436 -138.28115) (xy 65.960701 -138.249769)
			(xy 65.861596 -138.210873) (xy 65.765674 -138.16468) (xy 65.673473 -138.111447) (xy 65.585508 -138.051474)
			(xy 65.502271 -137.985094) (xy 65.424226 -137.91268) (xy 65.351812 -137.834635) (xy 65.285432 -137.751398)
			(xy 65.225459 -137.663433) (xy 65.172226 -137.571232) (xy 65.126033 -137.47531) (xy 65.087137 -137.376205)
			(xy 65.055756 -137.27447) (xy 65.032065 -137.170675) (xy 65.016198 -137.065399) (xy 65.008242 -136.959232)
			(xy 55.66157 -136.959232) (xy 55.653614 -137.065399) (xy 55.637747 -137.170675) (xy 55.614056 -137.27447)
			(xy 55.582675 -137.376205) (xy 55.543779 -137.47531) (xy 55.497586 -137.571232) (xy 55.444353 -137.663433)
			(xy 55.38438 -137.751398) (xy 55.318 -137.834635) (xy 55.245586 -137.91268) (xy 55.167541 -137.985094)
			(xy 55.084304 -138.051474) (xy 54.996339 -138.111447) (xy 54.904138 -138.16468) (xy 54.808216 -138.210873)
			(xy 54.709111 -138.249769) (xy 54.607376 -138.28115) (xy 54.503581 -138.304841) (xy 54.398305 -138.320708)
			(xy 54.292138 -138.328664) (xy 54.185674 -138.328664) (xy 54.079507 -138.320708) (xy 53.974231 -138.304841)
			(xy 53.870436 -138.28115) (xy 53.768701 -138.249769) (xy 53.669596 -138.210873) (xy 53.573674 -138.16468)
			(xy 53.481473 -138.111447) (xy 53.393508 -138.051474) (xy 53.310271 -137.985094) (xy 53.232226 -137.91268)
			(xy 53.159812 -137.834635) (xy 53.093432 -137.751398) (xy 53.033459 -137.663433) (xy 52.980226 -137.571232)
			(xy 52.934033 -137.47531) (xy 52.895137 -137.376205) (xy 52.863756 -137.27447) (xy 52.840065 -137.170675)
			(xy 52.824198 -137.065399) (xy 52.816242 -136.959232) (xy 43.46957 -136.959232) (xy 43.461614 -137.065399)
			(xy 43.445747 -137.170675) (xy 43.422056 -137.27447) (xy 43.390675 -137.376205) (xy 43.351779 -137.47531)
			(xy 43.305586 -137.571232) (xy 43.252353 -137.663433) (xy 43.19238 -137.751398) (xy 43.126 -137.834635)
			(xy 43.053586 -137.91268) (xy 42.975541 -137.985094) (xy 42.892304 -138.051474) (xy 42.804339 -138.111447)
			(xy 42.712138 -138.16468) (xy 42.616216 -138.210873) (xy 42.517111 -138.249769) (xy 42.415376 -138.28115)
			(xy 42.311581 -138.304841) (xy 42.206305 -138.320708) (xy 42.100138 -138.328664) (xy 41.993674 -138.328664)
			(xy 41.887507 -138.320708) (xy 41.782231 -138.304841) (xy 41.678436 -138.28115) (xy 41.576701 -138.249769)
			(xy 41.477596 -138.210873) (xy 41.381674 -138.16468) (xy 41.289473 -138.111447) (xy 41.201508 -138.051474)
			(xy 41.118271 -137.985094) (xy 41.040226 -137.91268) (xy 40.967812 -137.834635) (xy 40.901432 -137.751398)
			(xy 40.841459 -137.663433) (xy 40.788226 -137.571232) (xy 40.742033 -137.47531) (xy 40.703137 -137.376205)
			(xy 40.671756 -137.27447) (xy 40.648065 -137.170675) (xy 40.632198 -137.065399) (xy 40.624242 -136.959232)
			(xy 0.509016 -136.959232) (xy 0.509016 -141.95405) (xy 220.791775 -141.95405) (xy 220.791775 -141.82491)
			(xy 220.799725 -141.696015) (xy 220.815595 -141.567855) (xy 220.839324 -141.440914) (xy 220.870823 -141.315675)
			(xy 220.909972 -141.192612) (xy 220.956623 -141.072193) (xy 221.010598 -140.954874) (xy 221.071693 -140.8411)
			(xy 221.139676 -140.731303) (xy 221.21429 -140.6259) (xy 221.295251 -140.52529) (xy 221.382251 -140.429855)
			(xy 221.474962 -140.339956) (xy 221.573032 -140.255935) (xy 221.676087 -140.178111) (xy 221.783738 -140.106779)
			(xy 221.895577 -140.042209) (xy 222.011178 -139.984647) (xy 222.130103 -139.93431) (xy 222.251902 -139.89139)
			(xy 222.376112 -139.856049) (xy 222.502261 -139.828422) (xy 222.629873 -139.808613) (xy 222.758462 -139.796697)
			(xy 222.88754 -139.792721) (xy 223.016618 -139.796697) (xy 223.145207 -139.808613) (xy 223.272819 -139.828422)
			(xy 223.398968 -139.856049) (xy 223.523178 -139.89139) (xy 223.644977 -139.93431) (xy 223.763902 -139.984647)
			(xy 223.879503 -140.042209) (xy 223.991342 -140.106779) (xy 224.098993 -140.178111) (xy 224.202048 -140.255935)
			(xy 224.300118 -140.339956) (xy 224.392829 -140.429855) (xy 224.422133 -140.462) (xy 270.001492 -140.462)
			(xy 270.002075 -140.415604) (xy 270.01172 -140.323316) (xy 270.030916 -140.232532) (xy 270.059454 -140.144239)
			(xy 270.077692 -140.101574) (xy 270.081498 -140.091632) (xy 270.081498 -140.070368) (xy 270.077692 -140.060426)
			(xy 270.059447 -140.017764) (xy 270.030903 -139.929471) (xy 270.01171 -139.838686) (xy 270.002077 -139.746396)
			(xy 270.001492 -139.7) (xy 270.002075 -139.653604) (xy 270.01172 -139.561316) (xy 270.030916 -139.470532)
			(xy 270.059454 -139.382239) (xy 270.077692 -139.339574) (xy 270.081498 -139.329632) (xy 270.081498 -139.308368)
			(xy 270.077692 -139.298426) (xy 270.059447 -139.255764) (xy 270.030903 -139.167471) (xy 270.01171 -139.076686)
			(xy 270.002077 -138.984396) (xy 270.001492 -138.938) (xy 270.002075 -138.891604) (xy 270.01172 -138.799316)
			(xy 270.030916 -138.708532) (xy 270.059454 -138.620239) (xy 270.077692 -138.577574) (xy 270.081498 -138.567632)
			(xy 270.081498 -138.546368) (xy 270.077692 -138.536426) (xy 270.059447 -138.493764) (xy 270.030903 -138.405471)
			(xy 270.01171 -138.314686) (xy 270.002077 -138.222396) (xy 270.001492 -138.176) (xy 270.002075 -138.129604)
			(xy 270.01172 -138.037316) (xy 270.030916 -137.946532) (xy 270.059454 -137.858239) (xy 270.077692 -137.815574)
			(xy 270.081498 -137.805632) (xy 270.081498 -137.784368) (xy 270.077692 -137.774426) (xy 270.059447 -137.731764)
			(xy 270.030903 -137.643471) (xy 270.01171 -137.552686) (xy 270.002077 -137.460396) (xy 270.001492 -137.414)
			(xy 270.002075 -137.367604) (xy 270.01172 -137.275316) (xy 270.030916 -137.184532) (xy 270.059454 -137.096239)
			(xy 270.077692 -137.053574) (xy 270.081498 -137.043632) (xy 270.081498 -137.022368) (xy 270.077692 -137.012426)
			(xy 270.059447 -136.969764) (xy 270.030903 -136.881471) (xy 270.01171 -136.790686) (xy 270.002077 -136.698396)
			(xy 270.001492 -136.652) (xy 270.001967 -136.610898) (xy 270.009552 -136.529043) (xy 270.024657 -136.448238)
			(xy 270.047153 -136.369171) (xy 270.076849 -136.292517) (xy 270.113491 -136.21893) (xy 270.156766 -136.149038)
			(xy 270.206306 -136.083437) (xy 270.261687 -136.022687) (xy 270.322437 -135.967306) (xy 270.388038 -135.917766)
			(xy 270.45793 -135.874491) (xy 270.531517 -135.837849) (xy 270.608171 -135.808153) (xy 270.687238 -135.785657)
			(xy 270.768043 -135.770552) (xy 270.849898 -135.762967) (xy 270.891 -135.762492) (xy 270.937396 -135.763075)
			(xy 271.029684 -135.77272) (xy 271.120468 -135.791916) (xy 271.208761 -135.820454) (xy 271.251426 -135.838692)
			(xy 271.261368 -135.842498) (xy 271.282632 -135.842498) (xy 271.292574 -135.838692) (xy 271.335236 -135.820447)
			(xy 271.423529 -135.791903) (xy 271.514314 -135.77271) (xy 271.606604 -135.763077) (xy 271.653 -135.762492)
			(xy 271.694102 -135.762967) (xy 271.775957 -135.770552) (xy 271.856762 -135.785657) (xy 271.935829 -135.808153)
			(xy 272.012483 -135.837849) (xy 272.08607 -135.874491) (xy 272.155962 -135.917766) (xy 272.221563 -135.967306)
			(xy 272.282313 -136.022687) (xy 272.337694 -136.083437) (xy 272.387234 -136.149038) (xy 272.430509 -136.21893)
			(xy 272.467151 -136.292517) (xy 272.496847 -136.369171) (xy 272.519343 -136.448238) (xy 272.534448 -136.529043)
			(xy 272.542033 -136.610898) (xy 272.542508 -136.652) (xy 272.541925 -136.698396) (xy 272.53228 -136.790684)
			(xy 272.513084 -136.881468) (xy 272.484546 -136.969761) (xy 272.466308 -137.012426) (xy 272.462502 -137.022368)
			(xy 272.462502 -137.043632) (xy 272.466308 -137.053574) (xy 272.484553 -137.096236) (xy 272.513097 -137.184529)
			(xy 272.53229 -137.275314) (xy 272.541923 -137.367604) (xy 272.542508 -137.414) (xy 272.541925 -137.460396)
			(xy 272.53228 -137.552684) (xy 272.513084 -137.643468) (xy 272.484546 -137.731761) (xy 272.466308 -137.774426)
			(xy 272.462502 -137.784368) (xy 272.462502 -137.805632) (xy 272.466308 -137.815574) (xy 272.484553 -137.858236)
			(xy 272.513097 -137.946529) (xy 272.53229 -138.037314) (xy 272.541923 -138.129604) (xy 272.542508 -138.176)
			(xy 272.541925 -138.222396) (xy 272.53228 -138.314684) (xy 272.513084 -138.405468) (xy 272.484546 -138.493761)
			(xy 272.466308 -138.536426) (xy 272.462502 -138.546368) (xy 272.462502 -138.567632) (xy 272.466308 -138.577574)
			(xy 272.484553 -138.620236) (xy 272.513097 -138.708529) (xy 272.53229 -138.799314) (xy 272.541923 -138.891604)
			(xy 272.542508 -138.938) (xy 272.541925 -138.984396) (xy 272.53228 -139.076684) (xy 272.513084 -139.167468)
			(xy 272.484546 -139.255761) (xy 272.466308 -139.298426) (xy 272.462502 -139.308368) (xy 272.462502 -139.329632)
			(xy 272.466308 -139.339574) (xy 272.484553 -139.382236) (xy 272.513097 -139.470529) (xy 272.53229 -139.561314)
			(xy 272.541923 -139.653604) (xy 272.542508 -139.7) (xy 272.541925 -139.746396) (xy 272.53228 -139.838684)
			(xy 272.513084 -139.929468) (xy 272.484546 -140.017761) (xy 272.466308 -140.060426) (xy 272.462502 -140.070368)
			(xy 272.462502 -140.091632) (xy 272.466308 -140.101574) (xy 272.484553 -140.144236) (xy 272.513097 -140.232529)
			(xy 272.53229 -140.323314) (xy 272.541923 -140.415604) (xy 272.542508 -140.462) (xy 272.542033 -140.503102)
			(xy 272.534448 -140.584957) (xy 272.519343 -140.665762) (xy 272.496847 -140.744829) (xy 272.467151 -140.821483)
			(xy 272.430509 -140.89507) (xy 272.387234 -140.964962) (xy 272.337694 -141.030563) (xy 272.282313 -141.091313)
			(xy 272.221563 -141.146694) (xy 272.155962 -141.196234) (xy 272.08607 -141.239509) (xy 272.012483 -141.276151)
			(xy 271.935829 -141.305847) (xy 271.856762 -141.328343) (xy 271.775957 -141.343448) (xy 271.694102 -141.351033)
			(xy 271.653 -141.351508) (xy 271.606604 -141.350925) (xy 271.514316 -141.34128) (xy 271.423532 -141.322084)
			(xy 271.335239 -141.293546) (xy 271.292574 -141.275308) (xy 271.282632 -141.271502) (xy 271.261368 -141.271502)
			(xy 271.251426 -141.275308) (xy 271.208764 -141.293553) (xy 271.120471 -141.322097) (xy 271.029686 -141.34129)
			(xy 270.937396 -141.350923) (xy 270.891 -141.351508) (xy 270.849898 -141.351033) (xy 270.768043 -141.343448)
			(xy 270.687238 -141.328343) (xy 270.608171 -141.305847) (xy 270.531517 -141.276151) (xy 270.45793 -141.239509)
			(xy 270.388038 -141.196234) (xy 270.322437 -141.146694) (xy 270.261687 -141.091313) (xy 270.206306 -141.030563)
			(xy 270.156766 -140.964962) (xy 270.113491 -140.89507) (xy 270.076849 -140.821483) (xy 270.047153 -140.744829)
			(xy 270.024657 -140.665762) (xy 270.009552 -140.584957) (xy 270.001967 -140.503102) (xy 270.001492 -140.462)
			(xy 224.422133 -140.462) (xy 224.479829 -140.52529) (xy 224.56079 -140.6259) (xy 224.635404 -140.731303)
			(xy 224.703387 -140.8411) (xy 224.764482 -140.954874) (xy 224.818457 -141.072193) (xy 224.865108 -141.192612)
			(xy 224.904257 -141.315675) (xy 224.935756 -141.440914) (xy 224.959485 -141.567855) (xy 224.975355 -141.696015)
			(xy 224.983305 -141.82491) (xy 224.983802 -141.88948) (xy 224.983305 -141.95405) (xy 224.975355 -142.082945)
			(xy 224.959485 -142.211105) (xy 224.935756 -142.338046) (xy 224.904257 -142.463285) (xy 224.865108 -142.586348)
			(xy 224.818457 -142.706767) (xy 224.764482 -142.824086) (xy 224.703387 -142.93786) (xy 224.635404 -143.047657)
			(xy 224.56079 -143.15306) (xy 224.479829 -143.25367) (xy 224.392829 -143.349105) (xy 224.300118 -143.439004)
			(xy 224.202048 -143.523025) (xy 224.098993 -143.600849) (xy 223.991342 -143.672181) (xy 223.879503 -143.736751)
			(xy 223.763902 -143.794313) (xy 223.644977 -143.84465) (xy 223.523178 -143.88757) (xy 223.398968 -143.922911)
			(xy 223.272819 -143.950538) (xy 223.145207 -143.970347) (xy 223.016618 -143.982263) (xy 222.88754 -143.98624)
			(xy 222.758462 -143.982263) (xy 222.629873 -143.970347) (xy 222.502261 -143.950538) (xy 222.376112 -143.922911)
			(xy 222.251902 -143.88757) (xy 222.130103 -143.84465) (xy 222.011178 -143.794313) (xy 221.895577 -143.736751)
			(xy 221.783738 -143.672181) (xy 221.676087 -143.600849) (xy 221.573032 -143.523025) (xy 221.474962 -143.439004)
			(xy 221.382251 -143.349105) (xy 221.295251 -143.25367) (xy 221.21429 -143.15306) (xy 221.139676 -143.047657)
			(xy 221.071693 -142.93786) (xy 221.010598 -142.824086) (xy 220.956623 -142.706767) (xy 220.909972 -142.586348)
			(xy 220.870823 -142.463285) (xy 220.839324 -142.338046) (xy 220.815595 -142.211105) (xy 220.799725 -142.082945)
			(xy 220.791775 -141.95405) (xy 0.509016 -141.95405) (xy 0.509016 -141.99997) (xy 0.509522 -142.095303)
			(xy 0.517614 -142.285798) (xy 0.533784 -142.475778) (xy 0.558002 -142.664901) (xy 0.590225 -142.852825)
			(xy 0.630394 -143.039212) (xy 0.678438 -143.223727) (xy 0.73427 -143.406036) (xy 0.797788 -143.585811)
			(xy 0.86888 -143.762729) (xy 0.947415 -143.93647) (xy 1.033254 -144.106721) (xy 1.126242 -144.273176)
			(xy 1.22621 -144.435534) (xy 1.332978 -144.593504) (xy 1.446355 -144.746799) (xy 1.566136 -144.895145)
			(xy 1.692104 -145.038273) (xy 1.824034 -145.175926) (xy 1.961687 -145.307856) (xy 2.104815 -145.433824)
			(xy 2.253161 -145.553605) (xy 2.406456 -145.666982) (xy 2.564426 -145.77375) (xy 2.726784 -145.873718)
			(xy 2.893239 -145.966706) (xy 3.06349 -146.052545) (xy 3.237231 -146.13108) (xy 3.414149 -146.202172)
			(xy 3.593924 -146.26569) (xy 3.776233 -146.321522) (xy 3.960748 -146.369566) (xy 4.147135 -146.409735)
			(xy 4.335059 -146.441958) (xy 4.524182 -146.466176) (xy 4.714162 -146.482346) (xy 4.904657 -146.490438)
			(xy 4.99999 -146.490944) (xy 266.33297 -146.490944) (xy 266.33297 -146.49196) (xy 266.666472 -146.49196)
		)
		(stroke
			(width 0)
			(type solid)
		)
		(fill yes)
		(layer "In1.Cu")
		(net "GND")
	)
	(gr_circle
		(center 9.85012 -76.019914)
		(end 11.22172 -76.019914)
		(stroke
			(width 0.2)
			(type default)
		)
		(fill no)
		(layer "In1.Cu")
	)
	(gr_circle
		(center 9.85012 -74.319892)
		(end 11.22172 -74.319892)
		(stroke
			(width 0.2)
			(type default)
		)
		(fill no)
		(layer "In1.Cu")
	)
	(gr_circle
		(center 9.85012 -70.939914)
		(end 11.22172 -70.939914)
		(stroke
			(width 0.2)
			(type default)
		)
		(fill no)
		(layer "In1.Cu")
	)
	(gr_circle
		(center 9.85012 -69.239892)
		(end 11.22172 -69.239892)
		(stroke
			(width 0.2)
			(type default)
		)
		(fill no)
		(layer "In1.Cu")
	)
	(gr_circle
		(center 11.08964 -75.084432)
		(end 12.46124 -75.084432)
		(stroke
			(width 0.2)
			(type default)
		)
		(fill no)
		(layer "In1.Cu")
	)
	(gr_circle
		(center 11.222228 -70.016624)
		(end 12.593828 -70.016624)
		(stroke
			(width 0.2)
			(type default)
		)
		(fill no)
		(layer "In1.Cu")
	)
	(gr_circle
		(center 12.39012 -76.019914)
		(end 13.76172 -76.019914)
		(stroke
			(width 0.2)
			(type default)
		)
		(fill no)
		(layer "In1.Cu")
	)
	(gr_circle
		(center 12.39012 -74.319892)
		(end 13.76172 -74.319892)
		(stroke
			(width 0.2)
			(type default)
		)
		(fill no)
		(layer "In1.Cu")
	)
	(gr_circle
		(center 12.39012 -70.939914)
		(end 13.76172 -70.939914)
		(stroke
			(width 0.2)
			(type default)
		)
		(fill no)
		(layer "In1.Cu")
	)
	(gr_circle
		(center 12.39012 -69.239892)
		(end 13.76172 -69.239892)
		(stroke
			(width 0.2)
			(type default)
		)
		(fill no)
		(layer "In1.Cu")
	)
	(gr_circle
		(center 27.5844 -66.43624)
		(end 28.4734 -66.43624)
		(stroke
			(width 0.2)
			(type default)
		)
		(fill no)
		(layer "In1.Cu")
	)
	(gr_circle
		(center 27.5844 -65.67424)
		(end 28.4734 -65.67424)
		(stroke
			(width 0.2)
			(type default)
		)
		(fill no)
		(layer "In1.Cu")
	)
	(gr_circle
		(center 27.5844 -64.91224)
		(end 28.4734 -64.91224)
		(stroke
			(width 0.2)
			(type default)
		)
		(fill no)
		(layer "In1.Cu")
	)
	(gr_circle
		(center 28.3464 -66.43624)
		(end 29.2354 -66.43624)
		(stroke
			(width 0.2)
			(type default)
		)
		(fill no)
		(layer "In1.Cu")
	)
	(gr_circle
		(center 28.3464 -65.67424)
		(end 29.2354 -65.67424)
		(stroke
			(width 0.2)
			(type default)
		)
		(fill no)
		(layer "In1.Cu")
	)
	(gr_circle
		(center 28.3464 -64.91224)
		(end 29.2354 -64.91224)
		(stroke
			(width 0.2)
			(type default)
		)
		(fill no)
		(layer "In1.Cu")
	)
	(gr_circle
		(center 29.3878 -108.3818)
		(end 30.2768 -108.3818)
		(stroke
			(width 0.2)
			(type default)
		)
		(fill no)
		(layer "In1.Cu")
	)
	(gr_circle
		(center 29.3878 -107.6198)
		(end 30.2768 -107.6198)
		(stroke
			(width 0.2)
			(type default)
		)
		(fill no)
		(layer "In1.Cu")
	)
	(gr_circle
		(center 29.3878 -106.8324)
		(end 30.2768 -106.8324)
		(stroke
			(width 0.2)
			(type default)
		)
		(fill no)
		(layer "In1.Cu")
	)
	(gr_circle
		(center 29.3878 -106.0704)
		(end 30.2768 -106.0704)
		(stroke
			(width 0.2)
			(type default)
		)
		(fill no)
		(layer "In1.Cu")
	)
	(gr_circle
		(center 29.3878 -105.3084)
		(end 30.2768 -105.3084)
		(stroke
			(width 0.2)
			(type default)
		)
		(fill no)
		(layer "In1.Cu")
	)
	(gr_circle
		(center 29.3878 -104.5464)
		(end 30.2768 -104.5464)
		(stroke
			(width 0.2)
			(type default)
		)
		(fill no)
		(layer "In1.Cu")
	)
	(gr_circle
		(center 29.3878 -103.7844)
		(end 30.2768 -103.7844)
		(stroke
			(width 0.2)
			(type default)
		)
		(fill no)
		(layer "In1.Cu")
	)
	(gr_circle
		(center 30.353 -108.3564)
		(end 31.242 -108.3564)
		(stroke
			(width 0.2)
			(type default)
		)
		(fill no)
		(layer "In1.Cu")
	)
	(gr_circle
		(center 30.353 -106.807)
		(end 31.242 -106.807)
		(stroke
			(width 0.2)
			(type default)
		)
		(fill no)
		(layer "In1.Cu")
	)
	(gr_circle
		(center 30.353 -106.045)
		(end 31.242 -106.045)
		(stroke
			(width 0.2)
			(type default)
		)
		(fill no)
		(layer "In1.Cu")
	)
	(gr_circle
		(center 30.353 -105.283)
		(end 31.242 -105.283)
		(stroke
			(width 0.2)
			(type default)
		)
		(fill no)
		(layer "In1.Cu")
	)
	(gr_circle
		(center 30.353 -104.521)
		(end 31.242 -104.521)
		(stroke
			(width 0.2)
			(type default)
		)
		(fill no)
		(layer "In1.Cu")
	)
	(gr_circle
		(center 30.353 -103.759)
		(end 31.242 -103.759)
		(stroke
			(width 0.2)
			(type default)
		)
		(fill no)
		(layer "In1.Cu")
	)
	(gr_circle
		(center 31.242 -108.3564)
		(end 32.131 -108.3564)
		(stroke
			(width 0.2)
			(type default)
		)
		(fill no)
		(layer "In1.Cu")
	)
	(gr_circle
		(center 31.242 -107.5944)
		(end 32.131 -107.5944)
		(stroke
			(width 0.2)
			(type default)
		)
		(fill no)
		(layer "In1.Cu")
	)
	(gr_circle
		(center 31.242 -106.807)
		(end 32.131 -106.807)
		(stroke
			(width 0.2)
			(type default)
		)
		(fill no)
		(layer "In1.Cu")
	)
	(gr_circle
		(center 31.242 -106.045)
		(end 32.131 -106.045)
		(stroke
			(width 0.2)
			(type default)
		)
		(fill no)
		(layer "In1.Cu")
	)
	(gr_circle
		(center 31.242 -105.283)
		(end 32.131 -105.283)
		(stroke
			(width 0.2)
			(type default)
		)
		(fill no)
		(layer "In1.Cu")
	)
	(gr_circle
		(center 31.242 -104.521)
		(end 32.131 -104.521)
		(stroke
			(width 0.2)
			(type default)
		)
		(fill no)
		(layer "In1.Cu")
	)
	(gr_circle
		(center 31.242 -103.759)
		(end 32.131 -103.759)
		(stroke
			(width 0.2)
			(type default)
		)
		(fill no)
		(layer "In1.Cu")
	)
	(gr_circle
		(center 38.261036 -55.642002)
		(end 39.150036 -55.642002)
		(stroke
			(width 0.2)
			(type default)
		)
		(fill no)
		(layer "In1.Cu")
	)
	(gr_circle
		(center 38.692836 -58.436002)
		(end 39.581836 -58.436002)
		(stroke
			(width 0.2)
			(type default)
		)
		(fill no)
		(layer "In1.Cu")
	)
	(gr_circle
		(center 38.692836 -57.547002)
		(end 39.581836 -57.547002)
		(stroke
			(width 0.2)
			(type default)
		)
		(fill no)
		(layer "In1.Cu")
	)
	(gr_circle
		(center 38.692836 -56.658002)
		(end 39.581836 -56.658002)
		(stroke
			(width 0.2)
			(type default)
		)
		(fill no)
		(layer "In1.Cu")
	)
	(gr_circle
		(center 39.378636 -58.817002)
		(end 40.267636 -58.817002)
		(stroke
			(width 0.2)
			(type default)
		)
		(fill no)
		(layer "In1.Cu")
	)
	(gr_circle
		(center 39.378636 -57.928002)
		(end 40.267636 -57.928002)
		(stroke
			(width 0.2)
			(type default)
		)
		(fill no)
		(layer "In1.Cu")
	)
	(gr_circle
		(center 39.378636 -57.039002)
		(end 40.267636 -57.039002)
		(stroke
			(width 0.2)
			(type default)
		)
		(fill no)
		(layer "In1.Cu")
	)
	(gr_circle
		(center 39.8272 -108.3564)
		(end 40.7162 -108.3564)
		(stroke
			(width 0.2)
			(type default)
		)
		(fill no)
		(layer "In1.Cu")
	)
	(gr_circle
		(center 39.8272 -107.5944)
		(end 40.7162 -107.5944)
		(stroke
			(width 0.2)
			(type default)
		)
		(fill no)
		(layer "In1.Cu")
	)
	(gr_circle
		(center 39.878 -106.807)
		(end 40.767 -106.807)
		(stroke
			(width 0.2)
			(type default)
		)
		(fill no)
		(layer "In1.Cu")
	)
	(gr_circle
		(center 39.878 -106.045)
		(end 40.767 -106.045)
		(stroke
			(width 0.2)
			(type default)
		)
		(fill no)
		(layer "In1.Cu")
	)
	(gr_circle
		(center 39.878 -105.283)
		(end 40.767 -105.283)
		(stroke
			(width 0.2)
			(type default)
		)
		(fill no)
		(layer "In1.Cu")
	)
	(gr_circle
		(center 39.878 -104.521)
		(end 40.767 -104.521)
		(stroke
			(width 0.2)
			(type default)
		)
		(fill no)
		(layer "In1.Cu")
	)
	(gr_circle
		(center 39.878 -103.759)
		(end 40.767 -103.759)
		(stroke
			(width 0.2)
			(type default)
		)
		(fill no)
		(layer "In1.Cu")
	)
	(gr_circle
		(center 40.7162 -108.3564)
		(end 41.6052 -108.3564)
		(stroke
			(width 0.2)
			(type default)
		)
		(fill no)
		(layer "In1.Cu")
	)
	(gr_circle
		(center 40.7162 -107.5944)
		(end 41.6052 -107.5944)
		(stroke
			(width 0.2)
			(type default)
		)
		(fill no)
		(layer "In1.Cu")
	)
	(gr_circle
		(center 40.767 -106.807)
		(end 41.656 -106.807)
		(stroke
			(width 0.2)
			(type default)
		)
		(fill no)
		(layer "In1.Cu")
	)
	(gr_circle
		(center 40.767 -106.045)
		(end 41.656 -106.045)
		(stroke
			(width 0.2)
			(type default)
		)
		(fill no)
		(layer "In1.Cu")
	)
	(gr_circle
		(center 40.767 -105.283)
		(end 41.656 -105.283)
		(stroke
			(width 0.2)
			(type default)
		)
		(fill no)
		(layer "In1.Cu")
	)
	(gr_circle
		(center 40.767 -104.521)
		(end 41.656 -104.521)
		(stroke
			(width 0.2)
			(type default)
		)
		(fill no)
		(layer "In1.Cu")
	)
	(gr_circle
		(center 40.767 -103.759)
		(end 41.656 -103.759)
		(stroke
			(width 0.2)
			(type default)
		)
		(fill no)
		(layer "In1.Cu")
	)
	(gr_circle
		(center 41.3639 -58.604912)
		(end 42.2529 -58.604912)
		(stroke
			(width 0.2)
			(type default)
		)
		(fill no)
		(layer "In1.Cu")
	)
	(gr_circle
		(center 41.3639 -57.70499)
		(end 42.2529 -57.70499)
		(stroke
			(width 0.2)
			(type default)
		)
		(fill no)
		(layer "In1.Cu")
	)
	(gr_circle
		(center 41.3639 -56.805068)
		(end 42.2529 -56.805068)
		(stroke
			(width 0.2)
			(type default)
		)
		(fill no)
		(layer "In1.Cu")
	)
	(gr_circle
		(center 41.3639 -55.904892)
		(end 42.2529 -55.904892)
		(stroke
			(width 0.2)
			(type default)
		)
		(fill no)
		(layer "In1.Cu")
	)
	(gr_circle
		(center 41.6052 -108.3818)
		(end 42.4942 -108.3818)
		(stroke
			(width 0.2)
			(type default)
		)
		(fill no)
		(layer "In1.Cu")
	)
	(gr_circle
		(center 41.6052 -107.6198)
		(end 42.4942 -107.6198)
		(stroke
			(width 0.2)
			(type default)
		)
		(fill no)
		(layer "In1.Cu")
	)
	(gr_circle
		(center 41.656 -106.8324)
		(end 42.545 -106.8324)
		(stroke
			(width 0.2)
			(type default)
		)
		(fill no)
		(layer "In1.Cu")
	)
	(gr_circle
		(center 41.656 -106.0704)
		(end 42.545 -106.0704)
		(stroke
			(width 0.2)
			(type default)
		)
		(fill no)
		(layer "In1.Cu")
	)
	(gr_circle
		(center 41.656 -105.3084)
		(end 42.545 -105.3084)
		(stroke
			(width 0.2)
			(type default)
		)
		(fill no)
		(layer "In1.Cu")
	)
	(gr_circle
		(center 41.656 -104.5464)
		(end 42.545 -104.5464)
		(stroke
			(width 0.2)
			(type default)
		)
		(fill no)
		(layer "In1.Cu")
	)
	(gr_circle
		(center 41.656 -103.7844)
		(end 42.545 -103.7844)
		(stroke
			(width 0.2)
			(type default)
		)
		(fill no)
		(layer "In1.Cu")
	)
	(gr_circle
		(center 41.84904 -54.1147)
		(end 42.73804 -54.1147)
		(stroke
			(width 0.2)
			(type default)
		)
		(fill no)
		(layer "In1.Cu")
	)
	(gr_circle
		(center 41.84904 -53.3019)
		(end 42.73804 -53.3019)
		(stroke
			(width 0.2)
			(type default)
		)
		(fill no)
		(layer "In1.Cu")
	)
	(gr_circle
		(center 41.9989 -58.604912)
		(end 42.8879 -58.604912)
		(stroke
			(width 0.2)
			(type default)
		)
		(fill no)
		(layer "In1.Cu")
	)
	(gr_circle
		(center 41.9989 -57.70499)
		(end 42.8879 -57.70499)
		(stroke
			(width 0.2)
			(type default)
		)
		(fill no)
		(layer "In1.Cu")
	)
	(gr_circle
		(center 41.9989 -56.805068)
		(end 42.8879 -56.805068)
		(stroke
			(width 0.2)
			(type default)
		)
		(fill no)
		(layer "In1.Cu")
	)
	(gr_circle
		(center 41.9989 -55.904892)
		(end 42.8879 -55.904892)
		(stroke
			(width 0.2)
			(type default)
		)
		(fill no)
		(layer "In1.Cu")
	)
	(gr_circle
		(center 42.046906 -136.906)
		(end 43.469306 -136.906)
		(stroke
			(width 0.2)
			(type default)
		)
		(fill no)
		(layer "In1.Cu")
	)
	(gr_circle
		(center 42.58564 -54.1147)
		(end 43.47464 -54.1147)
		(stroke
			(width 0.2)
			(type default)
		)
		(fill no)
		(layer "In1.Cu")
	)
	(gr_circle
		(center 42.58564 -53.3019)
		(end 43.47464 -53.3019)
		(stroke
			(width 0.2)
			(type default)
		)
		(fill no)
		(layer "In1.Cu")
	)
	(gr_circle
		(center 42.910506 -131.572)
		(end 43.799506 -131.572)
		(stroke
			(width 0.2)
			(type default)
		)
		(fill no)
		(layer "In1.Cu")
	)
	(gr_circle
		(center 42.910506 -126.492)
		(end 43.799506 -126.492)
		(stroke
			(width 0.2)
			(type default)
		)
		(fill no)
		(layer "In1.Cu")
	)
	(gr_circle
		(center 43.672506 -131.572)
		(end 44.561506 -131.572)
		(stroke
			(width 0.2)
			(type default)
		)
		(fill no)
		(layer "In1.Cu")
	)
	(gr_circle
		(center 43.672506 -126.492)
		(end 44.561506 -126.492)
		(stroke
			(width 0.2)
			(type default)
		)
		(fill no)
		(layer "In1.Cu")
	)
	(gr_circle
		(center 44.36364 -52.2859)
		(end 45.25264 -52.2859)
		(stroke
			(width 0.2)
			(type default)
		)
		(fill no)
		(layer "In1.Cu")
	)
	(gr_circle
		(center 44.36364 -51.4731)
		(end 45.25264 -51.4731)
		(stroke
			(width 0.2)
			(type default)
		)
		(fill no)
		(layer "In1.Cu")
	)
	(gr_circle
		(center 44.84624 -50.0507)
		(end 45.73524 -50.0507)
		(stroke
			(width 0.2)
			(type default)
		)
		(fill no)
		(layer "In1.Cu")
	)
	(gr_circle
		(center 45.58284 -50.0507)
		(end 46.47184 -50.0507)
		(stroke
			(width 0.2)
			(type default)
		)
		(fill no)
		(layer "In1.Cu")
	)
	(gr_circle
		(center 46.29404 -50.0507)
		(end 47.18304 -50.0507)
		(stroke
			(width 0.2)
			(type default)
		)
		(fill no)
		(layer "In1.Cu")
	)
	(gr_circle
		(center 47.05604 -52.9209)
		(end 47.94504 -52.9209)
		(stroke
			(width 0.2)
			(type default)
		)
		(fill no)
		(layer "In1.Cu")
	)
	(gr_circle
		(center 47.05604 -52.1589)
		(end 47.94504 -52.1589)
		(stroke
			(width 0.2)
			(type default)
		)
		(fill no)
		(layer "In1.Cu")
	)
	(gr_circle
		(center 49.31664 -52.8828)
		(end 50.20564 -52.8828)
		(stroke
			(width 0.2)
			(type default)
		)
		(fill no)
		(layer "In1.Cu")
	)
	(gr_circle
		(center 49.31664 -52.1208)
		(end 50.20564 -52.1208)
		(stroke
			(width 0.2)
			(type default)
		)
		(fill no)
		(layer "In1.Cu")
	)
	(gr_circle
		(center 50.07864 -52.8828)
		(end 50.96764 -52.8828)
		(stroke
			(width 0.2)
			(type default)
		)
		(fill no)
		(layer "In1.Cu")
	)
	(gr_circle
		(center 50.07864 -52.1208)
		(end 50.96764 -52.1208)
		(stroke
			(width 0.2)
			(type default)
		)
		(fill no)
		(layer "In1.Cu")
	)
	(gr_circle
		(center 50.84064 -52.8828)
		(end 51.72964 -52.8828)
		(stroke
			(width 0.2)
			(type default)
		)
		(fill no)
		(layer "In1.Cu")
	)
	(gr_circle
		(center 50.84064 -52.1208)
		(end 51.72964 -52.1208)
		(stroke
			(width 0.2)
			(type default)
		)
		(fill no)
		(layer "In1.Cu")
	)
	(gr_circle
		(center 54.238906 -136.906)
		(end 55.661306 -136.906)
		(stroke
			(width 0.2)
			(type default)
		)
		(fill no)
		(layer "In1.Cu")
	)
	(gr_circle
		(center 55.102506 -131.572)
		(end 55.991506 -131.572)
		(stroke
			(width 0.2)
			(type default)
		)
		(fill no)
		(layer "In1.Cu")
	)
	(gr_circle
		(center 55.102506 -126.492)
		(end 55.991506 -126.492)
		(stroke
			(width 0.2)
			(type default)
		)
		(fill no)
		(layer "In1.Cu")
	)
	(gr_circle
		(center 55.864506 -131.572)
		(end 56.753506 -131.572)
		(stroke
			(width 0.2)
			(type default)
		)
		(fill no)
		(layer "In1.Cu")
	)
	(gr_circle
		(center 55.864506 -126.492)
		(end 56.753506 -126.492)
		(stroke
			(width 0.2)
			(type default)
		)
		(fill no)
		(layer "In1.Cu")
	)
	(gr_circle
		(center 62.850014 -77.71765)
		(end 63.739014 -77.71765)
		(stroke
			(width 0.2)
			(type default)
		)
		(fill no)
		(layer "In1.Cu")
	)
	(gr_circle
		(center 64.470026 -121.209816)
		(end 66.286126 -121.209816)
		(stroke
			(width 0.2)
			(type default)
		)
		(fill no)
		(layer "In1.Cu")
	)
	(gr_circle
		(center 64.470026 -70.409816)
		(end 66.667126 -70.409816)
		(stroke
			(width 0.2)
			(type default)
		)
		(fill no)
		(layer "In1.Cu")
	)
	(gr_circle
		(center 66.430906 -136.906)
		(end 67.853306 -136.906)
		(stroke
			(width 0.2)
			(type default)
		)
		(fill no)
		(layer "In1.Cu")
	)
	(gr_circle
		(center 67.294506 -131.572)
		(end 68.183506 -131.572)
		(stroke
			(width 0.2)
			(type default)
		)
		(fill no)
		(layer "In1.Cu")
	)
	(gr_circle
		(center 67.294506 -126.492)
		(end 68.183506 -126.492)
		(stroke
			(width 0.2)
			(type default)
		)
		(fill no)
		(layer "In1.Cu")
	)
	(gr_circle
		(center 68.056506 -131.572)
		(end 68.945506 -131.572)
		(stroke
			(width 0.2)
			(type default)
		)
		(fill no)
		(layer "In1.Cu")
	)
	(gr_circle
		(center 68.056506 -126.492)
		(end 68.945506 -126.492)
		(stroke
			(width 0.2)
			(type default)
		)
		(fill no)
		(layer "In1.Cu")
	)
	(gr_circle
		(center 68.072 -60.96)
		(end 69.469 -60.96)
		(stroke
			(width 0.2)
			(type default)
		)
		(fill no)
		(layer "In1.Cu")
	)
	(gr_circle
		(center 68.280026 -70.409816)
		(end 70.477126 -70.409816)
		(stroke
			(width 0.2)
			(type default)
		)
		(fill no)
		(layer "In1.Cu")
	)
	(gr_circle
		(center 70.413626 -71.901812)
		(end 71.302626 -71.901812)
		(stroke
			(width 0.2)
			(type default)
		)
		(fill no)
		(layer "In1.Cu")
	)
	(gr_circle
		(center 70.413626 -70.885812)
		(end 71.302626 -70.885812)
		(stroke
			(width 0.2)
			(type default)
		)
		(fill no)
		(layer "In1.Cu")
	)
	(gr_circle
		(center 70.413626 -69.869812)
		(end 71.302626 -69.869812)
		(stroke
			(width 0.2)
			(type default)
		)
		(fill no)
		(layer "In1.Cu")
	)
	(gr_circle
		(center 70.413626 -68.853812)
		(end 71.302626 -68.853812)
		(stroke
			(width 0.2)
			(type default)
		)
		(fill no)
		(layer "In1.Cu")
	)
	(gr_circle
		(center 71.429626 -71.901812)
		(end 72.318626 -71.901812)
		(stroke
			(width 0.2)
			(type default)
		)
		(fill no)
		(layer "In1.Cu")
	)
	(gr_circle
		(center 71.429626 -70.885812)
		(end 72.318626 -70.885812)
		(stroke
			(width 0.2)
			(type default)
		)
		(fill no)
		(layer "In1.Cu")
	)
	(gr_circle
		(center 71.429626 -69.869812)
		(end 72.318626 -69.869812)
		(stroke
			(width 0.2)
			(type default)
		)
		(fill no)
		(layer "In1.Cu")
	)
	(gr_circle
		(center 71.429626 -68.853812)
		(end 72.318626 -68.853812)
		(stroke
			(width 0.2)
			(type default)
		)
		(fill no)
		(layer "In1.Cu")
	)
	(gr_circle
		(center 71.882 -52.324)
		(end 72.771 -52.324)
		(stroke
			(width 0.2)
			(type default)
		)
		(fill no)
		(layer "In1.Cu")
	)
	(gr_circle
		(center 71.882 -51.689)
		(end 72.771 -51.689)
		(stroke
			(width 0.2)
			(type default)
		)
		(fill no)
		(layer "In1.Cu")
	)
	(gr_circle
		(center 71.882 -50.419)
		(end 72.771 -50.419)
		(stroke
			(width 0.2)
			(type default)
		)
		(fill no)
		(layer "In1.Cu")
	)
	(gr_circle
		(center 71.882 -49.784)
		(end 72.771 -49.784)
		(stroke
			(width 0.2)
			(type default)
		)
		(fill no)
		(layer "In1.Cu")
	)
	(gr_circle
		(center 72.445626 -71.901812)
		(end 73.334626 -71.901812)
		(stroke
			(width 0.2)
			(type default)
		)
		(fill no)
		(layer "In1.Cu")
	)
	(gr_circle
		(center 72.445626 -70.885812)
		(end 73.334626 -70.885812)
		(stroke
			(width 0.2)
			(type default)
		)
		(fill no)
		(layer "In1.Cu")
	)
	(gr_circle
		(center 72.445626 -69.869812)
		(end 73.334626 -69.869812)
		(stroke
			(width 0.2)
			(type default)
		)
		(fill no)
		(layer "In1.Cu")
	)
	(gr_circle
		(center 72.445626 -68.853812)
		(end 73.334626 -68.853812)
		(stroke
			(width 0.2)
			(type default)
		)
		(fill no)
		(layer "In1.Cu")
	)
	(gr_circle
		(center 77.343 -52.324)
		(end 78.232 -52.324)
		(stroke
			(width 0.2)
			(type default)
		)
		(fill no)
		(layer "In1.Cu")
	)
	(gr_circle
		(center 77.343 -51.689)
		(end 78.232 -51.689)
		(stroke
			(width 0.2)
			(type default)
		)
		(fill no)
		(layer "In1.Cu")
	)
	(gr_circle
		(center 77.343 -50.419)
		(end 78.232 -50.419)
		(stroke
			(width 0.2)
			(type default)
		)
		(fill no)
		(layer "In1.Cu")
	)
	(gr_circle
		(center 77.343 -49.784)
		(end 78.232 -49.784)
		(stroke
			(width 0.2)
			(type default)
		)
		(fill no)
		(layer "In1.Cu")
	)
	(gr_circle
		(center 79.375 -60.96)
		(end 80.772 -60.96)
		(stroke
			(width 0.2)
			(type default)
		)
		(fill no)
		(layer "In1.Cu")
	)
	(gr_circle
		(center 82.046826 -136.906)
		(end 83.469226 -136.906)
		(stroke
			(width 0.2)
			(type default)
		)
		(fill no)
		(layer "In1.Cu")
	)
	(gr_circle
		(center 82.804 -52.324)
		(end 83.693 -52.324)
		(stroke
			(width 0.2)
			(type default)
		)
		(fill no)
		(layer "In1.Cu")
	)
	(gr_circle
		(center 82.804 -51.689)
		(end 83.693 -51.689)
		(stroke
			(width 0.2)
			(type default)
		)
		(fill no)
		(layer "In1.Cu")
	)
	(gr_circle
		(center 82.804 -50.419)
		(end 83.693 -50.419)
		(stroke
			(width 0.2)
			(type default)
		)
		(fill no)
		(layer "In1.Cu")
	)
	(gr_circle
		(center 82.804 -49.784)
		(end 83.693 -49.784)
		(stroke
			(width 0.2)
			(type default)
		)
		(fill no)
		(layer "In1.Cu")
	)
	(gr_circle
		(center 82.910426 -131.572)
		(end 83.799426 -131.572)
		(stroke
			(width 0.2)
			(type default)
		)
		(fill no)
		(layer "In1.Cu")
	)
	(gr_circle
		(center 82.910426 -126.492)
		(end 83.799426 -126.492)
		(stroke
			(width 0.2)
			(type default)
		)
		(fill no)
		(layer "In1.Cu")
	)
	(gr_circle
		(center 83.672426 -131.572)
		(end 84.561426 -131.572)
		(stroke
			(width 0.2)
			(type default)
		)
		(fill no)
		(layer "In1.Cu")
	)
	(gr_circle
		(center 83.672426 -126.492)
		(end 84.561426 -126.492)
		(stroke
			(width 0.2)
			(type default)
		)
		(fill no)
		(layer "In1.Cu")
	)
	(gr_circle
		(center 88.265 -52.324)
		(end 89.154 -52.324)
		(stroke
			(width 0.2)
			(type default)
		)
		(fill no)
		(layer "In1.Cu")
	)
	(gr_circle
		(center 88.265 -51.689)
		(end 89.154 -51.689)
		(stroke
			(width 0.2)
			(type default)
		)
		(fill no)
		(layer "In1.Cu")
	)
	(gr_circle
		(center 88.265 -50.419)
		(end 89.154 -50.419)
		(stroke
			(width 0.2)
			(type default)
		)
		(fill no)
		(layer "In1.Cu")
	)
	(gr_circle
		(center 88.265 -49.784)
		(end 89.154 -49.784)
		(stroke
			(width 0.2)
			(type default)
		)
		(fill no)
		(layer "In1.Cu")
	)
	(gr_circle
		(center 90.678 -60.96)
		(end 92.075 -60.96)
		(stroke
			(width 0.2)
			(type default)
		)
		(fill no)
		(layer "In1.Cu")
	)
	(gr_circle
		(center 93.726 -52.324)
		(end 94.615 -52.324)
		(stroke
			(width 0.2)
			(type default)
		)
		(fill no)
		(layer "In1.Cu")
	)
	(gr_circle
		(center 93.726 -51.689)
		(end 94.615 -51.689)
		(stroke
			(width 0.2)
			(type default)
		)
		(fill no)
		(layer "In1.Cu")
	)
	(gr_circle
		(center 93.726 -50.419)
		(end 94.615 -50.419)
		(stroke
			(width 0.2)
			(type default)
		)
		(fill no)
		(layer "In1.Cu")
	)
	(gr_circle
		(center 93.726 -49.784)
		(end 94.615 -49.784)
		(stroke
			(width 0.2)
			(type default)
		)
		(fill no)
		(layer "In1.Cu")
	)
	(gr_circle
		(center 94.238826 -136.906)
		(end 95.661226 -136.906)
		(stroke
			(width 0.2)
			(type default)
		)
		(fill no)
		(layer "In1.Cu")
	)
	(gr_circle
		(center 95.102426 -131.572)
		(end 95.991426 -131.572)
		(stroke
			(width 0.2)
			(type default)
		)
		(fill no)
		(layer "In1.Cu")
	)
	(gr_circle
		(center 95.102426 -126.492)
		(end 95.991426 -126.492)
		(stroke
			(width 0.2)
			(type default)
		)
		(fill no)
		(layer "In1.Cu")
	)
	(gr_circle
		(center 95.864426 -131.572)
		(end 96.753426 -131.572)
		(stroke
			(width 0.2)
			(type default)
		)
		(fill no)
		(layer "In1.Cu")
	)
	(gr_circle
		(center 95.864426 -126.492)
		(end 96.753426 -126.492)
		(stroke
			(width 0.2)
			(type default)
		)
		(fill no)
		(layer "In1.Cu")
	)
	(gr_circle
		(center 99.187 -52.324)
		(end 100.076 -52.324)
		(stroke
			(width 0.2)
			(type default)
		)
		(fill no)
		(layer "In1.Cu")
	)
	(gr_circle
		(center 99.187 -51.689)
		(end 100.076 -51.689)
		(stroke
			(width 0.2)
			(type default)
		)
		(fill no)
		(layer "In1.Cu")
	)
	(gr_circle
		(center 99.187 -50.419)
		(end 100.076 -50.419)
		(stroke
			(width 0.2)
			(type default)
		)
		(fill no)
		(layer "In1.Cu")
	)
	(gr_circle
		(center 99.187 -49.784)
		(end 100.076 -49.784)
		(stroke
			(width 0.2)
			(type default)
		)
		(fill no)
		(layer "In1.Cu")
	)
	(gr_arc
		(start 100.645976 -40.55999)
		(mid 101.055743 -41.549255)
		(end 102.045008 -41.959022)
		(stroke
			(width 0.2)
			(type default)
		)
		(layer "In1.Cu")
	)
	(gr_arc
		(start 100.645976 -32.93999)
		(mid 100.86641 -33.693779)
		(end 101.458268 -34.20999)
		(stroke
			(width 0.2)
			(type default)
		)
		(layer "In1.Cu")
	)
	(gr_arc
		(start 101.458268 -39.28999)
		(mid 100.866448 -39.806225)
		(end 100.645976 -40.55999)
		(stroke
			(width 0.2)
			(type default)
		)
		(layer "In1.Cu")
	)
	(gr_arc
		(start 101.458268 -36.74999)
		(mid 100.646021 -38.01999)
		(end 101.458268 -39.28999)
		(stroke
			(width 0.2)
			(type default)
		)
		(layer "In1.Cu")
	)
	(gr_arc
		(start 101.458268 -34.20999)
		(mid 100.646021 -35.47999)
		(end 101.458268 -36.74999)
		(stroke
			(width 0.2)
			(type default)
		)
		(layer "In1.Cu")
	)
	(gr_arc
		(start 102.045008 -41.959022)
		(mid 102.798797 -41.738588)
		(end 103.315008 -41.14673)
		(stroke
			(width 0.2)
			(type default)
		)
		(layer "In1.Cu")
	)
	(gr_arc
		(start 102.045008 -31.540958)
		(mid 101.055743 -31.950725)
		(end 100.645976 -32.93999)
		(stroke
			(width 0.2)
			(type default)
		)
		(layer "In1.Cu")
	)
	(gr_circle
		(center 102.849934 -77.71765)
		(end 103.738934 -77.71765)
		(stroke
			(width 0.2)
			(type default)
		)
		(fill no)
		(layer "In1.Cu")
	)
	(gr_arc
		(start 103.315008 -41.14673)
		(mid 103.831243 -41.73855)
		(end 104.585008 -41.959022)
		(stroke
			(width 0.2)
			(type default)
		)
		(layer "In1.Cu")
	)
	(gr_arc
		(start 103.315008 -32.35325)
		(mid 102.798773 -31.76143)
		(end 102.045008 -31.540958)
		(stroke
			(width 0.2)
			(type default)
		)
		(layer "In1.Cu")
	)
	(gr_circle
		(center 104.469946 -121.209816)
		(end 106.286046 -121.209816)
		(stroke
			(width 0.2)
			(type default)
		)
		(fill no)
		(layer "In1.Cu")
	)
	(gr_circle
		(center 104.469946 -70.409816)
		(end 106.667046 -70.409816)
		(stroke
			(width 0.2)
			(type default)
		)
		(fill no)
		(layer "In1.Cu")
	)
	(gr_arc
		(start 104.585008 -41.959022)
		(mid 105.574273 -41.549255)
		(end 105.98404 -40.55999)
		(stroke
			(width 0.2)
			(type default)
		)
		(layer "In1.Cu")
	)
	(gr_arc
		(start 104.585008 -31.540958)
		(mid 103.831219 -31.761392)
		(end 103.315008 -32.35325)
		(stroke
			(width 0.2)
			(type default)
		)
		(layer "In1.Cu")
	)
	(gr_circle
		(center 104.648 -52.324)
		(end 105.537 -52.324)
		(stroke
			(width 0.2)
			(type default)
		)
		(fill no)
		(layer "In1.Cu")
	)
	(gr_circle
		(center 104.648 -51.689)
		(end 105.537 -51.689)
		(stroke
			(width 0.2)
			(type default)
		)
		(fill no)
		(layer "In1.Cu")
	)
	(gr_circle
		(center 104.648 -50.419)
		(end 105.537 -50.419)
		(stroke
			(width 0.2)
			(type default)
		)
		(fill no)
		(layer "In1.Cu")
	)
	(gr_circle
		(center 104.648 -49.784)
		(end 105.537 -49.784)
		(stroke
			(width 0.2)
			(type default)
		)
		(fill no)
		(layer "In1.Cu")
	)
	(gr_arc
		(start 105.171748 -39.28999)
		(mid 105.983995 -38.01999)
		(end 105.171748 -36.74999)
		(stroke
			(width 0.2)
			(type default)
		)
		(layer "In1.Cu")
	)
	(gr_arc
		(start 105.171748 -36.74999)
		(mid 105.763568 -36.233755)
		(end 105.98404 -35.47999)
		(stroke
			(width 0.2)
			(type default)
		)
		(layer "In1.Cu")
	)
	(gr_arc
		(start 105.171748 -34.20999)
		(mid 105.763568 -33.693755)
		(end 105.98404 -32.93999)
		(stroke
			(width 0.2)
			(type default)
		)
		(layer "In1.Cu")
	)
	(gr_arc
		(start 105.98404 -40.55999)
		(mid 105.763606 -39.806201)
		(end 105.171748 -39.28999)
		(stroke
			(width 0.2)
			(type default)
		)
		(layer "In1.Cu")
	)
	(gr_arc
		(start 105.98404 -35.47999)
		(mid 105.763606 -34.726201)
		(end 105.171748 -34.20999)
		(stroke
			(width 0.2)
			(type default)
		)
		(layer "In1.Cu")
	)
	(gr_arc
		(start 105.98404 -32.93999)
		(mid 105.574273 -31.950725)
		(end 104.585008 -31.540958)
		(stroke
			(width 0.2)
			(type default)
		)
		(layer "In1.Cu")
	)
	(gr_circle
		(center 106.430826 -136.906)
		(end 107.853226 -136.906)
		(stroke
			(width 0.2)
			(type default)
		)
		(fill no)
		(layer "In1.Cu")
	)
	(gr_circle
		(center 107.294426 -131.572)
		(end 108.183426 -131.572)
		(stroke
			(width 0.2)
			(type default)
		)
		(fill no)
		(layer "In1.Cu")
	)
	(gr_circle
		(center 107.294426 -126.492)
		(end 108.183426 -126.492)
		(stroke
			(width 0.2)
			(type default)
		)
		(fill no)
		(layer "In1.Cu")
	)
	(gr_circle
		(center 108.056426 -131.572)
		(end 108.945426 -131.572)
		(stroke
			(width 0.2)
			(type default)
		)
		(fill no)
		(layer "In1.Cu")
	)
	(gr_circle
		(center 108.056426 -126.492)
		(end 108.945426 -126.492)
		(stroke
			(width 0.2)
			(type default)
		)
		(fill no)
		(layer "In1.Cu")
	)
	(gr_circle
		(center 108.279946 -70.409816)
		(end 110.477046 -70.409816)
		(stroke
			(width 0.2)
			(type default)
		)
		(fill no)
		(layer "In1.Cu")
	)
	(gr_circle
		(center 108.839 -60.96)
		(end 110.236 -60.96)
		(stroke
			(width 0.2)
			(type default)
		)
		(fill no)
		(layer "In1.Cu")
	)
	(gr_arc
		(start 109.535976 -40.55999)
		(mid 109.945743 -41.549255)
		(end 110.935008 -41.959022)
		(stroke
			(width 0.2)
			(type default)
		)
		(layer "In1.Cu")
	)
	(gr_arc
		(start 109.535976 -35.47999)
		(mid 109.75641 -36.233779)
		(end 110.348268 -36.74999)
		(stroke
			(width 0.2)
			(type default)
		)
		(layer "In1.Cu")
	)
	(gr_arc
		(start 109.535976 -32.93999)
		(mid 109.75641 -33.693779)
		(end 110.348268 -34.20999)
		(stroke
			(width 0.2)
			(type default)
		)
		(layer "In1.Cu")
	)
	(gr_arc
		(start 110.348268 -39.28999)
		(mid 109.756448 -39.806225)
		(end 109.535976 -40.55999)
		(stroke
			(width 0.2)
			(type default)
		)
		(layer "In1.Cu")
	)
	(gr_arc
		(start 110.348268 -36.74999)
		(mid 109.536021 -38.01999)
		(end 110.348268 -39.28999)
		(stroke
			(width 0.2)
			(type default)
		)
		(layer "In1.Cu")
	)
	(gr_arc
		(start 110.348268 -34.20999)
		(mid 109.756448 -34.726225)
		(end 109.535976 -35.47999)
		(stroke
			(width 0.2)
			(type default)
		)
		(layer "In1.Cu")
	)
	(gr_circle
		(center 110.362746 -71.929244)
		(end 111.251746 -71.929244)
		(stroke
			(width 0.2)
			(type default)
		)
		(fill no)
		(layer "In1.Cu")
	)
	(gr_circle
		(center 110.362746 -70.913244)
		(end 111.251746 -70.913244)
		(stroke
			(width 0.2)
			(type default)
		)
		(fill no)
		(layer "In1.Cu")
	)
	(gr_circle
		(center 110.362746 -69.897244)
		(end 111.251746 -69.897244)
		(stroke
			(width 0.2)
			(type default)
		)
		(fill no)
		(layer "In1.Cu")
	)
	(gr_circle
		(center 110.362746 -68.881244)
		(end 111.251746 -68.881244)
		(stroke
			(width 0.2)
			(type default)
		)
		(fill no)
		(layer "In1.Cu")
	)
	(gr_arc
		(start 110.935008 -41.959022)
		(mid 111.688797 -41.738588)
		(end 112.205008 -41.14673)
		(stroke
			(width 0.2)
			(type default)
		)
		(layer "In1.Cu")
	)
	(gr_arc
		(start 110.935008 -31.540958)
		(mid 109.945743 -31.950725)
		(end 109.535976 -32.93999)
		(stroke
			(width 0.2)
			(type default)
		)
		(layer "In1.Cu")
	)
	(gr_circle
		(center 111.378746 -71.929244)
		(end 112.267746 -71.929244)
		(stroke
			(width 0.2)
			(type default)
		)
		(fill no)
		(layer "In1.Cu")
	)
	(gr_circle
		(center 111.378746 -70.913244)
		(end 112.267746 -70.913244)
		(stroke
			(width 0.2)
			(type default)
		)
		(fill no)
		(layer "In1.Cu")
	)
	(gr_circle
		(center 111.378746 -69.897244)
		(end 112.267746 -69.897244)
		(stroke
			(width 0.2)
			(type default)
		)
		(fill no)
		(layer "In1.Cu")
	)
	(gr_circle
		(center 111.378746 -68.881244)
		(end 112.267746 -68.881244)
		(stroke
			(width 0.2)
			(type default)
		)
		(fill no)
		(layer "In1.Cu")
	)
	(gr_arc
		(start 112.205008 -41.14673)
		(mid 112.721243 -41.73855)
		(end 113.475008 -41.959022)
		(stroke
			(width 0.2)
			(type default)
		)
		(layer "In1.Cu")
	)
	(gr_arc
		(start 112.205008 -32.35325)
		(mid 111.688773 -31.76143)
		(end 110.935008 -31.540958)
		(stroke
			(width 0.2)
			(type default)
		)
		(layer "In1.Cu")
	)
	(gr_circle
		(center 112.394746 -71.929244)
		(end 113.283746 -71.929244)
		(stroke
			(width 0.2)
			(type default)
		)
		(fill no)
		(layer "In1.Cu")
	)
	(gr_circle
		(center 112.394746 -70.913244)
		(end 113.283746 -70.913244)
		(stroke
			(width 0.2)
			(type default)
		)
		(fill no)
		(layer "In1.Cu")
	)
	(gr_circle
		(center 112.394746 -69.897244)
		(end 113.283746 -69.897244)
		(stroke
			(width 0.2)
			(type default)
		)
		(fill no)
		(layer "In1.Cu")
	)
	(gr_circle
		(center 112.394746 -68.881244)
		(end 113.283746 -68.881244)
		(stroke
			(width 0.2)
			(type default)
		)
		(fill no)
		(layer "In1.Cu")
	)
	(gr_arc
		(start 113.475008 -41.959022)
		(mid 114.464273 -41.549255)
		(end 114.87404 -40.55999)
		(stroke
			(width 0.2)
			(type default)
		)
		(layer "In1.Cu")
	)
	(gr_arc
		(start 113.475008 -31.540958)
		(mid 112.721219 -31.761392)
		(end 112.205008 -32.35325)
		(stroke
			(width 0.2)
			(type default)
		)
		(layer "In1.Cu")
	)
	(gr_arc
		(start 114.061748 -39.28999)
		(mid 114.653568 -38.773755)
		(end 114.87404 -38.01999)
		(stroke
			(width 0.2)
			(type default)
		)
		(layer "In1.Cu")
	)
	(gr_arc
		(start 114.061748 -36.74999)
		(mid 114.653568 -36.233755)
		(end 114.87404 -35.47999)
		(stroke
			(width 0.2)
			(type default)
		)
		(layer "In1.Cu")
	)
	(gr_arc
		(start 114.061748 -34.20999)
		(mid 114.653568 -33.693755)
		(end 114.87404 -32.93999)
		(stroke
			(width 0.2)
			(type default)
		)
		(layer "In1.Cu")
	)
	(gr_arc
		(start 114.87404 -40.55999)
		(mid 114.653606 -39.806201)
		(end 114.061748 -39.28999)
		(stroke
			(width 0.2)
			(type default)
		)
		(layer "In1.Cu")
	)
	(gr_arc
		(start 114.87404 -38.01999)
		(mid 114.653606 -37.266201)
		(end 114.061748 -36.74999)
		(stroke
			(width 0.2)
			(type default)
		)
		(layer "In1.Cu")
	)
	(gr_arc
		(start 114.87404 -35.47999)
		(mid 114.653606 -34.726201)
		(end 114.061748 -34.20999)
		(stroke
			(width 0.2)
			(type default)
		)
		(layer "In1.Cu")
	)
	(gr_arc
		(start 114.87404 -32.93999)
		(mid 114.464273 -31.950725)
		(end 113.475008 -31.540958)
		(stroke
			(width 0.2)
			(type default)
		)
		(layer "In1.Cu")
	)
	(gr_arc
		(start 118.425976 -40.55999)
		(mid 118.835743 -41.549255)
		(end 119.825008 -41.959022)
		(stroke
			(width 0.2)
			(type default)
		)
		(layer "In1.Cu")
	)
	(gr_arc
		(start 118.425976 -35.47999)
		(mid 118.646348 -36.233682)
		(end 119.238014 -36.74999)
		(stroke
			(width 0.2)
			(type default)
		)
		(layer "In1.Cu")
	)
	(gr_arc
		(start 118.425976 -32.93999)
		(mid 118.64641 -33.693779)
		(end 119.238268 -34.20999)
		(stroke
			(width 0.2)
			(type default)
		)
		(layer "In1.Cu")
	)
	(gr_arc
		(start 119.238014 -39.28999)
		(mid 118.646297 -39.806265)
		(end 118.425976 -40.55999)
		(stroke
			(width 0.2)
			(type default)
		)
		(layer "In1.Cu")
	)
	(gr_arc
		(start 119.238014 -36.74999)
		(mid 118.425915 -38.01999)
		(end 119.238014 -39.28999)
		(stroke
			(width 0.2)
			(type default)
		)
		(layer "In1.Cu")
	)
	(gr_arc
		(start 119.238268 -34.20999)
		(mid 118.646448 -34.726225)
		(end 118.425976 -35.47999)
		(stroke
			(width 0.2)
			(type default)
		)
		(layer "In1.Cu")
	)
	(gr_arc
		(start 119.825008 -41.959022)
		(mid 120.578797 -41.738588)
		(end 121.095008 -41.14673)
		(stroke
			(width 0.2)
			(type default)
		)
		(layer "In1.Cu")
	)
	(gr_arc
		(start 119.825008 -31.540958)
		(mid 118.835743 -31.950725)
		(end 118.425976 -32.93999)
		(stroke
			(width 0.2)
			(type default)
		)
		(layer "In1.Cu")
	)
	(gr_circle
		(center 120.015 -60.96)
		(end 121.412 -60.96)
		(stroke
			(width 0.2)
			(type default)
		)
		(fill no)
		(layer "In1.Cu")
	)
	(gr_arc
		(start 121.095008 -41.14673)
		(mid 121.611243 -41.73855)
		(end 122.365008 -41.959022)
		(stroke
			(width 0.2)
			(type default)
		)
		(layer "In1.Cu")
	)
	(gr_arc
		(start 121.095008 -32.35325)
		(mid 120.578773 -31.76143)
		(end 119.825008 -31.540958)
		(stroke
			(width 0.2)
			(type default)
		)
		(layer "In1.Cu")
	)
	(gr_circle
		(center 122.047 -136.906)
		(end 123.4694 -136.906)
		(stroke
			(width 0.2)
			(type default)
		)
		(fill no)
		(layer "In1.Cu")
	)
	(gr_arc
		(start 122.365008 -41.959022)
		(mid 123.354273 -41.549255)
		(end 123.76404 -40.55999)
		(stroke
			(width 0.2)
			(type default)
		)
		(layer "In1.Cu")
	)
	(gr_arc
		(start 122.365008 -31.540958)
		(mid 121.611219 -31.761392)
		(end 121.095008 -32.35325)
		(stroke
			(width 0.2)
			(type default)
		)
		(layer "In1.Cu")
	)
	(gr_circle
		(center 122.9106 -131.572)
		(end 123.7996 -131.572)
		(stroke
			(width 0.2)
			(type default)
		)
		(fill no)
		(layer "In1.Cu")
	)
	(gr_circle
		(center 122.9106 -126.492)
		(end 123.7996 -126.492)
		(stroke
			(width 0.2)
			(type default)
		)
		(fill no)
		(layer "In1.Cu")
	)
	(gr_arc
		(start 122.951748 -39.28999)
		(mid 123.543568 -38.773755)
		(end 123.76404 -38.01999)
		(stroke
			(width 0.2)
			(type default)
		)
		(layer "In1.Cu")
	)
	(gr_arc
		(start 122.951748 -34.20999)
		(mid 123.543568 -33.693755)
		(end 123.76404 -32.93999)
		(stroke
			(width 0.2)
			(type default)
		)
		(layer "In1.Cu")
	)
	(gr_arc
		(start 122.952002 -36.74999)
		(mid 123.543719 -36.233715)
		(end 123.76404 -35.47999)
		(stroke
			(width 0.2)
			(type default)
		)
		(layer "In1.Cu")
	)
	(gr_circle
		(center 123.6726 -131.572)
		(end 124.5616 -131.572)
		(stroke
			(width 0.2)
			(type default)
		)
		(fill no)
		(layer "In1.Cu")
	)
	(gr_circle
		(center 123.6726 -126.492)
		(end 124.5616 -126.492)
		(stroke
			(width 0.2)
			(type default)
		)
		(fill no)
		(layer "In1.Cu")
	)
	(gr_arc
		(start 123.76404 -40.55999)
		(mid 123.543606 -39.806201)
		(end 122.951748 -39.28999)
		(stroke
			(width 0.2)
			(type default)
		)
		(layer "In1.Cu")
	)
	(gr_arc
		(start 123.76404 -38.01999)
		(mid 123.543668 -37.266298)
		(end 122.952002 -36.74999)
		(stroke
			(width 0.2)
			(type default)
		)
		(layer "In1.Cu")
	)
	(gr_arc
		(start 123.76404 -35.47999)
		(mid 123.543606 -34.726201)
		(end 122.951748 -34.20999)
		(stroke
			(width 0.2)
			(type default)
		)
		(layer "In1.Cu")
	)
	(gr_arc
		(start 123.76404 -32.93999)
		(mid 123.354273 -31.950725)
		(end 122.365008 -31.540958)
		(stroke
			(width 0.2)
			(type default)
		)
		(layer "In1.Cu")
	)
	(gr_circle
		(center 131.191 -60.96)
		(end 132.588 -60.96)
		(stroke
			(width 0.2)
			(type default)
		)
		(fill no)
		(layer "In1.Cu")
	)
	(gr_circle
		(center 134.239 -136.906)
		(end 135.6614 -136.906)
		(stroke
			(width 0.2)
			(type default)
		)
		(fill no)
		(layer "In1.Cu")
	)
	(gr_circle
		(center 135.1026 -131.572)
		(end 135.9916 -131.572)
		(stroke
			(width 0.2)
			(type default)
		)
		(fill no)
		(layer "In1.Cu")
	)
	(gr_circle
		(center 135.1026 -126.492)
		(end 135.9916 -126.492)
		(stroke
			(width 0.2)
			(type default)
		)
		(fill no)
		(layer "In1.Cu")
	)
	(gr_circle
		(center 135.8646 -131.572)
		(end 136.7536 -131.572)
		(stroke
			(width 0.2)
			(type default)
		)
		(fill no)
		(layer "In1.Cu")
	)
	(gr_circle
		(center 135.8646 -126.492)
		(end 136.7536 -126.492)
		(stroke
			(width 0.2)
			(type default)
		)
		(fill no)
		(layer "In1.Cu")
	)
	(gr_circle
		(center 142.748 -112.268)
		(end 143.637 -112.268)
		(stroke
			(width 0.2)
			(type default)
		)
		(fill no)
		(layer "In1.Cu")
	)
	(gr_circle
		(center 142.850108 -77.71765)
		(end 143.739108 -77.71765)
		(stroke
			(width 0.2)
			(type default)
		)
		(fill no)
		(layer "In1.Cu")
	)
	(gr_circle
		(center 143.383 -112.268)
		(end 144.272 -112.268)
		(stroke
			(width 0.2)
			(type default)
		)
		(fill no)
		(layer "In1.Cu")
	)
	(gr_circle
		(center 144.47012 -121.209816)
		(end 146.28622 -121.209816)
		(stroke
			(width 0.2)
			(type default)
		)
		(fill no)
		(layer "In1.Cu")
	)
	(gr_circle
		(center 144.47012 -70.409816)
		(end 146.66722 -70.409816)
		(stroke
			(width 0.2)
			(type default)
		)
		(fill no)
		(layer "In1.Cu")
	)
	(gr_circle
		(center 146.431 -136.906)
		(end 147.8534 -136.906)
		(stroke
			(width 0.2)
			(type default)
		)
		(fill no)
		(layer "In1.Cu")
	)
	(gr_circle
		(center 146.939 -60.96)
		(end 148.336 -60.96)
		(stroke
			(width 0.2)
			(type default)
		)
		(fill no)
		(layer "In1.Cu")
	)
	(gr_circle
		(center 147.2946 -131.572)
		(end 148.1836 -131.572)
		(stroke
			(width 0.2)
			(type default)
		)
		(fill no)
		(layer "In1.Cu")
	)
	(gr_circle
		(center 147.2946 -126.492)
		(end 148.1836 -126.492)
		(stroke
			(width 0.2)
			(type default)
		)
		(fill no)
		(layer "In1.Cu")
	)
	(gr_circle
		(center 148.0566 -131.572)
		(end 148.9456 -131.572)
		(stroke
			(width 0.2)
			(type default)
		)
		(fill no)
		(layer "In1.Cu")
	)
	(gr_circle
		(center 148.0566 -126.492)
		(end 148.9456 -126.492)
		(stroke
			(width 0.2)
			(type default)
		)
		(fill no)
		(layer "In1.Cu")
	)
	(gr_circle
		(center 148.28012 -70.409816)
		(end 150.47722 -70.409816)
		(stroke
			(width 0.2)
			(type default)
		)
		(fill no)
		(layer "In1.Cu")
	)
	(gr_circle
		(center 149.987 -52.197)
		(end 150.876 -52.197)
		(stroke
			(width 0.2)
			(type default)
		)
		(fill no)
		(layer "In1.Cu")
	)
	(gr_circle
		(center 149.987 -51.562)
		(end 150.876 -51.562)
		(stroke
			(width 0.2)
			(type default)
		)
		(fill no)
		(layer "In1.Cu")
	)
	(gr_circle
		(center 149.987 -50.292)
		(end 150.876 -50.292)
		(stroke
			(width 0.2)
			(type default)
		)
		(fill no)
		(layer "In1.Cu")
	)
	(gr_circle
		(center 149.987 -49.657)
		(end 150.876 -49.657)
		(stroke
			(width 0.2)
			(type default)
		)
		(fill no)
		(layer "In1.Cu")
	)
	(gr_circle
		(center 155.448 -52.197)
		(end 156.337 -52.197)
		(stroke
			(width 0.2)
			(type default)
		)
		(fill no)
		(layer "In1.Cu")
	)
	(gr_circle
		(center 155.448 -51.562)
		(end 156.337 -51.562)
		(stroke
			(width 0.2)
			(type default)
		)
		(fill no)
		(layer "In1.Cu")
	)
	(gr_circle
		(center 155.448 -50.292)
		(end 156.337 -50.292)
		(stroke
			(width 0.2)
			(type default)
		)
		(fill no)
		(layer "In1.Cu")
	)
	(gr_circle
		(center 155.448 -49.657)
		(end 156.337 -49.657)
		(stroke
			(width 0.2)
			(type default)
		)
		(fill no)
		(layer "In1.Cu")
	)
	(gr_circle
		(center 158.115 -60.96)
		(end 159.512 -60.96)
		(stroke
			(width 0.2)
			(type default)
		)
		(fill no)
		(layer "In1.Cu")
	)
	(gr_circle
		(center 160.909 -52.197)
		(end 161.798 -52.197)
		(stroke
			(width 0.2)
			(type default)
		)
		(fill no)
		(layer "In1.Cu")
	)
	(gr_circle
		(center 160.909 -51.562)
		(end 161.798 -51.562)
		(stroke
			(width 0.2)
			(type default)
		)
		(fill no)
		(layer "In1.Cu")
	)
	(gr_circle
		(center 160.909 -50.292)
		(end 161.798 -50.292)
		(stroke
			(width 0.2)
			(type default)
		)
		(fill no)
		(layer "In1.Cu")
	)
	(gr_circle
		(center 160.909 -49.657)
		(end 161.798 -49.657)
		(stroke
			(width 0.2)
			(type default)
		)
		(fill no)
		(layer "In1.Cu")
	)
	(gr_circle
		(center 162.047174 -136.906)
		(end 163.469574 -136.906)
		(stroke
			(width 0.2)
			(type default)
		)
		(fill no)
		(layer "In1.Cu")
	)
	(gr_circle
		(center 162.1028 -11.811)
		(end 162.9918 -11.811)
		(stroke
			(width 0.2)
			(type default)
		)
		(fill no)
		(layer "In1.Cu")
	)
	(gr_circle
		(center 162.1028 -11.176)
		(end 162.9918 -11.176)
		(stroke
			(width 0.2)
			(type default)
		)
		(fill no)
		(layer "In1.Cu")
	)
	(gr_circle
		(center 162.7886 -10.7442)
		(end 163.6776 -10.7442)
		(stroke
			(width 0.2)
			(type default)
		)
		(fill no)
		(layer "In1.Cu")
	)
	(gr_circle
		(center 162.8394 -12.2174)
		(end 163.7284 -12.2174)
		(stroke
			(width 0.2)
			(type default)
		)
		(fill no)
		(layer "In1.Cu")
	)
	(gr_circle
		(center 162.910774 -131.572)
		(end 163.799774 -131.572)
		(stroke
			(width 0.2)
			(type default)
		)
		(fill no)
		(layer "In1.Cu")
	)
	(gr_circle
		(center 162.910774 -126.492)
		(end 163.799774 -126.492)
		(stroke
			(width 0.2)
			(type default)
		)
		(fill no)
		(layer "In1.Cu")
	)
	(gr_circle
		(center 163.672774 -131.572)
		(end 164.561774 -131.572)
		(stroke
			(width 0.2)
			(type default)
		)
		(fill no)
		(layer "In1.Cu")
	)
	(gr_circle
		(center 163.672774 -126.492)
		(end 164.561774 -126.492)
		(stroke
			(width 0.2)
			(type default)
		)
		(fill no)
		(layer "In1.Cu")
	)
	(gr_circle
		(center 166.37 -52.197)
		(end 167.259 -52.197)
		(stroke
			(width 0.2)
			(type default)
		)
		(fill no)
		(layer "In1.Cu")
	)
	(gr_circle
		(center 166.37 -51.562)
		(end 167.259 -51.562)
		(stroke
			(width 0.2)
			(type default)
		)
		(fill no)
		(layer "In1.Cu")
	)
	(gr_circle
		(center 166.37 -50.292)
		(end 167.259 -50.292)
		(stroke
			(width 0.2)
			(type default)
		)
		(fill no)
		(layer "In1.Cu")
	)
	(gr_circle
		(center 166.37 -49.657)
		(end 167.259 -49.657)
		(stroke
			(width 0.2)
			(type default)
		)
		(fill no)
		(layer "In1.Cu")
	)
	(gr_circle
		(center 169.291 -60.96)
		(end 170.688 -60.96)
		(stroke
			(width 0.2)
			(type default)
		)
		(fill no)
		(layer "In1.Cu")
	)
	(gr_circle
		(center 171.831 -52.197)
		(end 172.72 -52.197)
		(stroke
			(width 0.2)
			(type default)
		)
		(fill no)
		(layer "In1.Cu")
	)
	(gr_circle
		(center 171.831 -51.562)
		(end 172.72 -51.562)
		(stroke
			(width 0.2)
			(type default)
		)
		(fill no)
		(layer "In1.Cu")
	)
	(gr_circle
		(center 171.831 -50.292)
		(end 172.72 -50.292)
		(stroke
			(width 0.2)
			(type default)
		)
		(fill no)
		(layer "In1.Cu")
	)
	(gr_circle
		(center 171.831 -49.657)
		(end 172.72 -49.657)
		(stroke
			(width 0.2)
			(type default)
		)
		(fill no)
		(layer "In1.Cu")
	)
	(gr_circle
		(center 174.239174 -136.906)
		(end 175.661574 -136.906)
		(stroke
			(width 0.2)
			(type default)
		)
		(fill no)
		(layer "In1.Cu")
	)
	(gr_circle
		(center 175.102774 -131.572)
		(end 175.991774 -131.572)
		(stroke
			(width 0.2)
			(type default)
		)
		(fill no)
		(layer "In1.Cu")
	)
	(gr_circle
		(center 175.102774 -126.492)
		(end 175.991774 -126.492)
		(stroke
			(width 0.2)
			(type default)
		)
		(fill no)
		(layer "In1.Cu")
	)
	(gr_circle
		(center 175.864774 -131.572)
		(end 176.753774 -131.572)
		(stroke
			(width 0.2)
			(type default)
		)
		(fill no)
		(layer "In1.Cu")
	)
	(gr_circle
		(center 175.864774 -126.492)
		(end 176.753774 -126.492)
		(stroke
			(width 0.2)
			(type default)
		)
		(fill no)
		(layer "In1.Cu")
	)
	(gr_circle
		(center 177.28946 -52.197)
		(end 178.17846 -52.197)
		(stroke
			(width 0.2)
			(type default)
		)
		(fill no)
		(layer "In1.Cu")
	)
	(gr_circle
		(center 177.28946 -51.562)
		(end 178.17846 -51.562)
		(stroke
			(width 0.2)
			(type default)
		)
		(fill no)
		(layer "In1.Cu")
	)
	(gr_circle
		(center 177.28946 -50.292)
		(end 178.17846 -50.292)
		(stroke
			(width 0.2)
			(type default)
		)
		(fill no)
		(layer "In1.Cu")
	)
	(gr_circle
		(center 177.28946 -49.657)
		(end 178.17846 -49.657)
		(stroke
			(width 0.2)
			(type default)
		)
		(fill no)
		(layer "In1.Cu")
	)
	(gr_arc
		(start 179.590954 -37.949632)
		(mid 180.000721 -38.938897)
		(end 180.989986 -39.348664)
		(stroke
			(width 0.2)
			(type default)
		)
		(layer "In1.Cu")
	)
	(gr_arc
		(start 179.590954 -30.329632)
		(mid 179.811388 -31.083421)
		(end 180.403246 -31.599632)
		(stroke
			(width 0.2)
			(type default)
		)
		(layer "In1.Cu")
	)
	(gr_arc
		(start 180.403246 -36.679632)
		(mid 179.811426 -37.195867)
		(end 179.590954 -37.949632)
		(stroke
			(width 0.2)
			(type default)
		)
		(layer "In1.Cu")
	)
	(gr_arc
		(start 180.403246 -34.139632)
		(mid 179.590999 -35.409632)
		(end 180.403246 -36.679632)
		(stroke
			(width 0.2)
			(type default)
		)
		(layer "In1.Cu")
	)
	(gr_arc
		(start 180.403246 -31.599632)
		(mid 179.590999 -32.869632)
		(end 180.403246 -34.139632)
		(stroke
			(width 0.2)
			(type default)
		)
		(layer "In1.Cu")
	)
	(gr_arc
		(start 180.989986 -39.348664)
		(mid 181.743775 -39.12823)
		(end 182.259986 -38.536372)
		(stroke
			(width 0.2)
			(type default)
		)
		(layer "In1.Cu")
	)
	(gr_arc
		(start 180.989986 -28.9306)
		(mid 180.000721 -29.340367)
		(end 179.590954 -30.329632)
		(stroke
			(width 0.2)
			(type default)
		)
		(layer "In1.Cu")
	)
	(gr_arc
		(start 182.259986 -38.536372)
		(mid 182.776221 -39.128192)
		(end 183.529986 -39.348664)
		(stroke
			(width 0.2)
			(type default)
		)
		(layer "In1.Cu")
	)
	(gr_arc
		(start 182.259986 -29.742892)
		(mid 181.743751 -29.151072)
		(end 180.989986 -28.9306)
		(stroke
			(width 0.2)
			(type default)
		)
		(layer "In1.Cu")
	)
	(gr_circle
		(center 182.75046 -52.197)
		(end 183.63946 -52.197)
		(stroke
			(width 0.2)
			(type default)
		)
		(fill no)
		(layer "In1.Cu")
	)
	(gr_circle
		(center 182.75046 -51.562)
		(end 183.63946 -51.562)
		(stroke
			(width 0.2)
			(type default)
		)
		(fill no)
		(layer "In1.Cu")
	)
	(gr_circle
		(center 182.75046 -50.292)
		(end 183.63946 -50.292)
		(stroke
			(width 0.2)
			(type default)
		)
		(fill no)
		(layer "In1.Cu")
	)
	(gr_circle
		(center 182.75046 -49.657)
		(end 183.63946 -49.657)
		(stroke
			(width 0.2)
			(type default)
		)
		(fill no)
		(layer "In1.Cu")
	)
	(gr_circle
		(center 182.850282 -77.71765)
		(end 183.739282 -77.71765)
		(stroke
			(width 0.2)
			(type default)
		)
		(fill no)
		(layer "In1.Cu")
	)
	(gr_arc
		(start 183.529986 -39.348664)
		(mid 184.519251 -38.938897)
		(end 184.929018 -37.949632)
		(stroke
			(width 0.2)
			(type default)
		)
		(layer "In1.Cu")
	)
	(gr_arc
		(start 183.529986 -28.9306)
		(mid 182.776197 -29.151034)
		(end 182.259986 -29.742892)
		(stroke
			(width 0.2)
			(type default)
		)
		(layer "In1.Cu")
	)
	(gr_arc
		(start 184.116726 -36.679632)
		(mid 184.928973 -35.409632)
		(end 184.116726 -34.139632)
		(stroke
			(width 0.2)
			(type default)
		)
		(layer "In1.Cu")
	)
	(gr_arc
		(start 184.116726 -34.139632)
		(mid 184.708546 -33.623397)
		(end 184.929018 -32.869632)
		(stroke
			(width 0.2)
			(type default)
		)
		(layer "In1.Cu")
	)
	(gr_arc
		(start 184.116726 -31.599632)
		(mid 184.708546 -31.083397)
		(end 184.929018 -30.329632)
		(stroke
			(width 0.2)
			(type default)
		)
		(layer "In1.Cu")
	)
	(gr_circle
		(center 184.470294 -121.209816)
		(end 186.286394 -121.209816)
		(stroke
			(width 0.2)
			(type default)
		)
		(fill no)
		(layer "In1.Cu")
	)
	(gr_circle
		(center 184.470294 -70.409816)
		(end 186.667394 -70.409816)
		(stroke
			(width 0.2)
			(type default)
		)
		(fill no)
		(layer "In1.Cu")
	)
	(gr_arc
		(start 184.929018 -37.949632)
		(mid 184.708584 -37.195843)
		(end 184.116726 -36.679632)
		(stroke
			(width 0.2)
			(type default)
		)
		(layer "In1.Cu")
	)
	(gr_arc
		(start 184.929018 -32.869632)
		(mid 184.708584 -32.115843)
		(end 184.116726 -31.599632)
		(stroke
			(width 0.2)
			(type default)
		)
		(layer "In1.Cu")
	)
	(gr_arc
		(start 184.929018 -30.329632)
		(mid 184.519251 -29.340367)
		(end 183.529986 -28.9306)
		(stroke
			(width 0.2)
			(type default)
		)
		(layer "In1.Cu")
	)
	(gr_circle
		(center 186.431174 -136.906)
		(end 187.853574 -136.906)
		(stroke
			(width 0.2)
			(type default)
		)
		(fill no)
		(layer "In1.Cu")
	)
	(gr_circle
		(center 186.939174 -60.96)
		(end 188.336174 -60.96)
		(stroke
			(width 0.2)
			(type default)
		)
		(fill no)
		(layer "In1.Cu")
	)
	(gr_circle
		(center 187.294774 -131.572)
		(end 188.183774 -131.572)
		(stroke
			(width 0.2)
			(type default)
		)
		(fill no)
		(layer "In1.Cu")
	)
	(gr_circle
		(center 187.294774 -126.492)
		(end 188.183774 -126.492)
		(stroke
			(width 0.2)
			(type default)
		)
		(fill no)
		(layer "In1.Cu")
	)
	(gr_circle
		(center 188.056774 -131.572)
		(end 188.945774 -131.572)
		(stroke
			(width 0.2)
			(type default)
		)
		(fill no)
		(layer "In1.Cu")
	)
	(gr_circle
		(center 188.056774 -126.492)
		(end 188.945774 -126.492)
		(stroke
			(width 0.2)
			(type default)
		)
		(fill no)
		(layer "In1.Cu")
	)
	(gr_circle
		(center 188.280294 -70.409816)
		(end 190.477394 -70.409816)
		(stroke
			(width 0.2)
			(type default)
		)
		(fill no)
		(layer "In1.Cu")
	)
	(gr_arc
		(start 188.480954 -37.949632)
		(mid 188.890721 -38.938897)
		(end 189.879986 -39.348664)
		(stroke
			(width 0.2)
			(type default)
		)
		(layer "In1.Cu")
	)
	(gr_arc
		(start 188.480954 -32.869632)
		(mid 188.701388 -33.623421)
		(end 189.293246 -34.139632)
		(stroke
			(width 0.2)
			(type default)
		)
		(layer "In1.Cu")
	)
	(gr_arc
		(start 188.480954 -30.329632)
		(mid 188.701388 -31.083421)
		(end 189.293246 -31.599632)
		(stroke
			(width 0.2)
			(type default)
		)
		(layer "In1.Cu")
	)
	(gr_arc
		(start 189.293246 -36.679632)
		(mid 188.701426 -37.195867)
		(end 188.480954 -37.949632)
		(stroke
			(width 0.2)
			(type default)
		)
		(layer "In1.Cu")
	)
	(gr_arc
		(start 189.293246 -34.139632)
		(mid 188.480999 -35.409632)
		(end 189.293246 -36.679632)
		(stroke
			(width 0.2)
			(type default)
		)
		(layer "In1.Cu")
	)
	(gr_arc
		(start 189.293246 -31.599632)
		(mid 188.701426 -32.115867)
		(end 188.480954 -32.869632)
		(stroke
			(width 0.2)
			(type default)
		)
		(layer "In1.Cu")
	)
	(gr_arc
		(start 189.879986 -39.348664)
		(mid 190.633775 -39.12823)
		(end 191.149986 -38.536372)
		(stroke
			(width 0.2)
			(type default)
		)
		(layer "In1.Cu")
	)
	(gr_arc
		(start 189.879986 -28.9306)
		(mid 188.890721 -29.340367)
		(end 188.480954 -30.329632)
		(stroke
			(width 0.2)
			(type default)
		)
		(layer "In1.Cu")
	)
	(gr_arc
		(start 191.149986 -38.536372)
		(mid 191.666221 -39.128192)
		(end 192.419986 -39.348664)
		(stroke
			(width 0.2)
			(type default)
		)
		(layer "In1.Cu")
	)
	(gr_arc
		(start 191.149986 -29.742892)
		(mid 190.633751 -29.151072)
		(end 189.879986 -28.9306)
		(stroke
			(width 0.2)
			(type default)
		)
		(layer "In1.Cu")
	)
	(gr_arc
		(start 192.419986 -39.348664)
		(mid 193.409251 -38.938897)
		(end 193.819018 -37.949632)
		(stroke
			(width 0.2)
			(type default)
		)
		(layer "In1.Cu")
	)
	(gr_arc
		(start 192.419986 -28.9306)
		(mid 191.666197 -29.151034)
		(end 191.149986 -29.742892)
		(stroke
			(width 0.2)
			(type default)
		)
		(layer "In1.Cu")
	)
	(gr_arc
		(start 193.006726 -36.679632)
		(mid 193.818973 -35.409632)
		(end 193.006726 -34.139632)
		(stroke
			(width 0.2)
			(type default)
		)
		(layer "In1.Cu")
	)
	(gr_arc
		(start 193.006726 -34.139632)
		(mid 193.818973 -32.869632)
		(end 193.006726 -31.599632)
		(stroke
			(width 0.2)
			(type default)
		)
		(layer "In1.Cu")
	)
	(gr_arc
		(start 193.006726 -31.599632)
		(mid 193.598546 -31.083397)
		(end 193.819018 -30.329632)
		(stroke
			(width 0.2)
			(type default)
		)
		(layer "In1.Cu")
	)
	(gr_arc
		(start 193.819018 -37.949632)
		(mid 193.598584 -37.195843)
		(end 193.006726 -36.679632)
		(stroke
			(width 0.2)
			(type default)
		)
		(layer "In1.Cu")
	)
	(gr_arc
		(start 193.819018 -30.329632)
		(mid 193.409251 -29.340367)
		(end 192.419986 -28.9306)
		(stroke
			(width 0.2)
			(type default)
		)
		(layer "In1.Cu")
	)
	(gr_arc
		(start 197.370954 -37.949632)
		(mid 197.780721 -38.938897)
		(end 198.769986 -39.348664)
		(stroke
			(width 0.2)
			(type default)
		)
		(layer "In1.Cu")
	)
	(gr_arc
		(start 197.370954 -35.409632)
		(mid 197.591388 -36.163421)
		(end 198.183246 -36.679632)
		(stroke
			(width 0.2)
			(type default)
		)
		(layer "In1.Cu")
	)
	(gr_arc
		(start 197.370954 -30.329632)
		(mid 197.591388 -31.083421)
		(end 198.183246 -31.599632)
		(stroke
			(width 0.2)
			(type default)
		)
		(layer "In1.Cu")
	)
	(gr_circle
		(center 198.115174 -60.96)
		(end 199.512174 -60.96)
		(stroke
			(width 0.2)
			(type default)
		)
		(fill no)
		(layer "In1.Cu")
	)
	(gr_arc
		(start 198.183246 -36.679632)
		(mid 197.591426 -37.195867)
		(end 197.370954 -37.949632)
		(stroke
			(width 0.2)
			(type default)
		)
		(layer "In1.Cu")
	)
	(gr_arc
		(start 198.183246 -34.139632)
		(mid 197.591426 -34.655867)
		(end 197.370954 -35.409632)
		(stroke
			(width 0.2)
			(type default)
		)
		(layer "In1.Cu")
	)
	(gr_arc
		(start 198.183246 -31.599632)
		(mid 197.370999 -32.869632)
		(end 198.183246 -34.139632)
		(stroke
			(width 0.2)
			(type default)
		)
		(layer "In1.Cu")
	)
	(gr_arc
		(start 198.769986 -39.348664)
		(mid 199.523775 -39.12823)
		(end 200.039986 -38.536372)
		(stroke
			(width 0.2)
			(type default)
		)
		(layer "In1.Cu")
	)
	(gr_arc
		(start 198.769986 -28.9306)
		(mid 197.780721 -29.340367)
		(end 197.370954 -30.329632)
		(stroke
			(width 0.2)
			(type default)
		)
		(layer "In1.Cu")
	)
	(gr_arc
		(start 200.039986 -38.536372)
		(mid 200.556221 -39.128192)
		(end 201.309986 -39.348664)
		(stroke
			(width 0.2)
			(type default)
		)
		(layer "In1.Cu")
	)
	(gr_arc
		(start 200.039986 -29.742892)
		(mid 199.523751 -29.151072)
		(end 198.769986 -28.9306)
		(stroke
			(width 0.2)
			(type default)
		)
		(layer "In1.Cu")
	)
	(gr_arc
		(start 201.309986 -39.348664)
		(mid 202.299251 -38.938897)
		(end 202.709018 -37.949632)
		(stroke
			(width 0.2)
			(type default)
		)
		(layer "In1.Cu")
	)
	(gr_arc
		(start 201.309986 -28.9306)
		(mid 200.556197 -29.151034)
		(end 200.039986 -29.742892)
		(stroke
			(width 0.2)
			(type default)
		)
		(layer "In1.Cu")
	)
	(gr_arc
		(start 201.896726 -36.679632)
		(mid 202.708973 -35.409632)
		(end 201.896726 -34.139632)
		(stroke
			(width 0.2)
			(type default)
		)
		(layer "In1.Cu")
	)
	(gr_arc
		(start 201.896726 -34.139632)
		(mid 202.708973 -32.869632)
		(end 201.896726 -31.599632)
		(stroke
			(width 0.2)
			(type default)
		)
		(layer "In1.Cu")
	)
	(gr_arc
		(start 201.896726 -31.599632)
		(mid 202.488546 -31.083397)
		(end 202.709018 -30.329632)
		(stroke
			(width 0.2)
			(type default)
		)
		(layer "In1.Cu")
	)
	(gr_circle
		(center 202.3364 -105.883202)
		(end 203.2254 -105.883202)
		(stroke
			(width 0.2)
			(type default)
		)
		(fill no)
		(layer "In1.Cu")
	)
	(gr_circle
		(center 202.3364 -105.121202)
		(end 203.2254 -105.121202)
		(stroke
			(width 0.2)
			(type default)
		)
		(fill no)
		(layer "In1.Cu")
	)
	(gr_circle
		(center 202.3364 -104.418638)
		(end 203.2254 -104.418638)
		(stroke
			(width 0.2)
			(type default)
		)
		(fill no)
		(layer "In1.Cu")
	)
	(gr_circle
		(center 202.3364 -103.656638)
		(end 203.2254 -103.656638)
		(stroke
			(width 0.2)
			(type default)
		)
		(fill no)
		(layer "In1.Cu")
	)
	(gr_circle
		(center 202.3364 -102.894638)
		(end 203.2254 -102.894638)
		(stroke
			(width 0.2)
			(type default)
		)
		(fill no)
		(layer "In1.Cu")
	)
	(gr_circle
		(center 202.35037 -122.809762)
		(end 203.23937 -122.809762)
		(stroke
			(width 0.2)
			(type default)
		)
		(fill no)
		(layer "In1.Cu")
	)
	(gr_circle
		(center 202.35037 -122.047762)
		(end 203.23937 -122.047762)
		(stroke
			(width 0.2)
			(type default)
		)
		(fill no)
		(layer "In1.Cu")
	)
	(gr_circle
		(center 202.35037 -121.331736)
		(end 203.23937 -121.331736)
		(stroke
			(width 0.2)
			(type default)
		)
		(fill no)
		(layer "In1.Cu")
	)
	(gr_circle
		(center 202.35037 -120.569736)
		(end 203.23937 -120.569736)
		(stroke
			(width 0.2)
			(type default)
		)
		(fill no)
		(layer "In1.Cu")
	)
	(gr_circle
		(center 202.364086 -123.528328)
		(end 203.253086 -123.528328)
		(stroke
			(width 0.2)
			(type default)
		)
		(fill no)
		(layer "In1.Cu")
	)
	(gr_arc
		(start 202.709018 -37.949632)
		(mid 202.488584 -37.195843)
		(end 201.896726 -36.679632)
		(stroke
			(width 0.2)
			(type default)
		)
		(layer "In1.Cu")
	)
	(gr_arc
		(start 202.709018 -30.329632)
		(mid 202.299251 -29.340367)
		(end 201.309986 -28.9306)
		(stroke
			(width 0.2)
			(type default)
		)
		(layer "In1.Cu")
	)
	(gr_circle
		(center 203.028042 -105.896664)
		(end 203.917042 -105.896664)
		(stroke
			(width 0.2)
			(type default)
		)
		(fill no)
		(layer "In1.Cu")
	)
	(gr_circle
		(center 203.028042 -105.134664)
		(end 203.917042 -105.134664)
		(stroke
			(width 0.2)
			(type default)
		)
		(fill no)
		(layer "In1.Cu")
	)
	(gr_circle
		(center 203.028042 -104.4321)
		(end 203.917042 -104.4321)
		(stroke
			(width 0.2)
			(type default)
		)
		(fill no)
		(layer "In1.Cu")
	)
	(gr_circle
		(center 203.028042 -103.6701)
		(end 203.917042 -103.6701)
		(stroke
			(width 0.2)
			(type default)
		)
		(fill no)
		(layer "In1.Cu")
	)
	(gr_circle
		(center 203.028042 -102.9081)
		(end 203.917042 -102.9081)
		(stroke
			(width 0.2)
			(type default)
		)
		(fill no)
		(layer "In1.Cu")
	)
	(gr_circle
		(center 203.11237 -122.809762)
		(end 204.00137 -122.809762)
		(stroke
			(width 0.2)
			(type default)
		)
		(fill no)
		(layer "In1.Cu")
	)
	(gr_circle
		(center 203.11237 -122.047762)
		(end 204.00137 -122.047762)
		(stroke
			(width 0.2)
			(type default)
		)
		(fill no)
		(layer "In1.Cu")
	)
	(gr_circle
		(center 203.11237 -121.331736)
		(end 204.00137 -121.331736)
		(stroke
			(width 0.2)
			(type default)
		)
		(fill no)
		(layer "In1.Cu")
	)
	(gr_circle
		(center 203.11237 -120.569736)
		(end 204.00137 -120.569736)
		(stroke
			(width 0.2)
			(type default)
		)
		(fill no)
		(layer "In1.Cu")
	)
	(gr_circle
		(center 203.126086 -123.528328)
		(end 204.015086 -123.528328)
		(stroke
			(width 0.2)
			(type default)
		)
		(fill no)
		(layer "In1.Cu")
	)
	(gr_circle
		(center 203.790042 -105.896664)
		(end 204.679042 -105.896664)
		(stroke
			(width 0.2)
			(type default)
		)
		(fill no)
		(layer "In1.Cu")
	)
	(gr_circle
		(center 203.790042 -105.134664)
		(end 204.679042 -105.134664)
		(stroke
			(width 0.2)
			(type default)
		)
		(fill no)
		(layer "In1.Cu")
	)
	(gr_circle
		(center 203.790042 -104.4321)
		(end 204.679042 -104.4321)
		(stroke
			(width 0.2)
			(type default)
		)
		(fill no)
		(layer "In1.Cu")
	)
	(gr_circle
		(center 203.790042 -103.6701)
		(end 204.679042 -103.6701)
		(stroke
			(width 0.2)
			(type default)
		)
		(fill no)
		(layer "In1.Cu")
	)
	(gr_circle
		(center 203.790042 -102.9081)
		(end 204.679042 -102.9081)
		(stroke
			(width 0.2)
			(type default)
		)
		(fill no)
		(layer "In1.Cu")
	)
	(gr_circle
		(center 203.87437 -122.809762)
		(end 204.76337 -122.809762)
		(stroke
			(width 0.2)
			(type default)
		)
		(fill no)
		(layer "In1.Cu")
	)
	(gr_circle
		(center 203.87437 -122.047762)
		(end 204.76337 -122.047762)
		(stroke
			(width 0.2)
			(type default)
		)
		(fill no)
		(layer "In1.Cu")
	)
	(gr_circle
		(center 203.87437 -121.331736)
		(end 204.76337 -121.331736)
		(stroke
			(width 0.2)
			(type default)
		)
		(fill no)
		(layer "In1.Cu")
	)
	(gr_circle
		(center 203.87437 -120.569736)
		(end 204.76337 -120.569736)
		(stroke
			(width 0.2)
			(type default)
		)
		(fill no)
		(layer "In1.Cu")
	)
	(gr_circle
		(center 203.888086 -123.528328)
		(end 204.777086 -123.528328)
		(stroke
			(width 0.2)
			(type default)
		)
		(fill no)
		(layer "In1.Cu")
	)
	(gr_circle
		(center 204.552042 -105.896664)
		(end 205.441042 -105.896664)
		(stroke
			(width 0.2)
			(type default)
		)
		(fill no)
		(layer "In1.Cu")
	)
	(gr_circle
		(center 204.552042 -105.134664)
		(end 205.441042 -105.134664)
		(stroke
			(width 0.2)
			(type default)
		)
		(fill no)
		(layer "In1.Cu")
	)
	(gr_circle
		(center 204.552042 -104.4321)
		(end 205.441042 -104.4321)
		(stroke
			(width 0.2)
			(type default)
		)
		(fill no)
		(layer "In1.Cu")
	)
	(gr_circle
		(center 204.552042 -103.6701)
		(end 205.441042 -103.6701)
		(stroke
			(width 0.2)
			(type default)
		)
		(fill no)
		(layer "In1.Cu")
	)
	(gr_circle
		(center 204.552042 -102.9081)
		(end 205.441042 -102.9081)
		(stroke
			(width 0.2)
			(type default)
		)
		(fill no)
		(layer "In1.Cu")
	)
	(gr_circle
		(center 204.63637 -122.809762)
		(end 205.52537 -122.809762)
		(stroke
			(width 0.2)
			(type default)
		)
		(fill no)
		(layer "In1.Cu")
	)
	(gr_circle
		(center 204.63637 -122.047762)
		(end 205.52537 -122.047762)
		(stroke
			(width 0.2)
			(type default)
		)
		(fill no)
		(layer "In1.Cu")
	)
	(gr_circle
		(center 204.63637 -121.331736)
		(end 205.52537 -121.331736)
		(stroke
			(width 0.2)
			(type default)
		)
		(fill no)
		(layer "In1.Cu")
	)
	(gr_circle
		(center 204.63637 -120.569736)
		(end 205.52537 -120.569736)
		(stroke
			(width 0.2)
			(type default)
		)
		(fill no)
		(layer "In1.Cu")
	)
	(gr_circle
		(center 204.650086 -123.528328)
		(end 205.539086 -123.528328)
		(stroke
			(width 0.2)
			(type default)
		)
		(fill no)
		(layer "In1.Cu")
	)
	(gr_circle
		(center 205.314042 -105.896664)
		(end 206.203042 -105.896664)
		(stroke
			(width 0.2)
			(type default)
		)
		(fill no)
		(layer "In1.Cu")
	)
	(gr_circle
		(center 205.314042 -105.134664)
		(end 206.203042 -105.134664)
		(stroke
			(width 0.2)
			(type default)
		)
		(fill no)
		(layer "In1.Cu")
	)
	(gr_circle
		(center 205.314042 -104.4321)
		(end 206.203042 -104.4321)
		(stroke
			(width 0.2)
			(type default)
		)
		(fill no)
		(layer "In1.Cu")
	)
	(gr_circle
		(center 205.314042 -103.6701)
		(end 206.203042 -103.6701)
		(stroke
			(width 0.2)
			(type default)
		)
		(fill no)
		(layer "In1.Cu")
	)
	(gr_circle
		(center 205.314042 -102.9081)
		(end 206.203042 -102.9081)
		(stroke
			(width 0.2)
			(type default)
		)
		(fill no)
		(layer "In1.Cu")
	)
	(gr_circle
		(center 205.39837 -122.809762)
		(end 206.28737 -122.809762)
		(stroke
			(width 0.2)
			(type default)
		)
		(fill no)
		(layer "In1.Cu")
	)
	(gr_circle
		(center 205.39837 -122.047762)
		(end 206.28737 -122.047762)
		(stroke
			(width 0.2)
			(type default)
		)
		(fill no)
		(layer "In1.Cu")
	)
	(gr_circle
		(center 205.39837 -121.331736)
		(end 206.28737 -121.331736)
		(stroke
			(width 0.2)
			(type default)
		)
		(fill no)
		(layer "In1.Cu")
	)
	(gr_circle
		(center 205.39837 -120.569736)
		(end 206.28737 -120.569736)
		(stroke
			(width 0.2)
			(type default)
		)
		(fill no)
		(layer "In1.Cu")
	)
	(gr_circle
		(center 205.412086 -123.528328)
		(end 206.301086 -123.528328)
		(stroke
			(width 0.2)
			(type default)
		)
		(fill no)
		(layer "In1.Cu")
	)
	(gr_circle
		(center 206.076042 -105.896664)
		(end 206.965042 -105.896664)
		(stroke
			(width 0.2)
			(type default)
		)
		(fill no)
		(layer "In1.Cu")
	)
	(gr_circle
		(center 206.076042 -105.134664)
		(end 206.965042 -105.134664)
		(stroke
			(width 0.2)
			(type default)
		)
		(fill no)
		(layer "In1.Cu")
	)
	(gr_circle
		(center 206.076042 -104.4321)
		(end 206.965042 -104.4321)
		(stroke
			(width 0.2)
			(type default)
		)
		(fill no)
		(layer "In1.Cu")
	)
	(gr_circle
		(center 206.076042 -103.6701)
		(end 206.965042 -103.6701)
		(stroke
			(width 0.2)
			(type default)
		)
		(fill no)
		(layer "In1.Cu")
	)
	(gr_circle
		(center 206.076042 -102.9081)
		(end 206.965042 -102.9081)
		(stroke
			(width 0.2)
			(type default)
		)
		(fill no)
		(layer "In1.Cu")
	)
	(gr_circle
		(center 206.16037 -122.809762)
		(end 207.04937 -122.809762)
		(stroke
			(width 0.2)
			(type default)
		)
		(fill no)
		(layer "In1.Cu")
	)
	(gr_circle
		(center 206.16037 -122.047762)
		(end 207.04937 -122.047762)
		(stroke
			(width 0.2)
			(type default)
		)
		(fill no)
		(layer "In1.Cu")
	)
	(gr_circle
		(center 206.16037 -121.331736)
		(end 207.04937 -121.331736)
		(stroke
			(width 0.2)
			(type default)
		)
		(fill no)
		(layer "In1.Cu")
	)
	(gr_circle
		(center 206.16037 -120.569736)
		(end 207.04937 -120.569736)
		(stroke
			(width 0.2)
			(type default)
		)
		(fill no)
		(layer "In1.Cu")
	)
	(gr_circle
		(center 206.174086 -123.528328)
		(end 207.063086 -123.528328)
		(stroke
			(width 0.2)
			(type default)
		)
		(fill no)
		(layer "In1.Cu")
	)
	(gr_circle
		(center 206.838042 -105.896664)
		(end 207.727042 -105.896664)
		(stroke
			(width 0.2)
			(type default)
		)
		(fill no)
		(layer "In1.Cu")
	)
	(gr_circle
		(center 206.838042 -105.134664)
		(end 207.727042 -105.134664)
		(stroke
			(width 0.2)
			(type default)
		)
		(fill no)
		(layer "In1.Cu")
	)
	(gr_circle
		(center 206.838042 -104.4321)
		(end 207.727042 -104.4321)
		(stroke
			(width 0.2)
			(type default)
		)
		(fill no)
		(layer "In1.Cu")
	)
	(gr_circle
		(center 206.838042 -103.6701)
		(end 207.727042 -103.6701)
		(stroke
			(width 0.2)
			(type default)
		)
		(fill no)
		(layer "In1.Cu")
	)
	(gr_circle
		(center 206.838042 -102.9081)
		(end 207.727042 -102.9081)
		(stroke
			(width 0.2)
			(type default)
		)
		(fill no)
		(layer "In1.Cu")
	)
	(gr_circle
		(center 206.92237 -122.809762)
		(end 207.81137 -122.809762)
		(stroke
			(width 0.2)
			(type default)
		)
		(fill no)
		(layer "In1.Cu")
	)
	(gr_circle
		(center 206.92237 -122.047762)
		(end 207.81137 -122.047762)
		(stroke
			(width 0.2)
			(type default)
		)
		(fill no)
		(layer "In1.Cu")
	)
	(gr_circle
		(center 206.92237 -121.331736)
		(end 207.81137 -121.331736)
		(stroke
			(width 0.2)
			(type default)
		)
		(fill no)
		(layer "In1.Cu")
	)
	(gr_circle
		(center 206.92237 -120.569736)
		(end 207.81137 -120.569736)
		(stroke
			(width 0.2)
			(type default)
		)
		(fill no)
		(layer "In1.Cu")
	)
	(gr_circle
		(center 206.936086 -123.528328)
		(end 207.825086 -123.528328)
		(stroke
			(width 0.2)
			(type default)
		)
		(fill no)
		(layer "In1.Cu")
	)
	(gr_circle
		(center 207.556862 -105.882948)
		(end 208.445862 -105.882948)
		(stroke
			(width 0.2)
			(type default)
		)
		(fill no)
		(layer "In1.Cu")
	)
	(gr_circle
		(center 207.556862 -105.120948)
		(end 208.445862 -105.120948)
		(stroke
			(width 0.2)
			(type default)
		)
		(fill no)
		(layer "In1.Cu")
	)
	(gr_circle
		(center 207.556862 -104.418384)
		(end 208.445862 -104.418384)
		(stroke
			(width 0.2)
			(type default)
		)
		(fill no)
		(layer "In1.Cu")
	)
	(gr_circle
		(center 207.556862 -103.656384)
		(end 208.445862 -103.656384)
		(stroke
			(width 0.2)
			(type default)
		)
		(fill no)
		(layer "In1.Cu")
	)
	(gr_circle
		(center 207.556862 -102.894384)
		(end 208.445862 -102.894384)
		(stroke
			(width 0.2)
			(type default)
		)
		(fill no)
		(layer "In1.Cu")
	)
	(gr_circle
		(center 207.68437 -122.809762)
		(end 208.57337 -122.809762)
		(stroke
			(width 0.2)
			(type default)
		)
		(fill no)
		(layer "In1.Cu")
	)
	(gr_circle
		(center 207.68437 -122.047762)
		(end 208.57337 -122.047762)
		(stroke
			(width 0.2)
			(type default)
		)
		(fill no)
		(layer "In1.Cu")
	)
	(gr_circle
		(center 207.68437 -121.331736)
		(end 208.57337 -121.331736)
		(stroke
			(width 0.2)
			(type default)
		)
		(fill no)
		(layer "In1.Cu")
	)
	(gr_circle
		(center 207.68437 -120.569736)
		(end 208.57337 -120.569736)
		(stroke
			(width 0.2)
			(type default)
		)
		(fill no)
		(layer "In1.Cu")
	)
	(gr_circle
		(center 207.698086 -123.528328)
		(end 208.587086 -123.528328)
		(stroke
			(width 0.2)
			(type default)
		)
		(fill no)
		(layer "In1.Cu")
	)
	(gr_circle
		(center 209.291174 -60.96)
		(end 210.688174 -60.96)
		(stroke
			(width 0.2)
			(type default)
		)
		(fill no)
		(layer "In1.Cu")
	)
	(gr_circle
		(center 213.978236 -132.959856)
		(end 214.867236 -132.959856)
		(stroke
			(width 0.2)
			(type default)
		)
		(fill no)
		(layer "In1.Cu")
	)
	(gr_circle
		(center 213.978236 -132.197856)
		(end 214.867236 -132.197856)
		(stroke
			(width 0.2)
			(type default)
		)
		(fill no)
		(layer "In1.Cu")
	)
	(gr_circle
		(center 213.978236 -131.435856)
		(end 214.867236 -131.435856)
		(stroke
			(width 0.2)
			(type default)
		)
		(fill no)
		(layer "In1.Cu")
	)
	(gr_circle
		(center 213.978236 -130.673856)
		(end 214.867236 -130.673856)
		(stroke
			(width 0.2)
			(type default)
		)
		(fill no)
		(layer "In1.Cu")
	)
	(gr_circle
		(center 213.978236 -129.911856)
		(end 214.867236 -129.911856)
		(stroke
			(width 0.2)
			(type default)
		)
		(fill no)
		(layer "In1.Cu")
	)
	(gr_circle
		(center 213.978236 -129.149856)
		(end 214.867236 -129.149856)
		(stroke
			(width 0.2)
			(type default)
		)
		(fill no)
		(layer "In1.Cu")
	)
	(gr_circle
		(center 213.978236 -128.387856)
		(end 214.867236 -128.387856)
		(stroke
			(width 0.2)
			(type default)
		)
		(fill no)
		(layer "In1.Cu")
	)
	(gr_circle
		(center 213.978236 -127.625856)
		(end 214.867236 -127.625856)
		(stroke
			(width 0.2)
			(type default)
		)
		(fill no)
		(layer "In1.Cu")
	)
	(gr_circle
		(center 214.696802 -132.94614)
		(end 215.585802 -132.94614)
		(stroke
			(width 0.2)
			(type default)
		)
		(fill no)
		(layer "In1.Cu")
	)
	(gr_circle
		(center 214.696802 -132.18414)
		(end 215.585802 -132.18414)
		(stroke
			(width 0.2)
			(type default)
		)
		(fill no)
		(layer "In1.Cu")
	)
	(gr_circle
		(center 214.696802 -131.42214)
		(end 215.585802 -131.42214)
		(stroke
			(width 0.2)
			(type default)
		)
		(fill no)
		(layer "In1.Cu")
	)
	(gr_circle
		(center 214.696802 -130.66014)
		(end 215.585802 -130.66014)
		(stroke
			(width 0.2)
			(type default)
		)
		(fill no)
		(layer "In1.Cu")
	)
	(gr_circle
		(center 214.696802 -129.89814)
		(end 215.585802 -129.89814)
		(stroke
			(width 0.2)
			(type default)
		)
		(fill no)
		(layer "In1.Cu")
	)
	(gr_circle
		(center 214.696802 -129.13614)
		(end 215.585802 -129.13614)
		(stroke
			(width 0.2)
			(type default)
		)
		(fill no)
		(layer "In1.Cu")
	)
	(gr_circle
		(center 214.696802 -128.37414)
		(end 215.585802 -128.37414)
		(stroke
			(width 0.2)
			(type default)
		)
		(fill no)
		(layer "In1.Cu")
	)
	(gr_circle
		(center 214.696802 -127.61214)
		(end 215.585802 -127.61214)
		(stroke
			(width 0.2)
			(type default)
		)
		(fill no)
		(layer "In1.Cu")
	)
	(gr_circle
		(center 215.23706 -98.013012)
		(end 216.12606 -98.013012)
		(stroke
			(width 0.2)
			(type default)
		)
		(fill no)
		(layer "In1.Cu")
	)
	(gr_circle
		(center 215.458802 -132.94614)
		(end 216.347802 -132.94614)
		(stroke
			(width 0.2)
			(type default)
		)
		(fill no)
		(layer "In1.Cu")
	)
	(gr_circle
		(center 215.458802 -132.18414)
		(end 216.347802 -132.18414)
		(stroke
			(width 0.2)
			(type default)
		)
		(fill no)
		(layer "In1.Cu")
	)
	(gr_circle
		(center 215.458802 -131.42214)
		(end 216.347802 -131.42214)
		(stroke
			(width 0.2)
			(type default)
		)
		(fill no)
		(layer "In1.Cu")
	)
	(gr_circle
		(center 215.458802 -130.66014)
		(end 216.347802 -130.66014)
		(stroke
			(width 0.2)
			(type default)
		)
		(fill no)
		(layer "In1.Cu")
	)
	(gr_circle
		(center 215.458802 -129.89814)
		(end 216.347802 -129.89814)
		(stroke
			(width 0.2)
			(type default)
		)
		(fill no)
		(layer "In1.Cu")
	)
	(gr_circle
		(center 215.458802 -129.13614)
		(end 216.347802 -129.13614)
		(stroke
			(width 0.2)
			(type default)
		)
		(fill no)
		(layer "In1.Cu")
	)
	(gr_circle
		(center 215.458802 -128.37414)
		(end 216.347802 -128.37414)
		(stroke
			(width 0.2)
			(type default)
		)
		(fill no)
		(layer "In1.Cu")
	)
	(gr_circle
		(center 215.458802 -127.61214)
		(end 216.347802 -127.61214)
		(stroke
			(width 0.2)
			(type default)
		)
		(fill no)
		(layer "In1.Cu")
	)
	(gr_circle
		(center 215.646 -101.346)
		(end 216.535 -101.346)
		(stroke
			(width 0.2)
			(type default)
		)
		(fill no)
		(layer "In1.Cu")
	)
	(gr_circle
		(center 215.99906 -98.013012)
		(end 216.88806 -98.013012)
		(stroke
			(width 0.2)
			(type default)
		)
		(fill no)
		(layer "In1.Cu")
	)
	(gr_circle
		(center 216.174828 -132.94614)
		(end 217.063828 -132.94614)
		(stroke
			(width 0.2)
			(type default)
		)
		(fill no)
		(layer "In1.Cu")
	)
	(gr_circle
		(center 216.174828 -132.18414)
		(end 217.063828 -132.18414)
		(stroke
			(width 0.2)
			(type default)
		)
		(fill no)
		(layer "In1.Cu")
	)
	(gr_circle
		(center 216.174828 -131.42214)
		(end 217.063828 -131.42214)
		(stroke
			(width 0.2)
			(type default)
		)
		(fill no)
		(layer "In1.Cu")
	)
	(gr_circle
		(center 216.174828 -130.66014)
		(end 217.063828 -130.66014)
		(stroke
			(width 0.2)
			(type default)
		)
		(fill no)
		(layer "In1.Cu")
	)
	(gr_circle
		(center 216.174828 -129.89814)
		(end 217.063828 -129.89814)
		(stroke
			(width 0.2)
			(type default)
		)
		(fill no)
		(layer "In1.Cu")
	)
	(gr_circle
		(center 216.174828 -129.13614)
		(end 217.063828 -129.13614)
		(stroke
			(width 0.2)
			(type default)
		)
		(fill no)
		(layer "In1.Cu")
	)
	(gr_circle
		(center 216.174828 -128.37414)
		(end 217.063828 -128.37414)
		(stroke
			(width 0.2)
			(type default)
		)
		(fill no)
		(layer "In1.Cu")
	)
	(gr_circle
		(center 216.174828 -127.61214)
		(end 217.063828 -127.61214)
		(stroke
			(width 0.2)
			(type default)
		)
		(fill no)
		(layer "In1.Cu")
	)
	(gr_circle
		(center 216.727278 -122.809762)
		(end 217.616278 -122.809762)
		(stroke
			(width 0.2)
			(type default)
		)
		(fill no)
		(layer "In1.Cu")
	)
	(gr_circle
		(center 216.727278 -122.047762)
		(end 217.616278 -122.047762)
		(stroke
			(width 0.2)
			(type default)
		)
		(fill no)
		(layer "In1.Cu")
	)
	(gr_circle
		(center 216.727278 -121.331736)
		(end 217.616278 -121.331736)
		(stroke
			(width 0.2)
			(type default)
		)
		(fill no)
		(layer "In1.Cu")
	)
	(gr_circle
		(center 216.727278 -120.569736)
		(end 217.616278 -120.569736)
		(stroke
			(width 0.2)
			(type default)
		)
		(fill no)
		(layer "In1.Cu")
	)
	(gr_circle
		(center 216.740994 -123.528328)
		(end 217.629994 -123.528328)
		(stroke
			(width 0.2)
			(type default)
		)
		(fill no)
		(layer "In1.Cu")
	)
	(gr_circle
		(center 216.819226 -105.883202)
		(end 217.708226 -105.883202)
		(stroke
			(width 0.2)
			(type default)
		)
		(fill no)
		(layer "In1.Cu")
	)
	(gr_circle
		(center 216.819226 -105.121202)
		(end 217.708226 -105.121202)
		(stroke
			(width 0.2)
			(type default)
		)
		(fill no)
		(layer "In1.Cu")
	)
	(gr_circle
		(center 216.819226 -104.418638)
		(end 217.708226 -104.418638)
		(stroke
			(width 0.2)
			(type default)
		)
		(fill no)
		(layer "In1.Cu")
	)
	(gr_circle
		(center 216.819226 -103.656638)
		(end 217.708226 -103.656638)
		(stroke
			(width 0.2)
			(type default)
		)
		(fill no)
		(layer "In1.Cu")
	)
	(gr_circle
		(center 216.819226 -102.894638)
		(end 217.708226 -102.894638)
		(stroke
			(width 0.2)
			(type default)
		)
		(fill no)
		(layer "In1.Cu")
	)
	(gr_circle
		(center 216.936828 -132.94614)
		(end 217.825828 -132.94614)
		(stroke
			(width 0.2)
			(type default)
		)
		(fill no)
		(layer "In1.Cu")
	)
	(gr_circle
		(center 216.936828 -132.18414)
		(end 217.825828 -132.18414)
		(stroke
			(width 0.2)
			(type default)
		)
		(fill no)
		(layer "In1.Cu")
	)
	(gr_circle
		(center 216.936828 -131.42214)
		(end 217.825828 -131.42214)
		(stroke
			(width 0.2)
			(type default)
		)
		(fill no)
		(layer "In1.Cu")
	)
	(gr_circle
		(center 216.936828 -130.66014)
		(end 217.825828 -130.66014)
		(stroke
			(width 0.2)
			(type default)
		)
		(fill no)
		(layer "In1.Cu")
	)
	(gr_circle
		(center 216.936828 -129.89814)
		(end 217.825828 -129.89814)
		(stroke
			(width 0.2)
			(type default)
		)
		(fill no)
		(layer "In1.Cu")
	)
	(gr_circle
		(center 216.936828 -129.13614)
		(end 217.825828 -129.13614)
		(stroke
			(width 0.2)
			(type default)
		)
		(fill no)
		(layer "In1.Cu")
	)
	(gr_circle
		(center 216.936828 -128.37414)
		(end 217.825828 -128.37414)
		(stroke
			(width 0.2)
			(type default)
		)
		(fill no)
		(layer "In1.Cu")
	)
	(gr_circle
		(center 216.936828 -127.61214)
		(end 217.825828 -127.61214)
		(stroke
			(width 0.2)
			(type default)
		)
		(fill no)
		(layer "In1.Cu")
	)
	(gr_circle
		(center 217.488262 -98.013012)
		(end 218.377262 -98.013012)
		(stroke
			(width 0.2)
			(type default)
		)
		(fill no)
		(layer "In1.Cu")
	)
	(gr_circle
		(center 217.489278 -122.809762)
		(end 218.378278 -122.809762)
		(stroke
			(width 0.2)
			(type default)
		)
		(fill no)
		(layer "In1.Cu")
	)
	(gr_circle
		(center 217.489278 -122.047762)
		(end 218.378278 -122.047762)
		(stroke
			(width 0.2)
			(type default)
		)
		(fill no)
		(layer "In1.Cu")
	)
	(gr_circle
		(center 217.489278 -121.331736)
		(end 218.378278 -121.331736)
		(stroke
			(width 0.2)
			(type default)
		)
		(fill no)
		(layer "In1.Cu")
	)
	(gr_circle
		(center 217.489278 -120.569736)
		(end 218.378278 -120.569736)
		(stroke
			(width 0.2)
			(type default)
		)
		(fill no)
		(layer "In1.Cu")
	)
	(gr_circle
		(center 217.502994 -123.528328)
		(end 218.391994 -123.528328)
		(stroke
			(width 0.2)
			(type default)
		)
		(fill no)
		(layer "In1.Cu")
	)
	(gr_circle
		(center 217.510868 -105.896664)
		(end 218.399868 -105.896664)
		(stroke
			(width 0.2)
			(type default)
		)
		(fill no)
		(layer "In1.Cu")
	)
	(gr_circle
		(center 217.510868 -105.134664)
		(end 218.399868 -105.134664)
		(stroke
			(width 0.2)
			(type default)
		)
		(fill no)
		(layer "In1.Cu")
	)
	(gr_circle
		(center 217.510868 -104.4321)
		(end 218.399868 -104.4321)
		(stroke
			(width 0.2)
			(type default)
		)
		(fill no)
		(layer "In1.Cu")
	)
	(gr_circle
		(center 217.510868 -103.6701)
		(end 218.399868 -103.6701)
		(stroke
			(width 0.2)
			(type default)
		)
		(fill no)
		(layer "In1.Cu")
	)
	(gr_circle
		(center 217.510868 -102.9081)
		(end 218.399868 -102.9081)
		(stroke
			(width 0.2)
			(type default)
		)
		(fill no)
		(layer "In1.Cu")
	)
	(gr_circle
		(center 218.250262 -98.013012)
		(end 219.139262 -98.013012)
		(stroke
			(width 0.2)
			(type default)
		)
		(fill no)
		(layer "In1.Cu")
	)
	(gr_circle
		(center 218.251278 -122.809762)
		(end 219.140278 -122.809762)
		(stroke
			(width 0.2)
			(type default)
		)
		(fill no)
		(layer "In1.Cu")
	)
	(gr_circle
		(center 218.251278 -122.047762)
		(end 219.140278 -122.047762)
		(stroke
			(width 0.2)
			(type default)
		)
		(fill no)
		(layer "In1.Cu")
	)
	(gr_circle
		(center 218.251278 -121.331736)
		(end 219.140278 -121.331736)
		(stroke
			(width 0.2)
			(type default)
		)
		(fill no)
		(layer "In1.Cu")
	)
	(gr_circle
		(center 218.251278 -120.569736)
		(end 219.140278 -120.569736)
		(stroke
			(width 0.2)
			(type default)
		)
		(fill no)
		(layer "In1.Cu")
	)
	(gr_circle
		(center 218.264994 -123.528328)
		(end 219.153994 -123.528328)
		(stroke
			(width 0.2)
			(type default)
		)
		(fill no)
		(layer "In1.Cu")
	)
	(gr_circle
		(center 218.272868 -105.896664)
		(end 219.161868 -105.896664)
		(stroke
			(width 0.2)
			(type default)
		)
		(fill no)
		(layer "In1.Cu")
	)
	(gr_circle
		(center 218.272868 -105.134664)
		(end 219.161868 -105.134664)
		(stroke
			(width 0.2)
			(type default)
		)
		(fill no)
		(layer "In1.Cu")
	)
	(gr_circle
		(center 218.272868 -104.4321)
		(end 219.161868 -104.4321)
		(stroke
			(width 0.2)
			(type default)
		)
		(fill no)
		(layer "In1.Cu")
	)
	(gr_circle
		(center 218.272868 -103.6701)
		(end 219.161868 -103.6701)
		(stroke
			(width 0.2)
			(type default)
		)
		(fill no)
		(layer "In1.Cu")
	)
	(gr_circle
		(center 218.272868 -102.9081)
		(end 219.161868 -102.9081)
		(stroke
			(width 0.2)
			(type default)
		)
		(fill no)
		(layer "In1.Cu")
	)
	(gr_circle
		(center 219.013278 -122.809762)
		(end 219.902278 -122.809762)
		(stroke
			(width 0.2)
			(type default)
		)
		(fill no)
		(layer "In1.Cu")
	)
	(gr_circle
		(center 219.013278 -122.047762)
		(end 219.902278 -122.047762)
		(stroke
			(width 0.2)
			(type default)
		)
		(fill no)
		(layer "In1.Cu")
	)
	(gr_circle
		(center 219.013278 -121.331736)
		(end 219.902278 -121.331736)
		(stroke
			(width 0.2)
			(type default)
		)
		(fill no)
		(layer "In1.Cu")
	)
	(gr_circle
		(center 219.013278 -120.569736)
		(end 219.902278 -120.569736)
		(stroke
			(width 0.2)
			(type default)
		)
		(fill no)
		(layer "In1.Cu")
	)
	(gr_circle
		(center 219.026994 -123.528328)
		(end 219.915994 -123.528328)
		(stroke
			(width 0.2)
			(type default)
		)
		(fill no)
		(layer "In1.Cu")
	)
	(gr_circle
		(center 219.034868 -105.896664)
		(end 219.923868 -105.896664)
		(stroke
			(width 0.2)
			(type default)
		)
		(fill no)
		(layer "In1.Cu")
	)
	(gr_circle
		(center 219.034868 -105.134664)
		(end 219.923868 -105.134664)
		(stroke
			(width 0.2)
			(type default)
		)
		(fill no)
		(layer "In1.Cu")
	)
	(gr_circle
		(center 219.034868 -104.4321)
		(end 219.923868 -104.4321)
		(stroke
			(width 0.2)
			(type default)
		)
		(fill no)
		(layer "In1.Cu")
	)
	(gr_circle
		(center 219.034868 -103.6701)
		(end 219.923868 -103.6701)
		(stroke
			(width 0.2)
			(type default)
		)
		(fill no)
		(layer "In1.Cu")
	)
	(gr_circle
		(center 219.034868 -102.9081)
		(end 219.923868 -102.9081)
		(stroke
			(width 0.2)
			(type default)
		)
		(fill no)
		(layer "In1.Cu")
	)
	(gr_circle
		(center 219.775278 -122.809762)
		(end 220.664278 -122.809762)
		(stroke
			(width 0.2)
			(type default)
		)
		(fill no)
		(layer "In1.Cu")
	)
	(gr_circle
		(center 219.775278 -122.047762)
		(end 220.664278 -122.047762)
		(stroke
			(width 0.2)
			(type default)
		)
		(fill no)
		(layer "In1.Cu")
	)
	(gr_circle
		(center 219.775278 -121.331736)
		(end 220.664278 -121.331736)
		(stroke
			(width 0.2)
			(type default)
		)
		(fill no)
		(layer "In1.Cu")
	)
	(gr_circle
		(center 219.775278 -120.569736)
		(end 220.664278 -120.569736)
		(stroke
			(width 0.2)
			(type default)
		)
		(fill no)
		(layer "In1.Cu")
	)
	(gr_circle
		(center 219.788994 -123.528328)
		(end 220.677994 -123.528328)
		(stroke
			(width 0.2)
			(type default)
		)
		(fill no)
		(layer "In1.Cu")
	)
	(gr_circle
		(center 219.796868 -105.896664)
		(end 220.685868 -105.896664)
		(stroke
			(width 0.2)
			(type default)
		)
		(fill no)
		(layer "In1.Cu")
	)
	(gr_circle
		(center 219.796868 -105.134664)
		(end 220.685868 -105.134664)
		(stroke
			(width 0.2)
			(type default)
		)
		(fill no)
		(layer "In1.Cu")
	)
	(gr_circle
		(center 219.796868 -104.4321)
		(end 220.685868 -104.4321)
		(stroke
			(width 0.2)
			(type default)
		)
		(fill no)
		(layer "In1.Cu")
	)
	(gr_circle
		(center 219.796868 -103.6701)
		(end 220.685868 -103.6701)
		(stroke
			(width 0.2)
			(type default)
		)
		(fill no)
		(layer "In1.Cu")
	)
	(gr_circle
		(center 219.796868 -102.9081)
		(end 220.685868 -102.9081)
		(stroke
			(width 0.2)
			(type default)
		)
		(fill no)
		(layer "In1.Cu")
	)
	(gr_circle
		(center 219.847668 -97.985834)
		(end 220.736668 -97.985834)
		(stroke
			(width 0.2)
			(type default)
		)
		(fill no)
		(layer "In1.Cu")
	)
	(gr_circle
		(center 220.537278 -122.809762)
		(end 221.426278 -122.809762)
		(stroke
			(width 0.2)
			(type default)
		)
		(fill no)
		(layer "In1.Cu")
	)
	(gr_circle
		(center 220.537278 -122.047762)
		(end 221.426278 -122.047762)
		(stroke
			(width 0.2)
			(type default)
		)
		(fill no)
		(layer "In1.Cu")
	)
	(gr_circle
		(center 220.537278 -121.331736)
		(end 221.426278 -121.331736)
		(stroke
			(width 0.2)
			(type default)
		)
		(fill no)
		(layer "In1.Cu")
	)
	(gr_circle
		(center 220.537278 -120.569736)
		(end 221.426278 -120.569736)
		(stroke
			(width 0.2)
			(type default)
		)
		(fill no)
		(layer "In1.Cu")
	)
	(gr_circle
		(center 220.550994 -123.528328)
		(end 221.439994 -123.528328)
		(stroke
			(width 0.2)
			(type default)
		)
		(fill no)
		(layer "In1.Cu")
	)
	(gr_circle
		(center 220.558868 -105.896664)
		(end 221.447868 -105.896664)
		(stroke
			(width 0.2)
			(type default)
		)
		(fill no)
		(layer "In1.Cu")
	)
	(gr_circle
		(center 220.558868 -105.134664)
		(end 221.447868 -105.134664)
		(stroke
			(width 0.2)
			(type default)
		)
		(fill no)
		(layer "In1.Cu")
	)
	(gr_circle
		(center 220.558868 -104.4321)
		(end 221.447868 -104.4321)
		(stroke
			(width 0.2)
			(type default)
		)
		(fill no)
		(layer "In1.Cu")
	)
	(gr_circle
		(center 220.558868 -103.6701)
		(end 221.447868 -103.6701)
		(stroke
			(width 0.2)
			(type default)
		)
		(fill no)
		(layer "In1.Cu")
	)
	(gr_circle
		(center 220.558868 -102.9081)
		(end 221.447868 -102.9081)
		(stroke
			(width 0.2)
			(type default)
		)
		(fill no)
		(layer "In1.Cu")
	)
	(gr_circle
		(center 220.609668 -97.985834)
		(end 221.498668 -97.985834)
		(stroke
			(width 0.2)
			(type default)
		)
		(fill no)
		(layer "In1.Cu")
	)
	(gr_circle
		(center 221.299278 -122.809762)
		(end 222.188278 -122.809762)
		(stroke
			(width 0.2)
			(type default)
		)
		(fill no)
		(layer "In1.Cu")
	)
	(gr_circle
		(center 221.299278 -122.047762)
		(end 222.188278 -122.047762)
		(stroke
			(width 0.2)
			(type default)
		)
		(fill no)
		(layer "In1.Cu")
	)
	(gr_circle
		(center 221.299278 -121.331736)
		(end 222.188278 -121.331736)
		(stroke
			(width 0.2)
			(type default)
		)
		(fill no)
		(layer "In1.Cu")
	)
	(gr_circle
		(center 221.299278 -120.569736)
		(end 222.188278 -120.569736)
		(stroke
			(width 0.2)
			(type default)
		)
		(fill no)
		(layer "In1.Cu")
	)
	(gr_circle
		(center 221.312994 -123.528328)
		(end 222.201994 -123.528328)
		(stroke
			(width 0.2)
			(type default)
		)
		(fill no)
		(layer "In1.Cu")
	)
	(gr_circle
		(center 221.320868 -105.896664)
		(end 222.209868 -105.896664)
		(stroke
			(width 0.2)
			(type default)
		)
		(fill no)
		(layer "In1.Cu")
	)
	(gr_circle
		(center 221.320868 -105.134664)
		(end 222.209868 -105.134664)
		(stroke
			(width 0.2)
			(type default)
		)
		(fill no)
		(layer "In1.Cu")
	)
	(gr_circle
		(center 221.320868 -104.4321)
		(end 222.209868 -104.4321)
		(stroke
			(width 0.2)
			(type default)
		)
		(fill no)
		(layer "In1.Cu")
	)
	(gr_circle
		(center 221.320868 -103.6701)
		(end 222.209868 -103.6701)
		(stroke
			(width 0.2)
			(type default)
		)
		(fill no)
		(layer "In1.Cu")
	)
	(gr_circle
		(center 221.320868 -102.9081)
		(end 222.209868 -102.9081)
		(stroke
			(width 0.2)
			(type default)
		)
		(fill no)
		(layer "In1.Cu")
	)
	(gr_circle
		(center 222.039688 -105.882948)
		(end 222.928688 -105.882948)
		(stroke
			(width 0.2)
			(type default)
		)
		(fill no)
		(layer "In1.Cu")
	)
	(gr_circle
		(center 222.039688 -105.120948)
		(end 222.928688 -105.120948)
		(stroke
			(width 0.2)
			(type default)
		)
		(fill no)
		(layer "In1.Cu")
	)
	(gr_circle
		(center 222.039688 -104.418384)
		(end 222.928688 -104.418384)
		(stroke
			(width 0.2)
			(type default)
		)
		(fill no)
		(layer "In1.Cu")
	)
	(gr_circle
		(center 222.039688 -103.656384)
		(end 222.928688 -103.656384)
		(stroke
			(width 0.2)
			(type default)
		)
		(fill no)
		(layer "In1.Cu")
	)
	(gr_circle
		(center 222.039688 -102.894384)
		(end 222.928688 -102.894384)
		(stroke
			(width 0.2)
			(type default)
		)
		(fill no)
		(layer "In1.Cu")
	)
	(gr_circle
		(center 222.061278 -122.809762)
		(end 222.950278 -122.809762)
		(stroke
			(width 0.2)
			(type default)
		)
		(fill no)
		(layer "In1.Cu")
	)
	(gr_circle
		(center 222.061278 -122.047762)
		(end 222.950278 -122.047762)
		(stroke
			(width 0.2)
			(type default)
		)
		(fill no)
		(layer "In1.Cu")
	)
	(gr_circle
		(center 222.061278 -121.331736)
		(end 222.950278 -121.331736)
		(stroke
			(width 0.2)
			(type default)
		)
		(fill no)
		(layer "In1.Cu")
	)
	(gr_circle
		(center 222.061278 -120.569736)
		(end 222.950278 -120.569736)
		(stroke
			(width 0.2)
			(type default)
		)
		(fill no)
		(layer "In1.Cu")
	)
	(gr_circle
		(center 222.074994 -123.528328)
		(end 222.963994 -123.528328)
		(stroke
			(width 0.2)
			(type default)
		)
		(fill no)
		(layer "In1.Cu")
	)
	(gr_circle
		(center 222.09887 -97.985834)
		(end 222.98787 -97.985834)
		(stroke
			(width 0.2)
			(type default)
		)
		(fill no)
		(layer "In1.Cu")
	)
	(gr_circle
		(center 222.86087 -97.985834)
		(end 223.74987 -97.985834)
		(stroke
			(width 0.2)
			(type default)
		)
		(fill no)
		(layer "In1.Cu")
	)
	(gr_circle
		(center 224.593912 -97.985834)
		(end 225.482912 -97.985834)
		(stroke
			(width 0.2)
			(type default)
		)
		(fill no)
		(layer "In1.Cu")
	)
	(gr_circle
		(center 225.355912 -97.985834)
		(end 226.244912 -97.985834)
		(stroke
			(width 0.2)
			(type default)
		)
		(fill no)
		(layer "In1.Cu")
	)
	(gr_circle
		(center 226.845114 -97.985834)
		(end 227.734114 -97.985834)
		(stroke
			(width 0.2)
			(type default)
		)
		(fill no)
		(layer "In1.Cu")
	)
	(gr_circle
		(center 227.607114 -97.985834)
		(end 228.496114 -97.985834)
		(stroke
			(width 0.2)
			(type default)
		)
		(fill no)
		(layer "In1.Cu")
	)
	(gr_circle
		(center 229.530148 -98.012758)
		(end 230.419148 -98.012758)
		(stroke
			(width 0.2)
			(type default)
		)
		(fill no)
		(layer "In1.Cu")
	)
	(gr_circle
		(center 230.292148 -98.012758)
		(end 231.181148 -98.012758)
		(stroke
			(width 0.2)
			(type default)
		)
		(fill no)
		(layer "In1.Cu")
	)
	(gr_circle
		(center 231.591104 -131.110736)
		(end 232.480104 -131.110736)
		(stroke
			(width 0.2)
			(type default)
		)
		(fill no)
		(layer "In1.Cu")
	)
	(gr_circle
		(center 231.591104 -130.348736)
		(end 232.480104 -130.348736)
		(stroke
			(width 0.2)
			(type default)
		)
		(fill no)
		(layer "In1.Cu")
	)
	(gr_circle
		(center 231.591104 -129.586736)
		(end 232.480104 -129.586736)
		(stroke
			(width 0.2)
			(type default)
		)
		(fill no)
		(layer "In1.Cu")
	)
	(gr_circle
		(center 231.591104 -128.824736)
		(end 232.480104 -128.824736)
		(stroke
			(width 0.2)
			(type default)
		)
		(fill no)
		(layer "In1.Cu")
	)
	(gr_circle
		(center 231.591104 -128.062736)
		(end 232.480104 -128.062736)
		(stroke
			(width 0.2)
			(type default)
		)
		(fill no)
		(layer "In1.Cu")
	)
	(gr_circle
		(center 231.591104 -127.300736)
		(end 232.480104 -127.300736)
		(stroke
			(width 0.2)
			(type default)
		)
		(fill no)
		(layer "In1.Cu")
	)
	(gr_circle
		(center 231.604566 -126.609094)
		(end 232.493566 -126.609094)
		(stroke
			(width 0.2)
			(type default)
		)
		(fill no)
		(layer "In1.Cu")
	)
	(gr_circle
		(center 231.60482 -131.829556)
		(end 232.49382 -131.829556)
		(stroke
			(width 0.2)
			(type default)
		)
		(fill no)
		(layer "In1.Cu")
	)
	(gr_circle
		(center 231.78135 -98.012758)
		(end 232.67035 -98.012758)
		(stroke
			(width 0.2)
			(type default)
		)
		(fill no)
		(layer "In1.Cu")
	)
	(gr_circle
		(center 232.353104 -131.110736)
		(end 233.242104 -131.110736)
		(stroke
			(width 0.2)
			(type default)
		)
		(fill no)
		(layer "In1.Cu")
	)
	(gr_circle
		(center 232.353104 -130.348736)
		(end 233.242104 -130.348736)
		(stroke
			(width 0.2)
			(type default)
		)
		(fill no)
		(layer "In1.Cu")
	)
	(gr_circle
		(center 232.353104 -129.586736)
		(end 233.242104 -129.586736)
		(stroke
			(width 0.2)
			(type default)
		)
		(fill no)
		(layer "In1.Cu")
	)
	(gr_circle
		(center 232.353104 -128.824736)
		(end 233.242104 -128.824736)
		(stroke
			(width 0.2)
			(type default)
		)
		(fill no)
		(layer "In1.Cu")
	)
	(gr_circle
		(center 232.353104 -128.062736)
		(end 233.242104 -128.062736)
		(stroke
			(width 0.2)
			(type default)
		)
		(fill no)
		(layer "In1.Cu")
	)
	(gr_circle
		(center 232.353104 -127.300736)
		(end 233.242104 -127.300736)
		(stroke
			(width 0.2)
			(type default)
		)
		(fill no)
		(layer "In1.Cu")
	)
	(gr_circle
		(center 232.366566 -126.609094)
		(end 233.255566 -126.609094)
		(stroke
			(width 0.2)
			(type default)
		)
		(fill no)
		(layer "In1.Cu")
	)
	(gr_circle
		(center 232.36682 -131.829556)
		(end 233.25582 -131.829556)
		(stroke
			(width 0.2)
			(type default)
		)
		(fill no)
		(layer "In1.Cu")
	)
	(gr_circle
		(center 232.54335 -98.012758)
		(end 233.43235 -98.012758)
		(stroke
			(width 0.2)
			(type default)
		)
		(fill no)
		(layer "In1.Cu")
	)
	(gr_circle
		(center 233.055668 -131.110736)
		(end 233.944668 -131.110736)
		(stroke
			(width 0.2)
			(type default)
		)
		(fill no)
		(layer "In1.Cu")
	)
	(gr_circle
		(center 233.055668 -130.348736)
		(end 233.944668 -130.348736)
		(stroke
			(width 0.2)
			(type default)
		)
		(fill no)
		(layer "In1.Cu")
	)
	(gr_circle
		(center 233.055668 -129.586736)
		(end 233.944668 -129.586736)
		(stroke
			(width 0.2)
			(type default)
		)
		(fill no)
		(layer "In1.Cu")
	)
	(gr_circle
		(center 233.055668 -128.824736)
		(end 233.944668 -128.824736)
		(stroke
			(width 0.2)
			(type default)
		)
		(fill no)
		(layer "In1.Cu")
	)
	(gr_circle
		(center 233.055668 -128.062736)
		(end 233.944668 -128.062736)
		(stroke
			(width 0.2)
			(type default)
		)
		(fill no)
		(layer "In1.Cu")
	)
	(gr_circle
		(center 233.055668 -127.300736)
		(end 233.944668 -127.300736)
		(stroke
			(width 0.2)
			(type default)
		)
		(fill no)
		(layer "In1.Cu")
	)
	(gr_circle
		(center 233.06913 -126.609094)
		(end 233.95813 -126.609094)
		(stroke
			(width 0.2)
			(type default)
		)
		(fill no)
		(layer "In1.Cu")
	)
	(gr_circle
		(center 233.069384 -131.829556)
		(end 233.958384 -131.829556)
		(stroke
			(width 0.2)
			(type default)
		)
		(fill no)
		(layer "In1.Cu")
	)
	(gr_circle
		(center 233.817668 -131.110736)
		(end 234.706668 -131.110736)
		(stroke
			(width 0.2)
			(type default)
		)
		(fill no)
		(layer "In1.Cu")
	)
	(gr_circle
		(center 233.817668 -130.348736)
		(end 234.706668 -130.348736)
		(stroke
			(width 0.2)
			(type default)
		)
		(fill no)
		(layer "In1.Cu")
	)
	(gr_circle
		(center 233.817668 -129.586736)
		(end 234.706668 -129.586736)
		(stroke
			(width 0.2)
			(type default)
		)
		(fill no)
		(layer "In1.Cu")
	)
	(gr_circle
		(center 233.817668 -128.824736)
		(end 234.706668 -128.824736)
		(stroke
			(width 0.2)
			(type default)
		)
		(fill no)
		(layer "In1.Cu")
	)
	(gr_circle
		(center 233.817668 -128.062736)
		(end 234.706668 -128.062736)
		(stroke
			(width 0.2)
			(type default)
		)
		(fill no)
		(layer "In1.Cu")
	)
	(gr_circle
		(center 233.817668 -127.300736)
		(end 234.706668 -127.300736)
		(stroke
			(width 0.2)
			(type default)
		)
		(fill no)
		(layer "In1.Cu")
	)
	(gr_circle
		(center 233.83113 -126.609094)
		(end 234.72013 -126.609094)
		(stroke
			(width 0.2)
			(type default)
		)
		(fill no)
		(layer "In1.Cu")
	)
	(gr_circle
		(center 233.831384 -131.829556)
		(end 234.720384 -131.829556)
		(stroke
			(width 0.2)
			(type default)
		)
		(fill no)
		(layer "In1.Cu")
	)
	(gr_circle
		(center 234.303316 -97.985834)
		(end 235.192316 -97.985834)
		(stroke
			(width 0.2)
			(type default)
		)
		(fill no)
		(layer "In1.Cu")
	)
	(gr_circle
		(center 234.579668 -131.110736)
		(end 235.468668 -131.110736)
		(stroke
			(width 0.2)
			(type default)
		)
		(fill no)
		(layer "In1.Cu")
	)
	(gr_circle
		(center 234.579668 -130.348736)
		(end 235.468668 -130.348736)
		(stroke
			(width 0.2)
			(type default)
		)
		(fill no)
		(layer "In1.Cu")
	)
	(gr_circle
		(center 234.579668 -129.586736)
		(end 235.468668 -129.586736)
		(stroke
			(width 0.2)
			(type default)
		)
		(fill no)
		(layer "In1.Cu")
	)
	(gr_circle
		(center 234.579668 -128.824736)
		(end 235.468668 -128.824736)
		(stroke
			(width 0.2)
			(type default)
		)
		(fill no)
		(layer "In1.Cu")
	)
	(gr_circle
		(center 234.579668 -128.062736)
		(end 235.468668 -128.062736)
		(stroke
			(width 0.2)
			(type default)
		)
		(fill no)
		(layer "In1.Cu")
	)
	(gr_circle
		(center 234.579668 -127.300736)
		(end 235.468668 -127.300736)
		(stroke
			(width 0.2)
			(type default)
		)
		(fill no)
		(layer "In1.Cu")
	)
	(gr_circle
		(center 234.59313 -126.609094)
		(end 235.48213 -126.609094)
		(stroke
			(width 0.2)
			(type default)
		)
		(fill no)
		(layer "In1.Cu")
	)
	(gr_circle
		(center 234.593384 -131.829556)
		(end 235.482384 -131.829556)
		(stroke
			(width 0.2)
			(type default)
		)
		(fill no)
		(layer "In1.Cu")
	)
	(gr_circle
		(center 235.065316 -97.985834)
		(end 235.954316 -97.985834)
		(stroke
			(width 0.2)
			(type default)
		)
		(fill no)
		(layer "In1.Cu")
	)
	(gr_circle
		(center 236.554518 -97.985834)
		(end 237.443518 -97.985834)
		(stroke
			(width 0.2)
			(type default)
		)
		(fill no)
		(layer "In1.Cu")
	)
	(gr_circle
		(center 237.316518 -97.985834)
		(end 238.205518 -97.985834)
		(stroke
			(width 0.2)
			(type default)
		)
		(fill no)
		(layer "In1.Cu")
	)
	(gr_circle
		(center 239.076738 -98.012758)
		(end 239.965738 -98.012758)
		(stroke
			(width 0.2)
			(type default)
		)
		(fill no)
		(layer "In1.Cu")
	)
	(gr_circle
		(center 239.838738 -98.012758)
		(end 240.727738 -98.012758)
		(stroke
			(width 0.2)
			(type default)
		)
		(fill no)
		(layer "In1.Cu")
	)
	(gr_circle
		(center 241.32794 -98.012758)
		(end 242.21694 -98.012758)
		(stroke
			(width 0.2)
			(type default)
		)
		(fill no)
		(layer "In1.Cu")
	)
	(gr_circle
		(center 242.08994 -98.012758)
		(end 242.97894 -98.012758)
		(stroke
			(width 0.2)
			(type default)
		)
		(fill no)
		(layer "In1.Cu")
	)
	(gr_circle
		(center 258.219956 -50.232818)
		(end 259.108956 -50.232818)
		(stroke
			(width 0.2)
			(type default)
		)
		(fill no)
		(layer "In1.Cu")
	)
	(gr_circle
		(center 258.219956 -48.327818)
		(end 259.108956 -48.327818)
		(stroke
			(width 0.2)
			(type default)
		)
		(fill no)
		(layer "In1.Cu")
	)
	(gr_circle
		(center 258.219956 -47.565818)
		(end 259.108956 -47.565818)
		(stroke
			(width 0.2)
			(type default)
		)
		(fill no)
		(layer "In1.Cu")
	)
	(gr_circle
		(center 258.530598 -39.18712)
		(end 259.419598 -39.18712)
		(stroke
			(width 0.2)
			(type default)
		)
		(fill no)
		(layer "In1.Cu")
	)
	(gr_circle
		(center 258.548886 -38.461696)
		(end 259.437886 -38.461696)
		(stroke
			(width 0.2)
			(type default)
		)
		(fill no)
		(layer "In1.Cu")
	)
	(gr_circle
		(center 258.83362 -40.72382)
		(end 259.72262 -40.72382)
		(stroke
			(width 0.2)
			(type default)
		)
		(fill no)
		(layer "In1.Cu")
	)
	(gr_circle
		(center 258.83616 -39.95674)
		(end 259.72516 -39.95674)
		(stroke
			(width 0.2)
			(type default)
		)
		(fill no)
		(layer "In1.Cu")
	)
	(gr_circle
		(center 259.0038 -42.3164)
		(end 259.8928 -42.3164)
		(stroke
			(width 0.2)
			(type default)
		)
		(fill no)
		(layer "In1.Cu")
	)
	(gr_circle
		(center 259.588 -43.4848)
		(end 260.477 -43.4848)
		(stroke
			(width 0.2)
			(type default)
		)
		(fill no)
		(layer "In1.Cu")
	)
	(gr_circle
		(center 259.630672 -41.092882)
		(end 260.519672 -41.092882)
		(stroke
			(width 0.2)
			(type default)
		)
		(fill no)
		(layer "In1.Cu")
	)
	(gr_circle
		(center 259.630672 -39.592758)
		(end 260.519672 -39.592758)
		(stroke
			(width 0.2)
			(type default)
		)
		(fill no)
		(layer "In1.Cu")
	)
	(gr_circle
		(center 260.182106 -37.2364)
		(end 261.071106 -37.2364)
		(stroke
			(width 0.2)
			(type default)
		)
		(fill no)
		(layer "In1.Cu")
	)
	(gr_circle
		(center 269.24 -125.857)
		(end 270.129 -125.857)
		(stroke
			(width 0.2)
			(type default)
		)
		(fill no)
		(layer "In1.Cu")
	)
	(gr_circle
		(center 269.24 -125.095)
		(end 270.129 -125.095)
		(stroke
			(width 0.2)
			(type default)
		)
		(fill no)
		(layer "In1.Cu")
	)
	(gr_circle
		(center 269.24 -124.333)
		(end 270.129 -124.333)
		(stroke
			(width 0.2)
			(type default)
		)
		(fill no)
		(layer "In1.Cu")
	)
	(gr_circle
		(center 269.24 -123.571)
		(end 270.129 -123.571)
		(stroke
			(width 0.2)
			(type default)
		)
		(fill no)
		(layer "In1.Cu")
	)
	(gr_circle
		(center 269.24 -122.809)
		(end 270.129 -122.809)
		(stroke
			(width 0.2)
			(type default)
		)
		(fill no)
		(layer "In1.Cu")
	)
	(gr_circle
		(center 269.24 -122.047)
		(end 270.129 -122.047)
		(stroke
			(width 0.2)
			(type default)
		)
		(fill no)
		(layer "In1.Cu")
	)
	(gr_circle
		(center 269.24 -113.792)
		(end 270.129 -113.792)
		(stroke
			(width 0.2)
			(type default)
		)
		(fill no)
		(layer "In1.Cu")
	)
	(gr_circle
		(center 269.24 -113.03)
		(end 270.129 -113.03)
		(stroke
			(width 0.2)
			(type default)
		)
		(fill no)
		(layer "In1.Cu")
	)
	(gr_circle
		(center 269.24 -112.268)
		(end 270.129 -112.268)
		(stroke
			(width 0.2)
			(type default)
		)
		(fill no)
		(layer "In1.Cu")
	)
	(gr_circle
		(center 269.24 -111.506)
		(end 270.129 -111.506)
		(stroke
			(width 0.2)
			(type default)
		)
		(fill no)
		(layer "In1.Cu")
	)
	(gr_circle
		(center 269.24 -110.744)
		(end 270.129 -110.744)
		(stroke
			(width 0.2)
			(type default)
		)
		(fill no)
		(layer "In1.Cu")
	)
	(gr_circle
		(center 269.24 -109.982)
		(end 270.129 -109.982)
		(stroke
			(width 0.2)
			(type default)
		)
		(fill no)
		(layer "In1.Cu")
	)
	(gr_circle
		(center 269.24 -101.727)
		(end 270.129 -101.727)
		(stroke
			(width 0.2)
			(type default)
		)
		(fill no)
		(layer "In1.Cu")
	)
	(gr_circle
		(center 269.24 -100.965)
		(end 270.129 -100.965)
		(stroke
			(width 0.2)
			(type default)
		)
		(fill no)
		(layer "In1.Cu")
	)
	(gr_circle
		(center 269.24 -100.203)
		(end 270.129 -100.203)
		(stroke
			(width 0.2)
			(type default)
		)
		(fill no)
		(layer "In1.Cu")
	)
	(gr_circle
		(center 269.24 -99.441)
		(end 270.129 -99.441)
		(stroke
			(width 0.2)
			(type default)
		)
		(fill no)
		(layer "In1.Cu")
	)
	(gr_circle
		(center 269.24 -98.679)
		(end 270.129 -98.679)
		(stroke
			(width 0.2)
			(type default)
		)
		(fill no)
		(layer "In1.Cu")
	)
	(gr_circle
		(center 269.24 -97.917)
		(end 270.129 -97.917)
		(stroke
			(width 0.2)
			(type default)
		)
		(fill no)
		(layer "In1.Cu")
	)
	(gr_circle
		(center 269.24 -89.662)
		(end 270.129 -89.662)
		(stroke
			(width 0.2)
			(type default)
		)
		(fill no)
		(layer "In1.Cu")
	)
	(gr_circle
		(center 269.24 -88.9)
		(end 270.129 -88.9)
		(stroke
			(width 0.2)
			(type default)
		)
		(fill no)
		(layer "In1.Cu")
	)
	(gr_circle
		(center 269.24 -88.138)
		(end 270.129 -88.138)
		(stroke
			(width 0.2)
			(type default)
		)
		(fill no)
		(layer "In1.Cu")
	)
	(gr_circle
		(center 269.24 -87.376)
		(end 270.129 -87.376)
		(stroke
			(width 0.2)
			(type default)
		)
		(fill no)
		(layer "In1.Cu")
	)
	(gr_circle
		(center 269.24 -86.614)
		(end 270.129 -86.614)
		(stroke
			(width 0.2)
			(type default)
		)
		(fill no)
		(layer "In1.Cu")
	)
	(gr_circle
		(center 269.24 -85.852)
		(end 270.129 -85.852)
		(stroke
			(width 0.2)
			(type default)
		)
		(fill no)
		(layer "In1.Cu")
	)
	(gr_circle
		(center 269.24 -77.597)
		(end 270.129 -77.597)
		(stroke
			(width 0.2)
			(type default)
		)
		(fill no)
		(layer "In1.Cu")
	)
	(gr_circle
		(center 269.24 -76.835)
		(end 270.129 -76.835)
		(stroke
			(width 0.2)
			(type default)
		)
		(fill no)
		(layer "In1.Cu")
	)
	(gr_circle
		(center 269.24 -76.073)
		(end 270.129 -76.073)
		(stroke
			(width 0.2)
			(type default)
		)
		(fill no)
		(layer "In1.Cu")
	)
	(gr_circle
		(center 269.24 -75.311)
		(end 270.129 -75.311)
		(stroke
			(width 0.2)
			(type default)
		)
		(fill no)
		(layer "In1.Cu")
	)
	(gr_circle
		(center 269.24 -74.549)
		(end 270.129 -74.549)
		(stroke
			(width 0.2)
			(type default)
		)
		(fill no)
		(layer "In1.Cu")
	)
	(gr_circle
		(center 269.24 -73.787)
		(end 270.129 -73.787)
		(stroke
			(width 0.2)
			(type default)
		)
		(fill no)
		(layer "In1.Cu")
	)
	(gr_circle
		(center 269.24 -65.532)
		(end 270.129 -65.532)
		(stroke
			(width 0.2)
			(type default)
		)
		(fill no)
		(layer "In1.Cu")
	)
	(gr_circle
		(center 269.24 -64.77)
		(end 270.129 -64.77)
		(stroke
			(width 0.2)
			(type default)
		)
		(fill no)
		(layer "In1.Cu")
	)
	(gr_circle
		(center 269.24 -64.008)
		(end 270.129 -64.008)
		(stroke
			(width 0.2)
			(type default)
		)
		(fill no)
		(layer "In1.Cu")
	)
	(gr_circle
		(center 269.24 -63.246)
		(end 270.129 -63.246)
		(stroke
			(width 0.2)
			(type default)
		)
		(fill no)
		(layer "In1.Cu")
	)
	(gr_circle
		(center 269.24 -62.484)
		(end 270.129 -62.484)
		(stroke
			(width 0.2)
			(type default)
		)
		(fill no)
		(layer "In1.Cu")
	)
	(gr_circle
		(center 269.24 -61.722)
		(end 270.129 -61.722)
		(stroke
			(width 0.2)
			(type default)
		)
		(fill no)
		(layer "In1.Cu")
	)
	(gr_circle
		(center 270.002 -125.857)
		(end 270.891 -125.857)
		(stroke
			(width 0.2)
			(type default)
		)
		(fill no)
		(layer "In1.Cu")
	)
	(gr_circle
		(center 270.002 -125.095)
		(end 270.891 -125.095)
		(stroke
			(width 0.2)
			(type default)
		)
		(fill no)
		(layer "In1.Cu")
	)
	(gr_circle
		(center 270.002 -124.333)
		(end 270.891 -124.333)
		(stroke
			(width 0.2)
			(type default)
		)
		(fill no)
		(layer "In1.Cu")
	)
	(gr_circle
		(center 270.002 -123.571)
		(end 270.891 -123.571)
		(stroke
			(width 0.2)
			(type default)
		)
		(fill no)
		(layer "In1.Cu")
	)
	(gr_circle
		(center 270.002 -122.809)
		(end 270.891 -122.809)
		(stroke
			(width 0.2)
			(type default)
		)
		(fill no)
		(layer "In1.Cu")
	)
	(gr_circle
		(center 270.002 -122.047)
		(end 270.891 -122.047)
		(stroke
			(width 0.2)
			(type default)
		)
		(fill no)
		(layer "In1.Cu")
	)
	(gr_circle
		(center 270.002 -113.792)
		(end 270.891 -113.792)
		(stroke
			(width 0.2)
			(type default)
		)
		(fill no)
		(layer "In1.Cu")
	)
	(gr_circle
		(center 270.002 -113.03)
		(end 270.891 -113.03)
		(stroke
			(width 0.2)
			(type default)
		)
		(fill no)
		(layer "In1.Cu")
	)
	(gr_circle
		(center 270.002 -112.268)
		(end 270.891 -112.268)
		(stroke
			(width 0.2)
			(type default)
		)
		(fill no)
		(layer "In1.Cu")
	)
	(gr_circle
		(center 270.002 -111.506)
		(end 270.891 -111.506)
		(stroke
			(width 0.2)
			(type default)
		)
		(fill no)
		(layer "In1.Cu")
	)
	(gr_circle
		(center 270.002 -110.744)
		(end 270.891 -110.744)
		(stroke
			(width 0.2)
			(type default)
		)
		(fill no)
		(layer "In1.Cu")
	)
	(gr_circle
		(center 270.002 -109.982)
		(end 270.891 -109.982)
		(stroke
			(width 0.2)
			(type default)
		)
		(fill no)
		(layer "In1.Cu")
	)
	(gr_circle
		(center 270.002 -101.727)
		(end 270.891 -101.727)
		(stroke
			(width 0.2)
			(type default)
		)
		(fill no)
		(layer "In1.Cu")
	)
	(gr_circle
		(center 270.002 -100.965)
		(end 270.891 -100.965)
		(stroke
			(width 0.2)
			(type default)
		)
		(fill no)
		(layer "In1.Cu")
	)
	(gr_circle
		(center 270.002 -100.203)
		(end 270.891 -100.203)
		(stroke
			(width 0.2)
			(type default)
		)
		(fill no)
		(layer "In1.Cu")
	)
	(gr_circle
		(center 270.002 -99.441)
		(end 270.891 -99.441)
		(stroke
			(width 0.2)
			(type default)
		)
		(fill no)
		(layer "In1.Cu")
	)
	(gr_circle
		(center 270.002 -98.679)
		(end 270.891 -98.679)
		(stroke
			(width 0.2)
			(type default)
		)
		(fill no)
		(layer "In1.Cu")
	)
	(gr_circle
		(center 270.002 -97.917)
		(end 270.891 -97.917)
		(stroke
			(width 0.2)
			(type default)
		)
		(fill no)
		(layer "In1.Cu")
	)
	(gr_circle
		(center 270.002 -89.662)
		(end 270.891 -89.662)
		(stroke
			(width 0.2)
			(type default)
		)
		(fill no)
		(layer "In1.Cu")
	)
	(gr_circle
		(center 270.002 -88.9)
		(end 270.891 -88.9)
		(stroke
			(width 0.2)
			(type default)
		)
		(fill no)
		(layer "In1.Cu")
	)
	(gr_circle
		(center 270.002 -88.138)
		(end 270.891 -88.138)
		(stroke
			(width 0.2)
			(type default)
		)
		(fill no)
		(layer "In1.Cu")
	)
	(gr_circle
		(center 270.002 -87.376)
		(end 270.891 -87.376)
		(stroke
			(width 0.2)
			(type default)
		)
		(fill no)
		(layer "In1.Cu")
	)
	(gr_circle
		(center 270.002 -86.614)
		(end 270.891 -86.614)
		(stroke
			(width 0.2)
			(type default)
		)
		(fill no)
		(layer "In1.Cu")
	)
	(gr_circle
		(center 270.002 -85.852)
		(end 270.891 -85.852)
		(stroke
			(width 0.2)
			(type default)
		)
		(fill no)
		(layer "In1.Cu")
	)
	(gr_circle
		(center 270.002 -77.597)
		(end 270.891 -77.597)
		(stroke
			(width 0.2)
			(type default)
		)
		(fill no)
		(layer "In1.Cu")
	)
	(gr_circle
		(center 270.002 -76.835)
		(end 270.891 -76.835)
		(stroke
			(width 0.2)
			(type default)
		)
		(fill no)
		(layer "In1.Cu")
	)
	(gr_circle
		(center 270.002 -76.073)
		(end 270.891 -76.073)
		(stroke
			(width 0.2)
			(type default)
		)
		(fill no)
		(layer "In1.Cu")
	)
	(gr_circle
		(center 270.002 -75.311)
		(end 270.891 -75.311)
		(stroke
			(width 0.2)
			(type default)
		)
		(fill no)
		(layer "In1.Cu")
	)
	(gr_circle
		(center 270.002 -74.549)
		(end 270.891 -74.549)
		(stroke
			(width 0.2)
			(type default)
		)
		(fill no)
		(layer "In1.Cu")
	)
	(gr_circle
		(center 270.002 -73.787)
		(end 270.891 -73.787)
		(stroke
			(width 0.2)
			(type default)
		)
		(fill no)
		(layer "In1.Cu")
	)
	(gr_circle
		(center 270.002 -65.532)
		(end 270.891 -65.532)
		(stroke
			(width 0.2)
			(type default)
		)
		(fill no)
		(layer "In1.Cu")
	)
	(gr_circle
		(center 270.002 -64.77)
		(end 270.891 -64.77)
		(stroke
			(width 0.2)
			(type default)
		)
		(fill no)
		(layer "In1.Cu")
	)
	(gr_circle
		(center 270.002 -64.008)
		(end 270.891 -64.008)
		(stroke
			(width 0.2)
			(type default)
		)
		(fill no)
		(layer "In1.Cu")
	)
	(gr_circle
		(center 270.002 -63.246)
		(end 270.891 -63.246)
		(stroke
			(width 0.2)
			(type default)
		)
		(fill no)
		(layer "In1.Cu")
	)
	(gr_circle
		(center 270.002 -62.484)
		(end 270.891 -62.484)
		(stroke
			(width 0.2)
			(type default)
		)
		(fill no)
		(layer "In1.Cu")
	)
	(gr_circle
		(center 270.002 -61.722)
		(end 270.891 -61.722)
		(stroke
			(width 0.2)
			(type default)
		)
		(fill no)
		(layer "In1.Cu")
	)
	(gr_circle
		(center 270.764 -125.857)
		(end 271.653 -125.857)
		(stroke
			(width 0.2)
			(type default)
		)
		(fill no)
		(layer "In1.Cu")
	)
	(gr_circle
		(center 270.764 -125.095)
		(end 271.653 -125.095)
		(stroke
			(width 0.2)
			(type default)
		)
		(fill no)
		(layer "In1.Cu")
	)
	(gr_circle
		(center 270.764 -124.333)
		(end 271.653 -124.333)
		(stroke
			(width 0.2)
			(type default)
		)
		(fill no)
		(layer "In1.Cu")
	)
	(gr_circle
		(center 270.764 -123.571)
		(end 271.653 -123.571)
		(stroke
			(width 0.2)
			(type default)
		)
		(fill no)
		(layer "In1.Cu")
	)
	(gr_circle
		(center 270.764 -122.809)
		(end 271.653 -122.809)
		(stroke
			(width 0.2)
			(type default)
		)
		(fill no)
		(layer "In1.Cu")
	)
	(gr_circle
		(center 270.764 -122.047)
		(end 271.653 -122.047)
		(stroke
			(width 0.2)
			(type default)
		)
		(fill no)
		(layer "In1.Cu")
	)
	(gr_circle
		(center 270.764 -113.792)
		(end 271.653 -113.792)
		(stroke
			(width 0.2)
			(type default)
		)
		(fill no)
		(layer "In1.Cu")
	)
	(gr_circle
		(center 270.764 -113.03)
		(end 271.653 -113.03)
		(stroke
			(width 0.2)
			(type default)
		)
		(fill no)
		(layer "In1.Cu")
	)
	(gr_circle
		(center 270.764 -112.268)
		(end 271.653 -112.268)
		(stroke
			(width 0.2)
			(type default)
		)
		(fill no)
		(layer "In1.Cu")
	)
	(gr_circle
		(center 270.764 -111.506)
		(end 271.653 -111.506)
		(stroke
			(width 0.2)
			(type default)
		)
		(fill no)
		(layer "In1.Cu")
	)
	(gr_circle
		(center 270.764 -110.744)
		(end 271.653 -110.744)
		(stroke
			(width 0.2)
			(type default)
		)
		(fill no)
		(layer "In1.Cu")
	)
	(gr_circle
		(center 270.764 -109.982)
		(end 271.653 -109.982)
		(stroke
			(width 0.2)
			(type default)
		)
		(fill no)
		(layer "In1.Cu")
	)
	(gr_circle
		(center 270.764 -101.727)
		(end 271.653 -101.727)
		(stroke
			(width 0.2)
			(type default)
		)
		(fill no)
		(layer "In1.Cu")
	)
	(gr_circle
		(center 270.764 -100.965)
		(end 271.653 -100.965)
		(stroke
			(width 0.2)
			(type default)
		)
		(fill no)
		(layer "In1.Cu")
	)
	(gr_circle
		(center 270.764 -100.203)
		(end 271.653 -100.203)
		(stroke
			(width 0.2)
			(type default)
		)
		(fill no)
		(layer "In1.Cu")
	)
	(gr_circle
		(center 270.764 -99.441)
		(end 271.653 -99.441)
		(stroke
			(width 0.2)
			(type default)
		)
		(fill no)
		(layer "In1.Cu")
	)
	(gr_circle
		(center 270.764 -98.679)
		(end 271.653 -98.679)
		(stroke
			(width 0.2)
			(type default)
		)
		(fill no)
		(layer "In1.Cu")
	)
	(gr_circle
		(center 270.764 -97.917)
		(end 271.653 -97.917)
		(stroke
			(width 0.2)
			(type default)
		)
		(fill no)
		(layer "In1.Cu")
	)
	(gr_circle
		(center 270.764 -89.662)
		(end 271.653 -89.662)
		(stroke
			(width 0.2)
			(type default)
		)
		(fill no)
		(layer "In1.Cu")
	)
	(gr_circle
		(center 270.764 -88.9)
		(end 271.653 -88.9)
		(stroke
			(width 0.2)
			(type default)
		)
		(fill no)
		(layer "In1.Cu")
	)
	(gr_circle
		(center 270.764 -88.138)
		(end 271.653 -88.138)
		(stroke
			(width 0.2)
			(type default)
		)
		(fill no)
		(layer "In1.Cu")
	)
	(gr_circle
		(center 270.764 -87.376)
		(end 271.653 -87.376)
		(stroke
			(width 0.2)
			(type default)
		)
		(fill no)
		(layer "In1.Cu")
	)
	(gr_circle
		(center 270.764 -86.614)
		(end 271.653 -86.614)
		(stroke
			(width 0.2)
			(type default)
		)
		(fill no)
		(layer "In1.Cu")
	)
	(gr_circle
		(center 270.764 -85.852)
		(end 271.653 -85.852)
		(stroke
			(width 0.2)
			(type default)
		)
		(fill no)
		(layer "In1.Cu")
	)
	(gr_circle
		(center 270.764 -77.597)
		(end 271.653 -77.597)
		(stroke
			(width 0.2)
			(type default)
		)
		(fill no)
		(layer "In1.Cu")
	)
	(gr_circle
		(center 270.764 -76.835)
		(end 271.653 -76.835)
		(stroke
			(width 0.2)
			(type default)
		)
		(fill no)
		(layer "In1.Cu")
	)
	(gr_circle
		(center 270.764 -76.073)
		(end 271.653 -76.073)
		(stroke
			(width 0.2)
			(type default)
		)
		(fill no)
		(layer "In1.Cu")
	)
	(gr_circle
		(center 270.764 -75.311)
		(end 271.653 -75.311)
		(stroke
			(width 0.2)
			(type default)
		)
		(fill no)
		(layer "In1.Cu")
	)
	(gr_circle
		(center 270.764 -74.549)
		(end 271.653 -74.549)
		(stroke
			(width 0.2)
			(type default)
		)
		(fill no)
		(layer "In1.Cu")
	)
	(gr_circle
		(center 270.764 -73.787)
		(end 271.653 -73.787)
		(stroke
			(width 0.2)
			(type default)
		)
		(fill no)
		(layer "In1.Cu")
	)
	(gr_circle
		(center 270.764 -65.532)
		(end 271.653 -65.532)
		(stroke
			(width 0.2)
			(type default)
		)
		(fill no)
		(layer "In1.Cu")
	)
	(gr_circle
		(center 270.764 -64.77)
		(end 271.653 -64.77)
		(stroke
			(width 0.2)
			(type default)
		)
		(fill no)
		(layer "In1.Cu")
	)
	(gr_circle
		(center 270.764 -64.008)
		(end 271.653 -64.008)
		(stroke
			(width 0.2)
			(type default)
		)
		(fill no)
		(layer "In1.Cu")
	)
	(gr_circle
		(center 270.764 -63.246)
		(end 271.653 -63.246)
		(stroke
			(width 0.2)
			(type default)
		)
		(fill no)
		(layer "In1.Cu")
	)
	(gr_circle
		(center 270.764 -62.484)
		(end 271.653 -62.484)
		(stroke
			(width 0.2)
			(type default)
		)
		(fill no)
		(layer "In1.Cu")
	)
	(gr_circle
		(center 270.764 -61.722)
		(end 271.653 -61.722)
		(stroke
			(width 0.2)
			(type default)
		)
		(fill no)
		(layer "In1.Cu")
	)
	(gr_circle
		(center 270.891 -140.462)
		(end 271.78 -140.462)
		(stroke
			(width 0.2)
			(type default)
		)
		(fill no)
		(layer "In1.Cu")
	)
	(gr_circle
		(center 270.891 -139.7)
		(end 271.78 -139.7)
		(stroke
			(width 0.2)
			(type default)
		)
		(fill no)
		(layer "In1.Cu")
	)
	(gr_circle
		(center 270.891 -138.938)
		(end 271.78 -138.938)
		(stroke
			(width 0.2)
			(type default)
		)
		(fill no)
		(layer "In1.Cu")
	)
	(gr_circle
		(center 270.891 -138.176)
		(end 271.78 -138.176)
		(stroke
			(width 0.2)
			(type default)
		)
		(fill no)
		(layer "In1.Cu")
	)
	(gr_circle
		(center 270.891 -137.414)
		(end 271.78 -137.414)
		(stroke
			(width 0.2)
			(type default)
		)
		(fill no)
		(layer "In1.Cu")
	)
	(gr_circle
		(center 270.891 -136.652)
		(end 271.78 -136.652)
		(stroke
			(width 0.2)
			(type default)
		)
		(fill no)
		(layer "In1.Cu")
	)
	(gr_circle
		(center 271.526 -125.857)
		(end 272.415 -125.857)
		(stroke
			(width 0.2)
			(type default)
		)
		(fill no)
		(layer "In1.Cu")
	)
	(gr_circle
		(center 271.526 -125.095)
		(end 272.415 -125.095)
		(stroke
			(width 0.2)
			(type default)
		)
		(fill no)
		(layer "In1.Cu")
	)
	(gr_circle
		(center 271.526 -122.809)
		(end 272.415 -122.809)
		(stroke
			(width 0.2)
			(type default)
		)
		(fill no)
		(layer "In1.Cu")
	)
	(gr_circle
		(center 271.526 -122.047)
		(end 272.415 -122.047)
		(stroke
			(width 0.2)
			(type default)
		)
		(fill no)
		(layer "In1.Cu")
	)
	(gr_circle
		(center 271.526 -113.792)
		(end 272.415 -113.792)
		(stroke
			(width 0.2)
			(type default)
		)
		(fill no)
		(layer "In1.Cu")
	)
	(gr_circle
		(center 271.526 -113.03)
		(end 272.415 -113.03)
		(stroke
			(width 0.2)
			(type default)
		)
		(fill no)
		(layer "In1.Cu")
	)
	(gr_circle
		(center 271.526 -110.744)
		(end 272.415 -110.744)
		(stroke
			(width 0.2)
			(type default)
		)
		(fill no)
		(layer "In1.Cu")
	)
	(gr_circle
		(center 271.526 -109.982)
		(end 272.415 -109.982)
		(stroke
			(width 0.2)
			(type default)
		)
		(fill no)
		(layer "In1.Cu")
	)
	(gr_circle
		(center 271.526 -101.727)
		(end 272.415 -101.727)
		(stroke
			(width 0.2)
			(type default)
		)
		(fill no)
		(layer "In1.Cu")
	)
	(gr_circle
		(center 271.526 -100.965)
		(end 272.415 -100.965)
		(stroke
			(width 0.2)
			(type default)
		)
		(fill no)
		(layer "In1.Cu")
	)
	(gr_circle
		(center 271.526 -98.679)
		(end 272.415 -98.679)
		(stroke
			(width 0.2)
			(type default)
		)
		(fill no)
		(layer "In1.Cu")
	)
	(gr_circle
		(center 271.526 -97.917)
		(end 272.415 -97.917)
		(stroke
			(width 0.2)
			(type default)
		)
		(fill no)
		(layer "In1.Cu")
	)
	(gr_circle
		(center 271.526 -89.662)
		(end 272.415 -89.662)
		(stroke
			(width 0.2)
			(type default)
		)
		(fill no)
		(layer "In1.Cu")
	)
	(gr_circle
		(center 271.526 -88.9)
		(end 272.415 -88.9)
		(stroke
			(width 0.2)
			(type default)
		)
		(fill no)
		(layer "In1.Cu")
	)
	(gr_circle
		(center 271.526 -86.614)
		(end 272.415 -86.614)
		(stroke
			(width 0.2)
			(type default)
		)
		(fill no)
		(layer "In1.Cu")
	)
	(gr_circle
		(center 271.526 -85.852)
		(end 272.415 -85.852)
		(stroke
			(width 0.2)
			(type default)
		)
		(fill no)
		(layer "In1.Cu")
	)
	(gr_circle
		(center 271.526 -77.597)
		(end 272.415 -77.597)
		(stroke
			(width 0.2)
			(type default)
		)
		(fill no)
		(layer "In1.Cu")
	)
	(gr_circle
		(center 271.526 -76.835)
		(end 272.415 -76.835)
		(stroke
			(width 0.2)
			(type default)
		)
		(fill no)
		(layer "In1.Cu")
	)
	(gr_circle
		(center 271.526 -74.549)
		(end 272.415 -74.549)
		(stroke
			(width 0.2)
			(type default)
		)
		(fill no)
		(layer "In1.Cu")
	)
	(gr_circle
		(center 271.526 -73.787)
		(end 272.415 -73.787)
		(stroke
			(width 0.2)
			(type default)
		)
		(fill no)
		(layer "In1.Cu")
	)
	(gr_circle
		(center 271.526 -65.532)
		(end 272.415 -65.532)
		(stroke
			(width 0.2)
			(type default)
		)
		(fill no)
		(layer "In1.Cu")
	)
	(gr_circle
		(center 271.526 -64.77)
		(end 272.415 -64.77)
		(stroke
			(width 0.2)
			(type default)
		)
		(fill no)
		(layer "In1.Cu")
	)
	(gr_circle
		(center 271.526 -62.484)
		(end 272.415 -62.484)
		(stroke
			(width 0.2)
			(type default)
		)
		(fill no)
		(layer "In1.Cu")
	)
	(gr_circle
		(center 271.526 -61.722)
		(end 272.415 -61.722)
		(stroke
			(width 0.2)
			(type default)
		)
		(fill no)
		(layer "In1.Cu")
	)
	(gr_circle
		(center 271.653 -140.462)
		(end 272.542 -140.462)
		(stroke
			(width 0.2)
			(type default)
		)
		(fill no)
		(layer "In1.Cu")
	)
	(gr_circle
		(center 271.653 -139.7)
		(end 272.542 -139.7)
		(stroke
			(width 0.2)
			(type default)
		)
		(fill no)
		(layer "In1.Cu")
	)
	(gr_circle
		(center 271.653 -138.938)
		(end 272.542 -138.938)
		(stroke
			(width 0.2)
			(type default)
		)
		(fill no)
		(layer "In1.Cu")
	)
	(gr_circle
		(center 271.653 -138.176)
		(end 272.542 -138.176)
		(stroke
			(width 0.2)
			(type default)
		)
		(fill no)
		(layer "In1.Cu")
	)
	(gr_circle
		(center 271.653 -137.414)
		(end 272.542 -137.414)
		(stroke
			(width 0.2)
			(type default)
		)
		(fill no)
		(layer "In1.Cu")
	)
	(gr_circle
		(center 271.653 -136.652)
		(end 272.542 -136.652)
		(stroke
			(width 0.2)
			(type default)
		)
		(fill no)
		(layer "In1.Cu")
	)
	(gr_circle
		(center 272.288 -125.857)
		(end 273.177 -125.857)
		(stroke
			(width 0.2)
			(type default)
		)
		(fill no)
		(layer "In1.Cu")
	)
	(gr_circle
		(center 272.288 -125.095)
		(end 273.177 -125.095)
		(stroke
			(width 0.2)
			(type default)
		)
		(fill no)
		(layer "In1.Cu")
	)
	(gr_circle
		(center 272.288 -122.809)
		(end 273.177 -122.809)
		(stroke
			(width 0.2)
			(type default)
		)
		(fill no)
		(layer "In1.Cu")
	)
	(gr_circle
		(center 272.288 -122.047)
		(end 273.177 -122.047)
		(stroke
			(width 0.2)
			(type default)
		)
		(fill no)
		(layer "In1.Cu")
	)
	(gr_circle
		(center 272.288 -113.792)
		(end 273.177 -113.792)
		(stroke
			(width 0.2)
			(type default)
		)
		(fill no)
		(layer "In1.Cu")
	)
	(gr_circle
		(center 272.288 -113.03)
		(end 273.177 -113.03)
		(stroke
			(width 0.2)
			(type default)
		)
		(fill no)
		(layer "In1.Cu")
	)
	(gr_circle
		(center 272.288 -110.744)
		(end 273.177 -110.744)
		(stroke
			(width 0.2)
			(type default)
		)
		(fill no)
		(layer "In1.Cu")
	)
	(gr_circle
		(center 272.288 -109.982)
		(end 273.177 -109.982)
		(stroke
			(width 0.2)
			(type default)
		)
		(fill no)
		(layer "In1.Cu")
	)
	(gr_circle
		(center 272.288 -101.727)
		(end 273.177 -101.727)
		(stroke
			(width 0.2)
			(type default)
		)
		(fill no)
		(layer "In1.Cu")
	)
	(gr_circle
		(center 272.288 -100.965)
		(end 273.177 -100.965)
		(stroke
			(width 0.2)
			(type default)
		)
		(fill no)
		(layer "In1.Cu")
	)
	(gr_circle
		(center 272.288 -98.679)
		(end 273.177 -98.679)
		(stroke
			(width 0.2)
			(type default)
		)
		(fill no)
		(layer "In1.Cu")
	)
	(gr_circle
		(center 272.288 -97.917)
		(end 273.177 -97.917)
		(stroke
			(width 0.2)
			(type default)
		)
		(fill no)
		(layer "In1.Cu")
	)
	(gr_circle
		(center 272.288 -89.662)
		(end 273.177 -89.662)
		(stroke
			(width 0.2)
			(type default)
		)
		(fill no)
		(layer "In1.Cu")
	)
	(gr_circle
		(center 272.288 -88.9)
		(end 273.177 -88.9)
		(stroke
			(width 0.2)
			(type default)
		)
		(fill no)
		(layer "In1.Cu")
	)
	(gr_circle
		(center 272.288 -86.614)
		(end 273.177 -86.614)
		(stroke
			(width 0.2)
			(type default)
		)
		(fill no)
		(layer "In1.Cu")
	)
	(gr_circle
		(center 272.288 -85.852)
		(end 273.177 -85.852)
		(stroke
			(width 0.2)
			(type default)
		)
		(fill no)
		(layer "In1.Cu")
	)
	(gr_circle
		(center 272.288 -77.597)
		(end 273.177 -77.597)
		(stroke
			(width 0.2)
			(type default)
		)
		(fill no)
		(layer "In1.Cu")
	)
	(gr_circle
		(center 272.288 -76.835)
		(end 273.177 -76.835)
		(stroke
			(width 0.2)
			(type default)
		)
		(fill no)
		(layer "In1.Cu")
	)
	(gr_circle
		(center 272.288 -74.549)
		(end 273.177 -74.549)
		(stroke
			(width 0.2)
			(type default)
		)
		(fill no)
		(layer "In1.Cu")
	)
	(gr_circle
		(center 272.288 -73.787)
		(end 273.177 -73.787)
		(stroke
			(width 0.2)
			(type default)
		)
		(fill no)
		(layer "In1.Cu")
	)
	(gr_circle
		(center 272.288 -65.532)
		(end 273.177 -65.532)
		(stroke
			(width 0.2)
			(type default)
		)
		(fill no)
		(layer "In1.Cu")
	)
	(gr_circle
		(center 272.288 -64.77)
		(end 273.177 -64.77)
		(stroke
			(width 0.2)
			(type default)
		)
		(fill no)
		(layer "In1.Cu")
	)
	(gr_circle
		(center 272.288 -62.484)
		(end 273.177 -62.484)
		(stroke
			(width 0.2)
			(type default)
		)
		(fill no)
		(layer "In1.Cu")
	)
	(gr_circle
		(center 272.288 -61.722)
		(end 273.177 -61.722)
		(stroke
			(width 0.2)
			(type default)
		)
		(fill no)
		(layer "In1.Cu")
	)
	(gr_circle
		(center 272.5928 -23.0886)
		(end 273.4818 -23.0886)
		(stroke
			(width 0.2)
			(type default)
		)
		(fill no)
		(layer "In1.Cu")
	)
	(gr_circle
		(center 273.6088 -23.0886)
		(end 274.4978 -23.0886)
		(stroke
			(width 0.2)
			(type default)
		)
		(fill no)
		(layer "In1.Cu")
	)
	(gr_circle
		(center 275.41855 -33.070038)
		(end 276.30755 -33.070038)
		(stroke
			(width 0.2)
			(type default)
		)
		(fill no)
		(layer "In1.Cu")
	)
	(gr_circle
		(center 276.225 -51.054)
		(end 277.114 -51.054)
		(stroke
			(width 0.2)
			(type default)
		)
		(fill no)
		(layer "In1.Cu")
	)
	(gr_circle
		(center 276.225 -50.292)
		(end 277.114 -50.292)
		(stroke
			(width 0.2)
			(type default)
		)
		(fill no)
		(layer "In1.Cu")
	)
	(gr_circle
		(center 277.368 -20.955)
		(end 278.257 -20.955)
		(stroke
			(width 0.2)
			(type default)
		)
		(fill no)
		(layer "In1.Cu")
	)
	(gr_line
		(start 278.19985 -131.594352)
		(end 278.19985 -61.165994)
		(stroke
			(width 1.016)
			(type default)
		)
		(layer "In1.Cu")
	)
	(gr_line
		(start 278.19985 -97.85985)
		(end 279.6921 -96.3676)
		(stroke
			(width 1.016)
			(type default)
		)
		(layer "In1.Cu")
	)
	(gr_line
		(start 278.19985 -94.87535)
		(end 279.6921 -96.3676)
		(stroke
			(width 1.016)
			(type default)
		)
		(layer "In1.Cu")
	)
	(gr_line
		(start 278.19985 -61.165994)
		(end 278.19985 -55.65775)
		(stroke
			(width 1.016)
			(type default)
		)
		(layer "In1.Cu")
	)
	(gr_line
		(start 278.19985 -55.65775)
		(end 278.19985 -52.12715)
		(stroke
			(width 1.016)
			(type default)
		)
		(layer "In1.Cu")
	)
	(gr_line
		(start 278.19985 -55.65775)
		(end 279.648666 -57.106566)
		(stroke
			(width 1.016)
			(type default)
		)
		(layer "In1.Cu")
	)
	(gr_line
		(start 278.19985 -52.12715)
		(end 281.3558 -48.9712)
		(stroke
			(width 1.016)
			(type default)
		)
		(layer "In1.Cu")
	)
	(gr_line
		(start 278.326342 -58.394854)
		(end 279.648666 -59.717178)
		(stroke
			(width 1.016)
			(type default)
		)
		(layer "In1.Cu")
	)
	(gr_line
		(start 278.326342 -58.027062)
		(end 278.326342 -58.394854)
		(stroke
			(width 1.016)
			(type default)
		)
		(layer "In1.Cu")
	)
	(gr_line
		(start 278.326342 -58.027062)
		(end 295.422574 -58.027062)
		(stroke
			(width 1.016)
			(type default)
		)
		(layer "In1.Cu")
	)
	(gr_line
		(start 278.34971 -57.345072)
		(end 295.070022 -57.345072)
		(stroke
			(width 1.016)
			(type default)
		)
		(layer "In1.Cu")
	)
	(gr_line
		(start 278.44369 -60.00242)
		(end 278.44369 -59.838082)
		(stroke
			(width 1.016)
			(type default)
		)
		(layer "In1.Cu")
	)
	(gr_line
		(start 278.44369 -59.838082)
		(end 279.619964 -58.661808)
		(stroke
			(width 1.016)
			(type default)
		)
		(layer "In1.Cu")
	)
	(gr_line
		(start 278.8412 -55.245)
		(end 278.8412 -52.5018)
		(stroke
			(width 1.016)
			(type default)
		)
		(layer "In1.Cu")
	)
	(gr_line
		(start 278.8412 -52.5018)
		(end 281.432 -49.911)
		(stroke
			(width 1.016)
			(type default)
		)
		(layer "In1.Cu")
	)
	(gr_line
		(start 279.0571 -56.515)
		(end 278.19985 -55.65775)
		(stroke
			(width 1.016)
			(type default)
		)
		(layer "In1.Cu")
	)
	(gr_line
		(start 279.290526 -58.991246)
		(end 278.326342 -58.027062)
		(stroke
			(width 1.016)
			(type default)
		)
		(layer "In1.Cu")
	)
	(gr_line
		(start 279.565862 -132.960364)
		(end 278.19985 -131.594352)
		(stroke
			(width 1.016)
			(type default)
		)
		(layer "In1.Cu")
	)
	(gr_line
		(start 279.6032 -56.007)
		(end 278.8412 -55.245)
		(stroke
			(width 1.016)
			(type default)
		)
		(layer "In1.Cu")
	)
	(gr_line
		(start 279.6032 -56.007)
		(end 285.3436 -56.007)
		(stroke
			(width 2.032)
			(type default)
		)
		(layer "In1.Cu")
	)
	(gr_line
		(start 279.6032 -56.007)
		(end 287.6042 -56.007)
		(stroke
			(width 2.032)
			(type default)
		)
		(layer "In1.Cu")
	)
	(gr_line
		(start 279.6032 -52.8066)
		(end 279.6032 -56.007)
		(stroke
			(width 2.032)
			(type default)
		)
		(layer "In1.Cu")
	)
	(gr_line
		(start 279.619964 -58.661808)
		(end 296.386758 -58.661808)
		(stroke
			(width 1.016)
			(type default)
		)
		(layer "In1.Cu")
	)
	(gr_line
		(start 279.648666 -59.717178)
		(end 278.19985 -61.165994)
		(stroke
			(width 1.016)
			(type default)
		)
		(layer "In1.Cu")
	)
	(gr_line
		(start 279.648666 -59.717178)
		(end 291.200078 -59.717178)
		(stroke
			(width 1.016)
			(type default)
		)
		(layer "In1.Cu")
	)
	(gr_line
		(start 281.0002 -55.0164)
		(end 281.1018 -55.118)
		(stroke
			(width 2.032)
			(type default)
		)
		(layer "In1.Cu")
	)
	(gr_line
		(start 281.0002 -53.8988)
		(end 281.0002 -55.0164)
		(stroke
			(width 2.032)
			(type default)
		)
		(layer "In1.Cu")
	)
	(gr_line
		(start 281.1018 -55.118)
		(end 284.2768 -55.118)
		(stroke
			(width 2.032)
			(type default)
		)
		(layer "In1.Cu")
	)
	(gr_line
		(start 281.3558 -48.9712)
		(end 288.2392 -48.9712)
		(stroke
			(width 1.016)
			(type default)
		)
		(layer "In1.Cu")
	)
	(gr_line
		(start 281.408632 -49.65827)
		(end 288.292032 -49.65827)
		(stroke
			(width 1.016)
			(type default)
		)
		(layer "In1.Cu")
	)
	(gr_line
		(start 281.94 -50.4698)
		(end 279.6032 -52.8066)
		(stroke
			(width 2.032)
			(type default)
		)
		(layer "In1.Cu")
	)
	(gr_line
		(start 282.575 -54.1782)
		(end 283.5148 -54.1782)
		(stroke
			(width 2.032)
			(type default)
		)
		(layer "In1.Cu")
	)
	(gr_line
		(start 283.1338 -51.7652)
		(end 281.0002 -53.8988)
		(stroke
			(width 2.032)
			(type default)
		)
		(layer "In1.Cu")
	)
	(gr_circle
		(center 283.413454 -32.1564)
		(end 284.302454 -32.1564)
		(stroke
			(width 0.2)
			(type default)
		)
		(fill no)
		(layer "In1.Cu")
	)
	(gr_line
		(start 283.5148 -54.1782)
		(end 283.845 -53.848)
		(stroke
			(width 2.032)
			(type default)
		)
		(layer "In1.Cu")
	)
	(gr_line
		(start 283.7942 -52.959)
		(end 282.575 -54.1782)
		(stroke
			(width 2.032)
			(type default)
		)
		(layer "In1.Cu")
	)
	(gr_line
		(start 284.2768 -55.118)
		(end 285.8008 -53.594)
		(stroke
			(width 2.032)
			(type default)
		)
		(layer "In1.Cu")
	)
	(gr_circle
		(center 285.242 -30.687264)
		(end 286.131 -30.687264)
		(stroke
			(width 0.2)
			(type default)
		)
		(fill no)
		(layer "In1.Cu")
	)
	(gr_line
		(start 285.3436 -56.007)
		(end 287.2232 -54.1274)
		(stroke
			(width 2.032)
			(type default)
		)
		(layer "In1.Cu")
	)
	(gr_line
		(start 285.8008 -53.594)
		(end 285.8008 -52.959)
		(stroke
			(width 2.032)
			(type default)
		)
		(layer "In1.Cu")
	)
	(gr_line
		(start 285.8008 -52.959)
		(end 283.7942 -52.959)
		(stroke
			(width 2.032)
			(type default)
		)
		(layer "In1.Cu")
	)
	(gr_circle
		(center 286.004 -30.687264)
		(end 286.893 -30.687264)
		(stroke
			(width 0.2)
			(type default)
		)
		(fill no)
		(layer "In1.Cu")
	)
	(gr_line
		(start 286.9184 -51.7652)
		(end 283.1338 -51.7652)
		(stroke
			(width 2.032)
			(type default)
		)
		(layer "In1.Cu")
	)
	(gr_line
		(start 287.2232 -54.1274)
		(end 287.2232 -52.07)
		(stroke
			(width 2.032)
			(type default)
		)
		(layer "In1.Cu")
	)
	(gr_line
		(start 287.2232 -52.07)
		(end 286.9184 -51.7652)
		(stroke
			(width 2.032)
			(type default)
		)
		(layer "In1.Cu")
	)
	(gr_circle
		(center 287.401 -30.687264)
		(end 288.29 -30.687264)
		(stroke
			(width 0.2)
			(type default)
		)
		(fill no)
		(layer "In1.Cu")
	)
	(gr_line
		(start 287.6042 -56.007)
		(end 288.544 -55.0672)
		(stroke
			(width 2.032)
			(type default)
		)
		(layer "In1.Cu")
	)
	(gr_line
		(start 288.1376 -50.4698)
		(end 281.94 -50.4698)
		(stroke
			(width 2.032)
			(type default)
		)
		(layer "In1.Cu")
	)
	(gr_circle
		(center 288.163 -30.687264)
		(end 289.052 -30.687264)
		(stroke
			(width 0.2)
			(type default)
		)
		(fill no)
		(layer "In1.Cu")
	)
	(gr_line
		(start 288.2392 -48.9712)
		(end 289.2552 -49.9872)
		(stroke
			(width 1.016)
			(type default)
		)
		(layer "In1.Cu")
	)
	(gr_line
		(start 288.544 -55.0672)
		(end 288.544 -50.8762)
		(stroke
			(width 2.032)
			(type default)
		)
		(layer "In1.Cu")
	)
	(gr_line
		(start 288.544 -50.8762)
		(end 288.1376 -50.4698)
		(stroke
			(width 2.032)
			(type default)
		)
		(layer "In1.Cu")
	)
	(gr_line
		(start 289.2552 -55.499)
		(end 289.7632 -56.007)
		(stroke
			(width 1.016)
			(type default)
		)
		(layer "In1.Cu")
	)
	(gr_line
		(start 289.2552 -49.9872)
		(end 289.2552 -55.499)
		(stroke
			(width 1.016)
			(type default)
		)
		(layer "In1.Cu")
	)
	(gr_line
		(start 289.2552 -49.9872)
		(end 290.473384 -51.205384)
		(stroke
			(width 1.016)
			(type default)
		)
		(layer "In1.Cu")
	)
	(gr_line
		(start 289.67811 -50.660808)
		(end 289.67811 -56.172608)
		(stroke
			(width 1.016)
			(type default)
		)
		(layer "In1.Cu")
	)
	(gr_line
		(start 289.7632 -56.007)
		(end 279.6032 -56.007)
		(stroke
			(width 1.016)
			(type default)
		)
		(layer "In1.Cu")
	)
	(gr_line
		(start 290.034726 -50.991008)
		(end 290.034726 -56.502808)
		(stroke
			(width 1.016)
			(type default)
		)
		(layer "In1.Cu")
	)
	(gr_line
		(start 290.473384 -51.205384)
		(end 301.995332 -51.205384)
		(stroke
			(width 1.016)
			(type default)
		)
		(layer "In1.Cu")
	)
	(gr_line
		(start 290.82746 -51.255422)
		(end 290.82746 -56.767222)
		(stroke
			(width 1.016)
			(type default)
		)
		(layer "In1.Cu")
	)
	(gr_line
		(start 291.064696 -56.515)
		(end 290.1442 -55.594504)
		(stroke
			(width 1.016)
			(type default)
		)
		(layer "In1.Cu")
	)
	(gr_line
		(start 291.505386 -55.734458)
		(end 290.871148 -55.10022)
		(stroke
			(width 1.016)
			(type default)
		)
		(layer "In1.Cu")
	)
	(gr_line
		(start 291.5539 -51.347878)
		(end 291.5539 -56.859678)
		(stroke
			(width 1.016)
			(type default)
		)
		(layer "In1.Cu")
	)
	(gr_line
		(start 291.901626 -54.915562)
		(end 291.584634 -54.59857)
		(stroke
			(width 1.016)
			(type default)
		)
		(layer "In1.Cu")
	)
	(gr_line
		(start 292.007036 -52.775612)
		(end 292.773354 -53.54193)
		(stroke
			(width 1.016)
			(type default)
		)
		(layer "In1.Cu")
	)
	(gr_line
		(start 292.007036 -51.375564)
		(end 292.007036 -52.775612)
		(stroke
			(width 1.016)
			(type default)
		)
		(layer "In1.Cu")
	)
	(gr_line
		(start 292.245034 -54.123082)
		(end 292.245034 -51.851052)
		(stroke
			(width 1.016)
			(type default)
		)
		(layer "In1.Cu")
	)
	(gr_line
		(start 292.245034 -51.851052)
		(end 292.654482 -51.441604)
		(stroke
			(width 1.016)
			(type default)
		)
		(layer "In1.Cu")
	)
	(gr_line
		(start 292.324282 -54.20233)
		(end 292.245034 -54.123082)
		(stroke
			(width 1.016)
			(type default)
		)
		(layer "In1.Cu")
	)
	(gr_line
		(start 292.614858 -52.485036)
		(end 293.037768 -52.907946)
		(stroke
			(width 1.016)
			(type default)
		)
		(layer "In1.Cu")
	)
	(gr_line
		(start 292.654482 -51.441604)
		(end 297.330876 -51.441604)
		(stroke
			(width 1.016)
			(type default)
		)
		(layer "In1.Cu")
	)
	(gr_line
		(start 292.773354 -53.54193)
		(end 296.472102 -53.54193)
		(stroke
			(width 1.016)
			(type default)
		)
		(layer "In1.Cu")
	)
	(gr_line
		(start 292.93185 -52.168044)
		(end 292.614858 -52.485036)
		(stroke
			(width 1.016)
			(type default)
		)
		(layer "In1.Cu")
	)
	(gr_line
		(start 293.037768 -52.907946)
		(end 295.969944 -52.907946)
		(stroke
			(width 1.016)
			(type default)
		)
		(layer "In1.Cu")
	)
	(gr_circle
		(center 294.132 -45.466)
		(end 295.021 -45.466)
		(stroke
			(width 0.2)
			(type default)
		)
		(fill no)
		(layer "In1.Cu")
	)
	(gr_circle
		(center 294.1828 -34.9758)
		(end 295.0718 -34.9758)
		(stroke
			(width 0.2)
			(type default)
		)
		(fill no)
		(layer "In1.Cu")
	)
	(gr_circle
		(center 294.6908 -44.699428)
		(end 295.5798 -44.699428)
		(stroke
			(width 0.2)
			(type default)
		)
		(fill no)
		(layer "In1.Cu")
	)
	(gr_line
		(start 295.070022 -57.345072)
		(end 296.386758 -58.661808)
		(stroke
			(width 1.016)
			(type default)
		)
		(layer "In1.Cu")
	)
	(gr_line
		(start 295.323006 -56.515)
		(end 279.0571 -56.515)
		(stroke
			(width 1.016)
			(type default)
		)
		(layer "In1.Cu")
	)
	(gr_circle
		(center 295.3258 -44.693586)
		(end 296.2148 -44.693586)
		(stroke
			(width 0.2)
			(type default)
		)
		(fill no)
		(layer "In1.Cu")
	)
	(gr_line
		(start 295.422574 -58.027062)
		(end 296.386758 -58.991246)
		(stroke
			(width 1.016)
			(type default)
		)
		(layer "In1.Cu")
	)
	(gr_line
		(start 295.660826 -59.717178)
		(end 279.648666 -59.717178)
		(stroke
			(width 1.016)
			(type default)
		)
		(layer "In1.Cu")
	)
	(gr_line
		(start 295.706038 -55.734458)
		(end 291.505386 -55.734458)
		(stroke
			(width 1.016)
			(type default)
		)
		(layer "In1.Cu")
	)
	(gr_line
		(start 295.917112 -52.168044)
		(end 292.93185 -52.168044)
		(stroke
			(width 1.016)
			(type default)
		)
		(layer "In1.Cu")
	)
	(gr_line
		(start 295.969944 -54.915562)
		(end 291.901626 -54.915562)
		(stroke
			(width 1.016)
			(type default)
		)
		(layer "In1.Cu")
	)
	(gr_line
		(start 296.181272 -51.375564)
		(end 292.007036 -51.375564)
		(stroke
			(width 1.016)
			(type default)
		)
		(layer "In1.Cu")
	)
	(gr_line
		(start 296.366438 -54.20233)
		(end 292.324282 -54.20233)
		(stroke
			(width 1.016)
			(type default)
		)
		(layer "In1.Cu")
	)
	(gr_line
		(start 296.386758 -58.991246)
		(end 279.290526 -58.991246)
		(stroke
			(width 1.016)
			(type default)
		)
		(layer "In1.Cu")
	)
	(gr_line
		(start 296.386758 -58.991246)
		(end 295.660826 -59.717178)
		(stroke
			(width 1.016)
			(type default)
		)
		(layer "In1.Cu")
	)
	(gr_line
		(start 296.386758 -58.661808)
		(end 296.386758 -58.991246)
		(stroke
			(width 1.016)
			(type default)
		)
		(layer "In1.Cu")
	)
	(gr_line
		(start 296.472102 -53.54193)
		(end 302.390048 -59.459876)
		(stroke
			(width 1.016)
			(type default)
		)
		(layer "In1.Cu")
	)
	(gr_line
		(start 297.0784 -59.406028)
		(end 296.76725 -59.717178)
		(stroke
			(width 1.016)
			(type default)
		)
		(layer "In1.Cu")
	)
	(gr_line
		(start 297.0784 -59.406028)
		(end 297.0784 -58.5724)
		(stroke
			(width 1.016)
			(type default)
		)
		(layer "In1.Cu")
	)
	(gr_line
		(start 297.330876 -51.441604)
		(end 303.407064 -57.517792)
		(stroke
			(width 1.016)
			(type default)
		)
		(layer "In1.Cu")
	)
	(gr_line
		(start 298.215812 -51.520852)
		(end 304.292 -57.59704)
		(stroke
			(width 1.016)
			(type default)
		)
		(layer "In1.Cu")
	)
	(gr_line
		(start 298.26077 -46.604428)
		(end 298.64177 -46.985428)
		(stroke
			(width 1.016)
			(type default)
		)
		(layer "In1.Cu")
	)
	(gr_line
		(start 298.26077 -38.218364)
		(end 298.26077 -46.604428)
		(stroke
			(width 1.016)
			(type default)
		)
		(layer "In1.Cu")
	)
	(gr_line
		(start 298.271184 -96.3676)
		(end 278.19985 -96.3676)
		(stroke
			(width 1.016)
			(type default)
		)
		(layer "In1.Cu")
	)
	(gr_line
		(start 298.510706 -37.968428)
		(end 298.26077 -38.218364)
		(stroke
			(width 1.016)
			(type default)
		)
		(layer "In1.Cu")
	)
	(gr_line
		(start 298.525184 -59.717178)
		(end 291.200078 -59.717178)
		(stroke
			(width 1.016)
			(type default)
		)
		(layer "In1.Cu")
	)
	(gr_line
		(start 298.533566 -132.960364)
		(end 279.565862 -132.960364)
		(stroke
			(width 1.016)
			(type default)
		)
		(layer "In1.Cu")
	)
	(gr_line
		(start 298.64177 -46.985428)
		(end 302.45177 -46.985428)
		(stroke
			(width 1.016)
			(type default)
		)
		(layer "In1.Cu")
	)
	(gr_line
		(start 298.902882 -51.53406)
		(end 304.97907 -57.610248)
		(stroke
			(width 1.016)
			(type default)
		)
		(layer "In1.Cu")
	)
	(gr_line
		(start 298.971716 -46.985428)
		(end 298.971716 -37.991796)
		(stroke
			(width 1.016)
			(type default)
		)
		(layer "In1.Cu")
	)
	(gr_line
		(start 298.971716 -37.991796)
		(end 298.995084 -37.968428)
		(stroke
			(width 1.016)
			(type default)
		)
		(layer "In1.Cu")
	)
	(gr_line
		(start 299.37837 -51.33594)
		(end 305.454558 -57.412128)
		(stroke
			(width 1.016)
			(type default)
		)
		(layer "In1.Cu")
	)
	(gr_line
		(start 299.479716 -46.985428)
		(end 299.479716 -37.991796)
		(stroke
			(width 1.016)
			(type default)
		)
		(layer "In1.Cu")
	)
	(gr_line
		(start 299.479716 -37.991796)
		(end 299.503084 -37.968428)
		(stroke
			(width 1.016)
			(type default)
		)
		(layer "In1.Cu")
	)
	(gr_line
		(start 299.763434 -131.730496)
		(end 298.533566 -132.960364)
		(stroke
			(width 1.016)
			(type default)
		)
		(layer "In1.Cu")
	)
	(gr_line
		(start 299.763434 -127.672338)
		(end 299.763434 -131.730496)
		(stroke
			(width 1.016)
			(type default)
		)
		(layer "In1.Cu")
	)
	(gr_line
		(start 299.763434 -127.672338)
		(end 299.763434 -126.359666)
		(stroke
			(width 1.016)
			(type default)
		)
		(layer "In1.Cu")
	)
	(gr_line
		(start 299.763434 -127.672338)
		(end 299.763434 -126.219966)
		(stroke
			(width 1.016)
			(type default)
		)
		(layer "In1.Cu")
	)
	(gr_line
		(start 299.763434 -126.219966)
		(end 303.6824 -122.301)
		(stroke
			(width 1.016)
			(type default)
		)
		(layer "In1.Cu")
	)
	(gr_line
		(start 299.763434 -125.046994)
		(end 299.763434 -126.359666)
		(stroke
			(width 1.016)
			(type default)
		)
		(layer "In1.Cu")
	)
	(gr_line
		(start 299.763434 -125.046994)
		(end 299.763434 -122.1994)
		(stroke
			(width 1.016)
			(type default)
		)
		(layer "In1.Cu")
	)
	(gr_line
		(start 299.763434 -122.1994)
		(end 299.763434 -60.955428)
		(stroke
			(width 1.016)
			(type default)
		)
		(layer "In1.Cu")
	)
	(gr_line
		(start 299.763434 -97.85985)
		(end 298.271184 -96.3676)
		(stroke
			(width 1.016)
			(type default)
		)
		(layer "In1.Cu")
	)
	(gr_line
		(start 299.763434 -96.3676)
		(end 298.271184 -96.3676)
		(stroke
			(width 1.016)
			(type default)
		)
		(layer "In1.Cu")
	)
	(gr_line
		(start 299.763434 -94.87535)
		(end 298.271184 -96.3676)
		(stroke
			(width 1.016)
			(type default)
		)
		(layer "In1.Cu")
	)
	(gr_line
		(start 299.763434 -60.955428)
		(end 295.323006 -56.515)
		(stroke
			(width 1.016)
			(type default)
		)
		(layer "In1.Cu")
	)
	(gr_line
		(start 299.987716 -46.985428)
		(end 299.987716 -37.991796)
		(stroke
			(width 1.016)
			(type default)
		)
		(layer "In1.Cu")
	)
	(gr_line
		(start 299.987716 -37.991796)
		(end 300.011084 -37.968428)
		(stroke
			(width 1.016)
			(type default)
		)
		(layer "In1.Cu")
	)
	(gr_line
		(start 300.172374 -51.443128)
		(end 304.628042 -55.898796)
		(stroke
			(width 1.016)
			(type default)
		)
		(layer "In1.Cu")
	)
	(gr_line
		(start 300.461426 -73.303384)
		(end 300.461426 -60.041028)
		(stroke
			(width 1.016)
			(type default)
		)
		(layer "In1.Cu")
	)
	(gr_line
		(start 300.495716 -46.985428)
		(end 300.495716 -37.991796)
		(stroke
			(width 1.016)
			(type default)
		)
		(layer "In1.Cu")
	)
	(gr_line
		(start 300.495716 -37.991796)
		(end 300.519084 -37.968428)
		(stroke
			(width 1.016)
			(type default)
		)
		(layer "In1.Cu")
	)
	(gr_line
		(start 300.501304 -60.529724)
		(end 295.706038 -55.734458)
		(stroke
			(width 1.016)
			(type default)
		)
		(layer "In1.Cu")
	)
	(gr_line
		(start 300.56709 -73.554336)
		(end 299.748194 -74.373232)
		(stroke
			(width 1.016)
			(type default)
		)
		(layer "In1.Cu")
	)
	(gr_line
		(start 300.56709 -73.534524)
		(end 299.748194 -72.715628)
		(stroke
			(width 1.016)
			(type default)
		)
		(layer "In1.Cu")
	)
	(gr_line
		(start 300.832774 -51.390296)
		(end 305.288442 -55.845964)
		(stroke
			(width 1.016)
			(type default)
		)
		(layer "In1.Cu")
	)
	(gr_line
		(start 301.003716 -46.985428)
		(end 301.003716 -37.991796)
		(stroke
			(width 1.016)
			(type default)
		)
		(layer "In1.Cu")
	)
	(gr_line
		(start 301.003716 -37.991796)
		(end 301.027084 -37.968428)
		(stroke
			(width 1.016)
			(type default)
		)
		(layer "In1.Cu")
	)
	(gr_line
		(start 301.069248 -73.276968)
		(end 301.069248 -60.014612)
		(stroke
			(width 1.016)
			(type default)
		)
		(layer "In1.Cu")
	)
	(gr_line
		(start 301.084742 -122.1994)
		(end 299.763434 -123.520708)
		(stroke
			(width 1.016)
			(type default)
		)
		(layer "In1.Cu")
	)
	(gr_line
		(start 301.084742 -122.1994)
		(end 299.763434 -120.878092)
		(stroke
			(width 1.016)
			(type default)
		)
		(layer "In1.Cu")
	)
	(gr_line
		(start 301.214282 -73.554336)
		(end 300.56709 -73.554336)
		(stroke
			(width 1.016)
			(type default)
		)
		(layer "In1.Cu")
	)
	(gr_line
		(start 301.22749 -60.173108)
		(end 295.969944 -54.915562)
		(stroke
			(width 1.016)
			(type default)
		)
		(layer "In1.Cu")
	)
	(gr_line
		(start 301.38624 -73.276968)
		(end 301.38624 -60.014612)
		(stroke
			(width 1.016)
			(type default)
		)
		(layer "In1.Cu")
	)
	(gr_line
		(start 301.447708 -122.503692)
		(end 300.1264 -123.825)
		(stroke
			(width 1.016)
			(type default)
		)
		(layer "In1.Cu")
	)
	(gr_line
		(start 301.466758 -51.49596)
		(end 305.922426 -55.951628)
		(stroke
			(width 1.016)
			(type default)
		)
		(layer "In1.Cu")
	)
	(gr_line
		(start 301.511716 -46.985428)
		(end 301.511716 -37.991796)
		(stroke
			(width 1.016)
			(type default)
		)
		(layer "In1.Cu")
	)
	(gr_line
		(start 301.511716 -37.991796)
		(end 301.535084 -37.968428)
		(stroke
			(width 1.016)
			(type default)
		)
		(layer "In1.Cu")
	)
	(gr_line
		(start 301.993808 -73.092056)
		(end 301.993808 -59.8297)
		(stroke
			(width 1.016)
			(type default)
		)
		(layer "In1.Cu")
	)
	(gr_line
		(start 301.993808 -59.8297)
		(end 296.366438 -54.20233)
		(stroke
			(width 1.016)
			(type default)
		)
		(layer "In1.Cu")
	)
	(gr_line
		(start 301.995332 -51.205384)
		(end 306.451 -55.661052)
		(stroke
			(width 1.016)
			(type default)
		)
		(layer "In1.Cu")
	)
	(gr_line
		(start 302.019716 -46.985428)
		(end 302.019716 -37.991796)
		(stroke
			(width 1.016)
			(type default)
		)
		(layer "In1.Cu")
	)
	(gr_line
		(start 302.019716 -37.991796)
		(end 302.043084 -37.968428)
		(stroke
			(width 1.016)
			(type default)
		)
		(layer "In1.Cu")
	)
	(gr_line
		(start 302.390048 -59.459876)
		(end 302.390048 -58.64098)
		(stroke
			(width 1.016)
			(type default)
		)
		(layer "In1.Cu")
	)
	(gr_line
		(start 302.390048 -58.64098)
		(end 295.917112 -52.168044)
		(stroke
			(width 1.016)
			(type default)
		)
		(layer "In1.Cu")
	)
	(gr_line
		(start 302.45177 -46.985428)
		(end 302.85817 -46.579028)
		(stroke
			(width 1.016)
			(type default)
		)
		(layer "In1.Cu")
	)
	(gr_line
		(start 302.50257 -37.968428)
		(end 298.510706 -37.968428)
		(stroke
			(width 1.016)
			(type default)
		)
		(layer "In1.Cu")
	)
	(gr_line
		(start 302.50257 -37.968428)
		(end 302.85817 -38.324028)
		(stroke
			(width 1.016)
			(type default)
		)
		(layer "In1.Cu")
	)
	(gr_line
		(start 302.509428 -122.301)
		(end 299.763434 -125.046994)
		(stroke
			(width 1.016)
			(type default)
		)
		(layer "In1.Cu")
	)
	(gr_line
		(start 302.548798 -73.276968)
		(end 302.548798 -60.014612)
		(stroke
			(width 1.016)
			(type default)
		)
		(layer "In1.Cu")
	)
	(gr_line
		(start 302.707294 -71.692262)
		(end 302.707294 -57.901586)
		(stroke
			(width 1.016)
			(type default)
		)
		(layer "In1.Cu")
	)
	(gr_line
		(start 302.707294 -57.901586)
		(end 296.181272 -51.375564)
		(stroke
			(width 1.016)
			(type default)
		)
		(layer "In1.Cu")
	)
	(gr_line
		(start 302.85817 -46.579028)
		(end 302.85817 -38.324028)
		(stroke
			(width 1.016)
			(type default)
		)
		(layer "In1.Cu")
	)
	(gr_line
		(start 303.050448 -72.035416)
		(end 302.707294 -71.692262)
		(stroke
			(width 1.016)
			(type default)
		)
		(layer "In1.Cu")
	)
	(gr_line
		(start 303.104042 -57.214262)
		(end 306.036218 -57.214262)
		(stroke
			(width 1.016)
			(type default)
		)
		(layer "In1.Cu")
	)
	(gr_line
		(start 303.18329 -56.606694)
		(end 306.115466 -56.606694)
		(stroke
			(width 1.016)
			(type default)
		)
		(layer "In1.Cu")
	)
	(gr_line
		(start 303.288954 -56.065166)
		(end 306.22113 -56.065166)
		(stroke
			(width 1.016)
			(type default)
		)
		(layer "In1.Cu")
	)
	(gr_line
		(start 303.407064 -71.6788)
		(end 303.050448 -72.035416)
		(stroke
			(width 1.016)
			(type default)
		)
		(layer "In1.Cu")
	)
	(gr_line
		(start 303.407064 -57.517792)
		(end 303.407064 -71.6788)
		(stroke
			(width 1.016)
			(type default)
		)
		(layer "In1.Cu")
	)
	(gr_line
		(start 303.6824 -122.301)
		(end 302.509428 -122.301)
		(stroke
			(width 1.016)
			(type default)
		)
		(layer "In1.Cu")
	)
	(gr_line
		(start 303.948846 -72.035416)
		(end 303.050448 -72.035416)
		(stroke
			(width 1.016)
			(type default)
		)
		(layer "In1.Cu")
	)
	(gr_line
		(start 304.014378 -72.894698)
		(end 302.614076 -72.894698)
		(stroke
			(width 1.016)
			(type default)
		)
		(layer "In1.Cu")
	)
	(gr_line
		(start 304.160174 -71.824088)
		(end 303.948846 -72.035416)
		(stroke
			(width 1.016)
			(type default)
		)
		(layer "In1.Cu")
	)
	(gr_line
		(start 304.160174 -57.346342)
		(end 304.160174 -71.824088)
		(stroke
			(width 1.016)
			(type default)
		)
		(layer "In1.Cu")
	)
	(gr_line
		(start 304.365406 -122.1994)
		(end 304.688494 -122.1994)
		(stroke
			(width 1.016)
			(type default)
		)
		(layer "In1.Cu")
	)
	(gr_line
		(start 304.688494 -72.458072)
		(end 303.288192 -72.458072)
		(stroke
			(width 1.016)
			(type default)
		)
		(layer "In1.Cu")
	)
	(gr_line
		(start 304.97907 -72.167496)
		(end 304.688494 -72.458072)
		(stroke
			(width 1.016)
			(type default)
		)
		(layer "In1.Cu")
	)
	(gr_line
		(start 304.97907 -57.161176)
		(end 304.97907 -72.167496)
		(stroke
			(width 1.016)
			(type default)
		)
		(layer "In1.Cu")
	)
	(gr_line
		(start 305.362102 -72.973184)
		(end 303.62525 -72.973184)
		(stroke
			(width 1.016)
			(type default)
		)
		(layer "In1.Cu")
	)
	(gr_line
		(start 305.66614 -72.669146)
		(end 305.362102 -72.973184)
		(stroke
			(width 1.016)
			(type default)
		)
		(layer "In1.Cu")
	)
	(gr_line
		(start 305.66614 -56.923432)
		(end 305.66614 -72.669146)
		(stroke
			(width 1.016)
			(type default)
		)
		(layer "In1.Cu")
	)
	(gr_line
		(start 306.38115 -73.53935)
		(end 299.92447 -73.53935)
		(stroke
			(width 1.016)
			(type default)
		)
		(layer "In1.Cu")
	)
	(gr_line
		(start 306.451 -73.6092)
		(end 306.38115 -73.53935)
		(stroke
			(width 1.016)
			(type default)
		)
		(layer "In1.Cu")
	)
	(gr_line
		(start 306.451 -73.6092)
		(end 308.6608 -75.819)
		(stroke
			(width 1.016)
			(type default)
		)
		(layer "In1.Cu")
	)
	(gr_line
		(start 306.451 -56.5912)
		(end 306.451 -73.6092)
		(stroke
			(width 1.016)
			(type default)
		)
		(layer "In1.Cu")
	)
	(gr_line
		(start 306.451 -55.661052)
		(end 306.451 -56.5912)
		(stroke
			(width 1.016)
			(type default)
		)
		(layer "In1.Cu")
	)
	(gr_line
		(start 308.6608 -75.819)
		(end 319.8876 -75.819)
		(stroke
			(width 1.016)
			(type default)
		)
		(layer "In1.Cu")
	)
	(gr_circle
		(center 311.410096 -72.879966)
		(end 312.809128 -72.879966)
		(stroke
			(width 0.2)
			(type default)
		)
		(fill no)
		(layer "In1.Cu")
	)
	(gr_line
		(start 319.6336 -122.1994)
		(end 299.763434 -122.1994)
		(stroke
			(width 1.016)
			(type default)
		)
		(layer "In1.Cu")
	)
	(gr_line
		(start 319.8876 -75.819)
		(end 320.929 -76.8604)
		(stroke
			(width 1.016)
			(type default)
		)
		(layer "In1.Cu")
	)
	(gr_line
		(start 320.929 -120.904)
		(end 319.6336 -122.1994)
		(stroke
			(width 1.016)
			(type default)
		)
		(layer "In1.Cu")
	)
	(gr_line
		(start 320.929 -76.8604)
		(end 320.929 -120.904)
		(stroke
			(width 1.016)
			(type default)
		)
		(layer "In1.Cu")
	)
	(gr_poly
		(pts
			(xy 295.3893 -131.6609) (xy 295.3893 -118.1989) (xy 295.9989 -117.5893) (xy 295.9989 -97.5614) (xy 295.4655 -97.028)
			(xy 279.4 -97.028) (xy 278.99868 -97.42932) (xy 278.99868 -131.351782) (xy 279.726898 -132.08) (xy 294.9702 -132.08)
		)
		(stroke
			(width 0)
			(type solid)
		)
		(fill yes)
		(layer "In2.Cu")
		(net "P52V_HS1_DRAIN_1")
	)
	(gr_poly
		(pts
			(xy 295.9862 -95.4024)
			(arc
				(start 295.9862 -83.920584)
				(mid 295.957061 -83.923631)
				(end 295.92778 -83.924648)
			)
			(arc
				(start 295.92778 -83.924648)
				(mid 295.505632 -83.5025)
				(end 295.92778 -83.080352)
			)
			(arc
				(start 295.92778 -83.080352)
				(mid 295.957061 -83.081369)
				(end 295.9862 -83.084416)
			)
			(xy 295.9862 -61.7728) (xy 295.6306 -61.4172) (xy 279.68448 -61.4172) (xy 278.99868 -62.103) (xy 278.99868 -95.156782)
			(xy 279.726898 -95.885) (xy 295.5036 -95.885)
		)
		(stroke
			(width 0)
			(type solid)
		)
		(fill yes)
		(layer "In2.Cu")
		(net "P52V_HS1_DRAIN_2")
	)
	(gr_poly
		(pts
			(xy 319.40373 -121.692416) (xy 319.413798 -121.691988) (xy 319.432396 -121.684268) (xy 319.439798 -121.67743)
			(xy 320.413888 -120.703086) (xy 320.420733 -120.695687) (xy 320.428465 -120.677089) (xy 320.428874 -120.667018)
			(xy 320.428874 -77.097636) (xy 320.428439 -77.087572) (xy 320.420705 -77.068986) (xy 320.413888 -77.061568)
			(xy 319.692528 -76.340208) (xy 319.685126 -76.333372) (xy 319.666528 -76.325663) (xy 319.65646 -76.325222)
			(xy 308.461664 -76.325222) (xy 308.451596 -76.324793) (xy 308.432999 -76.317072) (xy 308.425596 -76.310236)
			(xy 306.171346 -74.055986) (xy 306.163949 -74.049139) (xy 306.145349 -74.041411) (xy 306.135278 -74.041)
			(xy 304.313082 -74.041) (xy 304.303013 -74.041427) (xy 304.284414 -74.049146) (xy 304.277014 -74.055986)
			(xy 303.860708 -74.472292) (xy 303.853859 -74.47969) (xy 303.846121 -74.498288) (xy 303.845722 -74.50836)
			(xy 303.845722 -101.454966) (xy 306.278033 -101.454966) (xy 306.28204 -101.252216) (xy 306.294053 -101.049782)
			(xy 306.314054 -100.847981) (xy 306.342013 -100.647127) (xy 306.377884 -100.447535) (xy 306.421613 -100.249516)
			(xy 306.473131 -100.053379) (xy 306.532357 -99.859431) (xy 306.599199 -99.667973) (xy 306.673553 -99.479306)
			(xy 306.755302 -99.293724) (xy 306.84432 -99.111516) (xy 306.940466 -98.932967) (xy 307.043591 -98.758356)
			(xy 307.153534 -98.587956) (xy 307.270123 -98.422032) (xy 307.393176 -98.260843) (xy 307.522501 -98.104642)
			(xy 307.657896 -97.953672) (xy 307.799149 -97.808168) (xy 307.946041 -97.668359) (xy 308.098341 -97.534462)
			(xy 308.255812 -97.406687) (xy 308.418209 -97.285232) (xy 308.585276 -97.170288) (xy 308.756755 -97.062034)
			(xy 308.932376 -96.960639) (xy 309.111866 -96.866261) (xy 309.294944 -96.779049) (xy 309.481325 -96.699137)
			(xy 309.670718 -96.62665) (xy 309.862826 -96.561703) (xy 310.05735 -96.504395) (xy 310.253986 -96.454818)
			(xy 310.452428 -96.413047) (xy 310.652365 -96.379149) (xy 310.853484 -96.353177) (xy 311.055473 -96.33517)
			(xy 311.258016 -96.325157) (xy 311.460796 -96.323153) (xy 311.663497 -96.329163) (xy 311.865802 -96.343175)
			(xy 312.067396 -96.36517) (xy 312.267963 -96.395111) (xy 312.467191 -96.432952) (xy 312.664769 -96.478635)
			(xy 312.860387 -96.532088) (xy 313.053741 -96.593227) (xy 313.244529 -96.661958) (xy 313.432452 -96.738172)
			(xy 313.617218 -96.821751) (xy 313.798537 -96.912564) (xy 313.976128 -97.010469) (xy 314.149711 -97.115314)
			(xy 314.319017 -97.226935) (xy 314.483782 -97.345157) (xy 314.643747 -97.469797) (xy 314.798663 -97.600658)
			(xy 314.948288 -97.737538) (xy 315.092388 -97.880222) (xy 315.23074 -98.028488) (xy 315.363125 -98.182104)
			(xy 315.489339 -98.340829) (xy 315.609183 -98.504418) (xy 315.722471 -98.672613) (xy 315.829026 -98.845152)
			(xy 315.928681 -99.021767) (xy 316.021281 -99.20218) (xy 316.106681 -99.386111) (xy 316.184748 -99.573272)
			(xy 316.25536 -99.763372) (xy 316.318406 -99.956112) (xy 316.373789 -100.151193) (xy 316.421421 -100.34831)
			(xy 316.461229 -100.547154) (xy 316.493151 -100.747416) (xy 316.517135 -100.948782) (xy 316.533146 -101.150939)
			(xy 316.541157 -101.353571) (xy 316.541658 -101.454966) (xy 316.541157 -101.556361) (xy 316.533146 -101.758993)
			(xy 316.517135 -101.96115) (xy 316.493151 -102.162516) (xy 316.461229 -102.362778) (xy 316.421421 -102.561622)
			(xy 316.373789 -102.758739) (xy 316.318406 -102.95382) (xy 316.25536 -103.14656) (xy 316.184748 -103.33666)
			(xy 316.106681 -103.523821) (xy 316.021281 -103.707752) (xy 315.928681 -103.888165) (xy 315.829026 -104.06478)
			(xy 315.722471 -104.237319) (xy 315.609183 -104.405514) (xy 315.489339 -104.569103) (xy 315.363125 -104.727828)
			(xy 315.23074 -104.881444) (xy 315.092388 -105.02971) (xy 314.948288 -105.172394) (xy 314.798663 -105.309274)
			(xy 314.643747 -105.440135) (xy 314.483782 -105.564775) (xy 314.319017 -105.682997) (xy 314.149711 -105.794618)
			(xy 313.976128 -105.899463) (xy 313.798537 -105.997368) (xy 313.617218 -106.088181) (xy 313.432452 -106.17176)
			(xy 313.244529 -106.247974) (xy 313.053741 -106.316705) (xy 312.860387 -106.377844) (xy 312.664769 -106.431297)
			(xy 312.467191 -106.47698) (xy 312.267963 -106.514821) (xy 312.067396 -106.544762) (xy 311.865802 -106.566757)
			(xy 311.663497 -106.580769) (xy 311.460796 -106.586779) (xy 311.258016 -106.584775) (xy 311.055473 -106.574762)
			(xy 310.853484 -106.556755) (xy 310.652365 -106.530783) (xy 310.452428 -106.496885) (xy 310.253986 -106.455114)
			(xy 310.05735 -106.405537) (xy 309.862826 -106.348229) (xy 309.670718 -106.283282) (xy 309.481325 -106.210795)
			(xy 309.294944 -106.130883) (xy 309.111866 -106.043671) (xy 308.932376 -105.949293) (xy 308.756755 -105.847898)
			(xy 308.585276 -105.739644) (xy 308.418209 -105.6247) (xy 308.255812 -105.503245) (xy 308.098341 -105.37547)
			(xy 307.946041 -105.241573) (xy 307.799149 -105.101764) (xy 307.657896 -104.95626) (xy 307.522501 -104.80529)
			(xy 307.393176 -104.649089) (xy 307.270123 -104.4879) (xy 307.153534 -104.321976) (xy 307.043591 -104.151576)
			(xy 306.940466 -103.976965) (xy 306.84432 -103.798416) (xy 306.755302 -103.616208) (xy 306.673553 -103.430626)
			(xy 306.599199 -103.241959) (xy 306.532357 -103.050501) (xy 306.473131 -102.856553) (xy 306.421613 -102.660416)
			(xy 306.377884 -102.462397) (xy 306.342013 -102.262805) (xy 306.314054 -102.061951) (xy 306.294053 -101.86015)
			(xy 306.28204 -101.657716) (xy 306.278033 -101.454966) (xy 303.845722 -101.454966) (xy 303.845722 -120.964198)
			(xy 303.846145 -120.974268) (xy 303.853862 -120.992871) (xy 303.860708 -121.000266) (xy 304.537872 -121.67743)
			(xy 304.545271 -121.684273) (xy 304.56387 -121.691992) (xy 304.57394 -121.692416)
		)
		(stroke
			(width 0)
			(type solid)
		)
		(fill yes)
		(layer "In2.Cu")
		(net "P52V_1")
	)
	(gr_poly
		(pts
			(xy 297.666918 -47.371) (xy 297.676987 -47.370573) (xy 297.695586 -47.362854) (xy 297.702986 -47.356014)
			(xy 297.927014 -47.131986) (xy 297.933868 -47.124591) (xy 297.94161 -47.105992) (xy 297.942 -47.095918)
			(xy 297.942 -45.233082) (xy 297.941573 -45.223013) (xy 297.933854 -45.204414) (xy 297.927014 -45.197014)
			(xy 292.241986 -39.511986) (xy 292.235132 -39.504591) (xy 292.22739 -39.485992) (xy 292.227 -39.475918)
			(xy 292.227 -38.51021) (xy 292.226492 -38.481) (xy 292.227 -38.45179) (xy 292.227 -37.867082) (xy 292.226573 -37.857013)
			(xy 292.218854 -37.838414) (xy 292.212014 -37.831014) (xy 289.003486 -34.622486) (xy 288.996632 -34.615091)
			(xy 288.98889 -34.596492) (xy 288.9885 -34.586418) (xy 288.9885 -33.739582) (xy 288.988073 -33.729513)
			(xy 288.980354 -33.710914) (xy 288.973514 -33.703514) (xy 287.161986 -31.891986) (xy 287.154591 -31.885132)
			(xy 287.135992 -31.87739) (xy 287.125918 -31.877) (xy 286.279082 -31.877) (xy 286.269013 -31.876573)
			(xy 286.250414 -31.868854) (xy 286.243014 -31.862014) (xy 285.424372 -31.043372) (xy 285.394908 -31.037276)
			(xy 285.380684 -31.04261) (xy 285.358513 -31.050899) (xy 285.312635 -31.062548) (xy 285.265667 -31.068418)
			(xy 285.242 -31.068772) (xy 285.212363 -31.068189) (xy 285.153807 -31.058984) (xy 285.097376 -31.040842)
			(xy 285.044427 -31.014198) (xy 285.020004 -30.997398) (xy 285.013361 -30.993043) (xy 284.998225 -30.988257)
			(xy 284.990286 -30.988) (xy 282.824682 -30.988) (xy 282.814613 -30.988427) (xy 282.796014 -30.996146)
			(xy 282.788614 -31.002986) (xy 281.040586 -32.751014) (xy 281.033191 -32.757868) (xy 281.014592 -32.76561)
			(xy 281.004518 -32.766) (xy 274.569682 -32.766) (xy 274.559613 -32.766427) (xy 274.541014 -32.774146)
			(xy 274.533614 -32.780986) (xy 274.31746 -32.99714) (xy 274.310613 -33.004538) (xy 274.302884 -33.023137)
			(xy 274.302474 -33.033208) (xy 274.302474 -33.792668) (xy 274.302977 -33.80272) (xy 274.310696 -33.821283)
			(xy 274.31746 -33.828736) (xy 274.940014 -34.45129) (xy 274.947413 -34.458135) (xy 274.966011 -34.465866)
			(xy 274.976082 -34.466276) (xy 278.694642 -34.466276) (xy 278.704708 -34.465845) (xy 278.723299 -34.458117)
			(xy 278.73071 -34.45129) (xy 279.385014 -33.796986) (xy 279.392409 -33.790132) (xy 279.411008 -33.78239)
			(xy 279.421082 -33.782) (xy 281.52979 -33.782) (xy 281.559 -33.781492) (xy 281.58821 -33.782) (xy 282.553918 -33.782)
			(xy 282.563987 -33.781573) (xy 282.582586 -33.773854) (xy 282.589986 -33.767014) (xy 282.687014 -33.669986)
			(xy 282.694409 -33.663132) (xy 282.713008 -33.65539) (xy 282.723082 -33.655) (xy 285.90875 -33.655)
			(xy 285.912052 -33.654492) (xy 285.939687 -33.651258) (xy 285.995227 -33.647827) (xy 286.02305 -33.647634)
			(xy 286.050873 -33.647826) (xy 286.106413 -33.651259) (xy 286.134048 -33.654492) (xy 286.13735 -33.655)
			(xy 286.885126 -33.655) (xy 286.889698 -33.654238) (xy 286.929846 -33.64724) (xy 287.011 -33.639731)
			(xy 287.05175 -33.639252) (xy 287.0925 -33.639732) (xy 287.173655 -33.647236) (xy 287.213802 -33.654238)
			(xy 287.218374 -33.655) (xy 287.506918 -33.655) (xy 287.516987 -33.655427) (xy 287.535586 -33.663146)
			(xy 287.542986 -33.669986) (xy 287.957514 -34.084514) (xy 287.964368 -34.091909) (xy 287.97211 -34.110508)
			(xy 287.9725 -34.120582) (xy 287.9725 -37.507418) (xy 287.972927 -37.517487) (xy 287.980646 -37.536086)
			(xy 287.987486 -37.543486) (xy 290.561014 -40.117014) (xy 290.567868 -40.124409) (xy 290.57561 -40.143008)
			(xy 290.576 -40.153082) (xy 290.576 -42.092626) (xy 292.424356 -42.092626) (xy 292.428427 -42.037004)
			(xy 292.440553 -41.982567) (xy 292.460476 -41.930476) (xy 292.487772 -41.881841) (xy 292.521858 -41.837698)
			(xy 292.562007 -41.798989) (xy 292.607365 -41.766538) (xy 292.656965 -41.741037) (xy 292.709749 -41.72303)
			(xy 292.764592 -41.7129) (xy 292.820326 -41.710863) (xy 292.875763 -41.716963) (xy 292.92972 -41.731069)
			(xy 292.981049 -41.752881) (xy 293.028655 -41.781935) (xy 293.071523 -41.81761) (xy 293.10874 -41.859147)
			(xy 293.139513 -41.90566) (xy 293.163185 -41.956157) (xy 293.179253 -42.009564) (xy 293.187373 -42.06474)
			(xy 293.187882 -42.092626) (xy 293.187373 -42.120512) (xy 293.179253 -42.175688) (xy 293.163185 -42.229095)
			(xy 293.139513 -42.279592) (xy 293.10874 -42.326105) (xy 293.071523 -42.367642) (xy 293.028655 -42.403317)
			(xy 292.981049 -42.432371) (xy 292.92972 -42.454183) (xy 292.875763 -42.468289) (xy 292.820326 -42.474389)
			(xy 292.764592 -42.472352) (xy 292.709749 -42.462222) (xy 292.656965 -42.444215) (xy 292.607365 -42.418714)
			(xy 292.562007 -42.386263) (xy 292.521858 -42.347554) (xy 292.487772 -42.303411) (xy 292.460476 -42.254776)
			(xy 292.440553 -42.202685) (xy 292.428427 -42.148248) (xy 292.424356 -42.092626) (xy 290.576 -42.092626)
			(xy 290.576 -43.870118) (xy 290.576427 -43.880187) (xy 290.584146 -43.898786) (xy 290.590986 -43.906186)
			(xy 291.411449 -44.726649) (xy 294.309806 -44.726649) (xy 294.309806 -44.672151) (xy 294.317562 -44.618207)
			(xy 294.332916 -44.565916) (xy 294.355556 -44.516343) (xy 294.38502 -44.470496) (xy 294.420709 -44.429309)
			(xy 294.461896 -44.39362) (xy 294.507743 -44.364156) (xy 294.557316 -44.341516) (xy 294.609607 -44.326162)
			(xy 294.663551 -44.318406) (xy 294.6908 -44.31792) (xy 294.717827 -44.318409) (xy 294.771338 -44.326044)
			(xy 294.823239 -44.341146) (xy 294.872492 -44.363414) (xy 294.918114 -44.392404) (xy 294.938958 -44.409614)
			(xy 294.94607 -44.41571) (xy 294.963088 -44.421806) (xy 295.048432 -44.421044) (xy 295.06545 -44.414694)
			(xy 295.072308 -44.408344) (xy 295.093373 -44.3903) (xy 295.139754 -44.359884) (xy 295.190044 -44.33649)
			(xy 295.243187 -44.320611) (xy 295.298068 -44.31258) (xy 295.3258 -44.312078) (xy 295.35305 -44.312592)
			(xy 295.406996 -44.320348) (xy 295.459289 -44.335703) (xy 295.508864 -44.358343) (xy 295.554713 -44.387808)
			(xy 295.595901 -44.423499) (xy 295.631592 -44.464687) (xy 295.661057 -44.510536) (xy 295.683697 -44.560111)
			(xy 295.699052 -44.612404) (xy 295.706808 -44.66635) (xy 295.706808 -44.72085) (xy 295.699052 -44.774796)
			(xy 295.683697 -44.827089) (xy 295.661057 -44.876664) (xy 295.631592 -44.922513) (xy 295.595901 -44.963701)
			(xy 295.554713 -44.999392) (xy 295.508864 -45.028857) (xy 295.459289 -45.051497) (xy 295.406996 -45.066852)
			(xy 295.35305 -45.074608) (xy 295.3258 -45.075094) (xy 295.298774 -45.074601) (xy 295.245262 -45.066967)
			(xy 295.193362 -45.051866) (xy 295.144108 -45.029598) (xy 295.098486 -45.00061) (xy 295.077642 -44.9834)
			(xy 295.07053 -44.977304) (xy 295.053512 -44.971208) (xy 294.968168 -44.97197) (xy 294.95115 -44.97832)
			(xy 294.944292 -44.98467) (xy 294.923229 -45.002716) (xy 294.876847 -45.033132) (xy 294.826557 -45.056524)
			(xy 294.773413 -45.072403) (xy 294.718532 -45.080434) (xy 294.6908 -45.080936) (xy 294.663551 -45.080394)
			(xy 294.609607 -45.072638) (xy 294.557316 -45.057284) (xy 294.507743 -45.034644) (xy 294.461896 -45.00518)
			(xy 294.420709 -44.969491) (xy 294.38502 -44.928304) (xy 294.355556 -44.882457) (xy 294.332916 -44.832884)
			(xy 294.317562 -44.780593) (xy 294.309806 -44.726649) (xy 291.411449 -44.726649) (xy 294.040814 -47.356014)
			(xy 294.048209 -47.362868) (xy 294.066808 -47.37061) (xy 294.076882 -47.371)
		)
		(stroke
			(width 0)
			(type solid)
		)
		(fill yes)
		(layer "In2.Cu")
		(net "P52V_1_R")
	)
	(gr_poly
		(pts
			(xy 31.63443 -116.228114) (xy 31.644498 -116.227686) (xy 31.663096 -116.219965) (xy 31.670498 -116.213128)
			(xy 34.136838 -116.213128) (xy 34.146906 -116.212699) (xy 34.165503 -116.204978) (xy 34.172906 -116.198142)
			(xy 34.57956 -115.791488) (xy 34.586409 -115.784091) (xy 34.594145 -115.765492) (xy 34.594546 -115.75542)
			(xy 34.594546 -80.934052) (xy 34.594113 -80.923987) (xy 34.58638 -80.9054) (xy 34.57956 -80.897984)
			(xy 21.616162 -67.934586) (xy 21.608766 -67.927736) (xy 21.590166 -67.920002) (xy 21.580094 -67.9196)
			(xy 8.809482 -67.9196) (xy 8.799413 -67.920027) (xy 8.780814 -67.927746) (xy 8.773414 -67.934586)
			(xy 8.473186 -68.234814) (xy 8.466332 -68.242209) (xy 8.45859 -68.260808) (xy 8.4582 -68.270882)
			(xy 8.4582 -70.939914) (xy 8.859012 -70.939914) (xy 8.859529 -70.895741) (xy 8.867385 -70.807746)
			(xy 8.883045 -70.7208) (xy 8.906383 -70.635593) (xy 8.937216 -70.552803) (xy 8.975297 -70.473086)
			(xy 9.020325 -70.397077) (xy 9.071942 -70.325379) (xy 9.129737 -70.258561) (xy 9.193252 -70.197155)
			(xy 9.227312 -70.169024) (xy 9.236202 -70.161658) (xy 9.246108 -70.141084) (xy 9.246108 -70.038722)
			(xy 9.236202 -70.018148) (xy 9.227312 -70.010782) (xy 9.193255 -69.982647) (xy 9.129742 -69.921238)
			(xy 9.071948 -69.854419) (xy 9.020332 -69.782721) (xy 8.975302 -69.706713) (xy 8.937217 -69.626998)
			(xy 8.90638 -69.544209) (xy 8.883034 -69.459004) (xy 8.867365 -69.372059) (xy 8.859498 -69.284065)
			(xy 8.859012 -69.239892) (xy 8.859511 -69.195404) (xy 8.867487 -69.106785) (xy 8.883374 -69.019239)
			(xy 8.907045 -68.933468) (xy 8.938309 -68.850165) (xy 8.976915 -68.77) (xy 9.022551 -68.693618) (xy 9.07485 -68.621635)
			(xy 9.133391 -68.554629) (xy 9.197703 -68.493141) (xy 9.267268 -68.437665) (xy 9.341525 -68.388648)
			(xy 9.419878 -68.346485) (xy 9.501694 -68.311514) (xy 9.586316 -68.284019) (xy 9.673062 -68.26422)
			(xy 9.761233 -68.252276) (xy 9.85012 -68.248285) (xy 9.939007 -68.252276) (xy 10.027178 -68.26422)
			(xy 10.113924 -68.284019) (xy 10.198546 -68.311514) (xy 10.280362 -68.346485) (xy 10.358715 -68.388648)
			(xy 10.432972 -68.437665) (xy 10.502537 -68.493141) (xy 10.566849 -68.554629) (xy 10.62539 -68.621635)
			(xy 10.677689 -68.693618) (xy 10.723325 -68.77) (xy 10.761931 -68.850165) (xy 10.793195 -68.933468)
			(xy 10.816866 -69.019239) (xy 10.832753 -69.106785) (xy 10.840729 -69.195404) (xy 10.841228 -69.239892)
			(xy 10.840737 -69.284065) (xy 10.83288 -69.372062) (xy 10.817219 -69.45901) (xy 10.793879 -69.544217)
			(xy 10.763044 -69.627009) (xy 10.724959 -69.706725) (xy 10.679928 -69.782734) (xy 10.628308 -69.854431)
			(xy 10.570509 -69.921248) (xy 10.50699 -69.982652) (xy 10.472928 -70.010782) (xy 10.464038 -70.018148)
			(xy 10.454132 -70.038722) (xy 10.454132 -70.141084) (xy 10.464038 -70.161658) (xy 10.472928 -70.169024)
			(xy 10.506988 -70.197155) (xy 10.570501 -70.258565) (xy 10.628294 -70.325384) (xy 10.679911 -70.397083)
			(xy 10.72494 -70.473092) (xy 10.763024 -70.552807) (xy 10.793862 -70.635596) (xy 10.817207 -70.720801)
			(xy 10.832875 -70.807746) (xy 10.840742 -70.895741) (xy 10.841228 -70.939914) (xy 11.399012 -70.939914)
			(xy 11.399529 -70.895741) (xy 11.407385 -70.807746) (xy 11.423045 -70.7208) (xy 11.446383 -70.635593)
			(xy 11.477216 -70.552803) (xy 11.515297 -70.473086) (xy 11.560325 -70.397077) (xy 11.611942 -70.325379)
			(xy 11.669737 -70.258561) (xy 11.733252 -70.197155) (xy 11.767312 -70.169024) (xy 11.776202 -70.161658)
			(xy 11.786108 -70.141084) (xy 11.786108 -70.038722) (xy 11.776202 -70.018148) (xy 11.767312 -70.010782)
			(xy 11.733255 -69.982647) (xy 11.669742 -69.921238) (xy 11.611948 -69.854419) (xy 11.560332 -69.782721)
			(xy 11.515302 -69.706713) (xy 11.477217 -69.626998) (xy 11.44638 -69.544209) (xy 11.423034 -69.459004)
			(xy 11.407365 -69.372059) (xy 11.399498 -69.284065) (xy 11.399012 -69.239892) (xy 11.399511 -69.195404)
			(xy 11.407487 -69.106785) (xy 11.423374 -69.019239) (xy 11.447045 -68.933468) (xy 11.478309 -68.850165)
			(xy 11.516915 -68.77) (xy 11.562551 -68.693618) (xy 11.61485 -68.621635) (xy 11.673391 -68.554629)
			(xy 11.737703 -68.493141) (xy 11.807268 -68.437665) (xy 11.881525 -68.388648) (xy 11.959878 -68.346485)
			(xy 12.041694 -68.311514) (xy 12.126316 -68.284019) (xy 12.213062 -68.26422) (xy 12.301233 -68.252276)
			(xy 12.39012 -68.248285) (xy 12.479007 -68.252276) (xy 12.567178 -68.26422) (xy 12.653924 -68.284019)
			(xy 12.738546 -68.311514) (xy 12.820362 -68.346485) (xy 12.898715 -68.388648) (xy 12.972972 -68.437665)
			(xy 13.042537 -68.493141) (xy 13.106849 -68.554629) (xy 13.16539 -68.621635) (xy 13.217689 -68.693618)
			(xy 13.263325 -68.77) (xy 13.301931 -68.850165) (xy 13.333195 -68.933468) (xy 13.356866 -69.019239)
			(xy 13.372753 -69.106785) (xy 13.380729 -69.195404) (xy 13.381228 -69.239892) (xy 13.380737 -69.284065)
			(xy 13.37288 -69.372062) (xy 13.357219 -69.45901) (xy 13.333879 -69.544217) (xy 13.303044 -69.627009)
			(xy 13.264959 -69.706725) (xy 13.219928 -69.782734) (xy 13.168308 -69.854431) (xy 13.110509 -69.921248)
			(xy 13.04699 -69.982652) (xy 13.012928 -70.010782) (xy 13.004038 -70.018148) (xy 12.994132 -70.038722)
			(xy 12.994132 -70.141084) (xy 13.004038 -70.161658) (xy 13.012928 -70.169024) (xy 13.046988 -70.197155)
			(xy 13.110501 -70.258565) (xy 13.168294 -70.325384) (xy 13.219911 -70.397083) (xy 13.26494 -70.473092)
			(xy 13.303024 -70.552807) (xy 13.333862 -70.635596) (xy 13.357207 -70.720801) (xy 13.372875 -70.807746)
			(xy 13.380742 -70.895741) (xy 13.381228 -70.939914) (xy 13.380729 -70.984402) (xy 13.372753 -71.073021)
			(xy 13.356866 -71.160567) (xy 13.333195 -71.246338) (xy 13.301931 -71.329641) (xy 13.263325 -71.409806)
			(xy 13.217689 -71.486188) (xy 13.16539 -71.558171) (xy 13.106849 -71.625177) (xy 13.042537 -71.686665)
			(xy 12.972972 -71.742141) (xy 12.898715 -71.791158) (xy 12.820362 -71.833321) (xy 12.738546 -71.868292)
			(xy 12.653924 -71.895787) (xy 12.567178 -71.915586) (xy 12.479007 -71.92753) (xy 12.39012 -71.931522)
			(xy 12.301233 -71.92753) (xy 12.213062 -71.915586) (xy 12.126316 -71.895787) (xy 12.041694 -71.868292)
			(xy 11.959878 -71.833321) (xy 11.881525 -71.791158) (xy 11.807268 -71.742141) (xy 11.737703 -71.686665)
			(xy 11.673391 -71.625177) (xy 11.61485 -71.558171) (xy 11.562551 -71.486188) (xy 11.516915 -71.409806)
			(xy 11.478309 -71.329641) (xy 11.447045 -71.246338) (xy 11.423374 -71.160567) (xy 11.407487 -71.073021)
			(xy 11.399511 -70.984402) (xy 11.399012 -70.939914) (xy 10.841228 -70.939914) (xy 10.840729 -70.984402)
			(xy 10.832753 -71.073021) (xy 10.816866 -71.160567) (xy 10.793195 -71.246338) (xy 10.761931 -71.329641)
			(xy 10.723325 -71.409806) (xy 10.677689 -71.486188) (xy 10.62539 -71.558171) (xy 10.566849 -71.625177)
			(xy 10.502537 -71.686665) (xy 10.432972 -71.742141) (xy 10.358715 -71.791158) (xy 10.280362 -71.833321)
			(xy 10.198546 -71.868292) (xy 10.113924 -71.895787) (xy 10.027178 -71.915586) (xy 9.939007 -71.92753)
			(xy 9.85012 -71.931522) (xy 9.761233 -71.92753) (xy 9.673062 -71.915586) (xy 9.586316 -71.895787)
			(xy 9.501694 -71.868292) (xy 9.419878 -71.833321) (xy 9.341525 -71.791158) (xy 9.267268 -71.742141)
			(xy 9.197703 -71.686665) (xy 9.133391 -71.625177) (xy 9.07485 -71.558171) (xy 9.022551 -71.486188)
			(xy 8.976915 -71.409806) (xy 8.938309 -71.329641) (xy 8.907045 -71.246338) (xy 8.883374 -71.160567)
			(xy 8.867487 -71.073021) (xy 8.859511 -70.984402) (xy 8.859012 -70.939914) (xy 8.4582 -70.939914)
			(xy 8.4582 -76.019914) (xy 8.859012 -76.019914) (xy 8.859529 -75.975741) (xy 8.867385 -75.887746)
			(xy 8.883045 -75.8008) (xy 8.906383 -75.715593) (xy 8.937216 -75.632803) (xy 8.975297 -75.553086)
			(xy 9.020325 -75.477077) (xy 9.071942 -75.405379) (xy 9.129737 -75.338561) (xy 9.193252 -75.277155)
			(xy 9.227312 -75.249024) (xy 9.236202 -75.241658) (xy 9.246108 -75.221084) (xy 9.246108 -75.118722)
			(xy 9.236202 -75.098148) (xy 9.227312 -75.090782) (xy 9.193255 -75.062647) (xy 9.129742 -75.001238)
			(xy 9.071948 -74.934419) (xy 9.020332 -74.862721) (xy 8.975302 -74.786713) (xy 8.937217 -74.706998)
			(xy 8.90638 -74.624209) (xy 8.883034 -74.539004) (xy 8.867365 -74.452059) (xy 8.859498 -74.364065)
			(xy 8.859012 -74.319892) (xy 8.859511 -74.275404) (xy 8.867487 -74.186785) (xy 8.883374 -74.099239)
			(xy 8.907045 -74.013468) (xy 8.938309 -73.930165) (xy 8.976915 -73.85) (xy 9.022551 -73.773618) (xy 9.07485 -73.701635)
			(xy 9.133391 -73.634629) (xy 9.197703 -73.573141) (xy 9.267268 -73.517665) (xy 9.341525 -73.468648)
			(xy 9.419878 -73.426485) (xy 9.501694 -73.391514) (xy 9.586316 -73.364019) (xy 9.673062 -73.34422)
			(xy 9.761233 -73.332276) (xy 9.85012 -73.328285) (xy 9.939007 -73.332276) (xy 10.027178 -73.34422)
			(xy 10.113924 -73.364019) (xy 10.198546 -73.391514) (xy 10.280362 -73.426485) (xy 10.358715 -73.468648)
			(xy 10.432972 -73.517665) (xy 10.502537 -73.573141) (xy 10.566849 -73.634629) (xy 10.62539 -73.701635)
			(xy 10.677689 -73.773618) (xy 10.723325 -73.85) (xy 10.761931 -73.930165) (xy 10.793195 -74.013468)
			(xy 10.816866 -74.099239) (xy 10.832753 -74.186785) (xy 10.840729 -74.275404) (xy 10.841228 -74.319892)
			(xy 10.840737 -74.364065) (xy 10.83288 -74.452062) (xy 10.817219 -74.53901) (xy 10.793879 -74.624217)
			(xy 10.763044 -74.707009) (xy 10.724959 -74.786725) (xy 10.679928 -74.862734) (xy 10.628308 -74.934431)
			(xy 10.570509 -75.001248) (xy 10.50699 -75.062652) (xy 10.472928 -75.090782) (xy 10.464038 -75.098148)
			(xy 10.454132 -75.118722) (xy 10.454132 -75.221084) (xy 10.464038 -75.241658) (xy 10.472928 -75.249024)
			(xy 10.506988 -75.277155) (xy 10.570501 -75.338565) (xy 10.628294 -75.405384) (xy 10.679911 -75.477083)
			(xy 10.72494 -75.553092) (xy 10.763024 -75.632807) (xy 10.793862 -75.715596) (xy 10.817207 -75.800801)
			(xy 10.832875 -75.887746) (xy 10.840742 -75.975741) (xy 10.841228 -76.019914) (xy 11.399012 -76.019914)
			(xy 11.399529 -75.975741) (xy 11.407385 -75.887746) (xy 11.423045 -75.8008) (xy 11.446383 -75.715593)
			(xy 11.477216 -75.632803) (xy 11.515297 -75.553086) (xy 11.560325 -75.477077) (xy 11.611942 -75.405379)
			(xy 11.669737 -75.338561) (xy 11.733252 -75.277155) (xy 11.767312 -75.249024) (xy 11.776202 -75.241658)
			(xy 11.786108 -75.221084) (xy 11.786108 -75.118722) (xy 11.776202 -75.098148) (xy 11.767312 -75.090782)
			(xy 11.733255 -75.062647) (xy 11.669742 -75.001238) (xy 11.611948 -74.934419) (xy 11.560332 -74.862721)
			(xy 11.515302 -74.786713) (xy 11.477217 -74.706998) (xy 11.44638 -74.624209) (xy 11.423034 -74.539004)
			(xy 11.407365 -74.452059) (xy 11.399498 -74.364065) (xy 11.399012 -74.319892) (xy 11.399511 -74.275404)
			(xy 11.407487 -74.186785) (xy 11.423374 -74.099239) (xy 11.447045 -74.013468) (xy 11.478309 -73.930165)
			(xy 11.516915 -73.85) (xy 11.562551 -73.773618) (xy 11.61485 -73.701635) (xy 11.673391 -73.634629)
			(xy 11.737703 -73.573141) (xy 11.807268 -73.517665) (xy 11.881525 -73.468648) (xy 11.959878 -73.426485)
			(xy 12.041694 -73.391514) (xy 12.126316 -73.364019) (xy 12.213062 -73.34422) (xy 12.301233 -73.332276)
			(xy 12.39012 -73.328285) (xy 12.479007 -73.332276) (xy 12.567178 -73.34422) (xy 12.653924 -73.364019)
			(xy 12.738546 -73.391514) (xy 12.820362 -73.426485) (xy 12.898715 -73.468648) (xy 12.972972 -73.517665)
			(xy 13.042537 -73.573141) (xy 13.106849 -73.634629) (xy 13.16539 -73.701635) (xy 13.217689 -73.773618)
			(xy 13.263325 -73.85) (xy 13.301931 -73.930165) (xy 13.333195 -74.013468) (xy 13.356866 -74.099239)
			(xy 13.372753 -74.186785) (xy 13.380729 -74.275404) (xy 13.381228 -74.319892) (xy 13.380737 -74.364065)
			(xy 13.37288 -74.452062) (xy 13.357219 -74.53901) (xy 13.333879 -74.624217) (xy 13.303044 -74.707009)
			(xy 13.264959 -74.786725) (xy 13.219928 -74.862734) (xy 13.168308 -74.934431) (xy 13.110509 -75.001248)
			(xy 13.04699 -75.062652) (xy 13.012928 -75.090782) (xy 13.004038 -75.098148) (xy 12.994132 -75.118722)
			(xy 12.994132 -75.221084) (xy 13.004038 -75.241658) (xy 13.012928 -75.249024) (xy 13.046988 -75.277155)
			(xy 13.110501 -75.338565) (xy 13.168294 -75.405384) (xy 13.219911 -75.477083) (xy 13.26494 -75.553092)
			(xy 13.303024 -75.632807) (xy 13.333862 -75.715596) (xy 13.357207 -75.800801) (xy 13.372875 -75.887746)
			(xy 13.380742 -75.975741) (xy 13.381228 -76.019914) (xy 13.380729 -76.064402) (xy 13.372753 -76.153021)
			(xy 13.356866 -76.240567) (xy 13.333195 -76.326338) (xy 13.301931 -76.409641) (xy 13.263325 -76.489806)
			(xy 13.217689 -76.566188) (xy 13.16539 -76.638171) (xy 13.106849 -76.705177) (xy 13.042537 -76.766665)
			(xy 12.972972 -76.822141) (xy 12.898715 -76.871158) (xy 12.820362 -76.913321) (xy 12.738546 -76.948292)
			(xy 12.653924 -76.975787) (xy 12.567178 -76.995586) (xy 12.479007 -77.00753) (xy 12.39012 -77.011522)
			(xy 12.301233 -77.00753) (xy 12.213062 -76.995586) (xy 12.126316 -76.975787) (xy 12.041694 -76.948292)
			(xy 11.959878 -76.913321) (xy 11.881525 -76.871158) (xy 11.807268 -76.822141) (xy 11.737703 -76.766665)
			(xy 11.673391 -76.705177) (xy 11.61485 -76.638171) (xy 11.562551 -76.566188) (xy 11.516915 -76.489806)
			(xy 11.478309 -76.409641) (xy 11.447045 -76.326338) (xy 11.423374 -76.240567) (xy 11.407487 -76.153021)
			(xy 11.399511 -76.064402) (xy 11.399012 -76.019914) (xy 10.841228 -76.019914) (xy 10.840729 -76.064402)
			(xy 10.832753 -76.153021) (xy 10.816866 -76.240567) (xy 10.793195 -76.326338) (xy 10.761931 -76.409641)
			(xy 10.723325 -76.489806) (xy 10.677689 -76.566188) (xy 10.62539 -76.638171) (xy 10.566849 -76.705177)
			(xy 10.502537 -76.766665) (xy 10.432972 -76.822141) (xy 10.358715 -76.871158) (xy 10.280362 -76.913321)
			(xy 10.198546 -76.948292) (xy 10.113924 -76.975787) (xy 10.027178 -76.995586) (xy 9.939007 -77.00753)
			(xy 9.85012 -77.011522) (xy 9.761233 -77.00753) (xy 9.673062 -76.995586) (xy 9.586316 -76.975787)
			(xy 9.501694 -76.948292) (xy 9.419878 -76.913321) (xy 9.341525 -76.871158) (xy 9.267268 -76.822141)
			(xy 9.197703 -76.766665) (xy 9.133391 -76.705177) (xy 9.07485 -76.638171) (xy 9.022551 -76.566188)
			(xy 8.976915 -76.489806) (xy 8.938309 -76.409641) (xy 8.907045 -76.326338) (xy 8.883374 -76.240567)
			(xy 8.867487 -76.153021) (xy 8.859511 -76.064402) (xy 8.859012 -76.019914) (xy 8.4582 -76.019914)
			(xy 8.4582 -76.763118) (xy 8.458627 -76.773187) (xy 8.466346 -76.791786) (xy 8.473186 -76.799186)
			(xy 9.154414 -77.480414) (xy 9.161809 -77.487268) (xy 9.180408 -77.49501) (xy 9.190482 -77.4954)
			(xy 11.67511 -77.4954) (xy 11.685179 -77.495825) (xy 11.703781 -77.503542) (xy 11.711178 -77.510386)
			(xy 16.911574 -82.710782) (xy 16.91841 -82.718184) (xy 16.926119 -82.736782) (xy 16.92656 -82.74685)
			(xy 16.92656 -89.536778) (xy 16.926671 -89.541875) (xy 16.928715 -89.551863) (xy 16.930624 -89.55659)
			(xy 16.945927 -89.593492) (xy 16.97062 -89.669474) (xy 16.988402 -89.747364) (xy 16.999128 -89.826535)
			(xy 17.002714 -89.906348) (xy 16.999129 -89.986162) (xy 16.988402 -90.065332) (xy 16.970621 -90.143222)
			(xy 16.945928 -90.219204) (xy 16.930624 -90.256106) (xy 16.928754 -90.260845) (xy 16.926708 -90.270825)
			(xy 16.92656 -90.275918) (xy 16.92656 -115.609116) (xy 16.926988 -115.619184) (xy 16.934713 -115.637778)
			(xy 16.941546 -115.645184) (xy 17.50949 -116.213128) (xy 17.516884 -116.219984) (xy 17.535483 -116.227733)
			(xy 17.545558 -116.228114)
		)
		(stroke
			(width 0)
			(type solid)
		)
		(fill yes)
		(layer "In2.Cu")
		(net "P52V_FAN")
	)
	(gr_poly
		(pts
			(xy 38.421818 -67.7545) (xy 38.431887 -67.754073) (xy 38.450486 -67.746354) (xy 38.457886 -67.739514)
			(xy 39.253414 -66.943986) (xy 39.260268 -66.936591) (xy 39.26801 -66.917992) (xy 39.2684 -66.907918)
			(xy 39.2684 -63.825882) (xy 39.267973 -63.815813) (xy 39.260254 -63.797214) (xy 39.253414 -63.789814)
			(xy 33.238186 -57.774586) (xy 33.230791 -57.767732) (xy 33.212192 -57.75999) (xy 33.202118 -57.7596)
			(xy 9.241282 -57.7596) (xy 9.231213 -57.760027) (xy 9.212614 -57.767746) (xy 9.205214 -57.774586)
			(xy 8.422386 -58.557414) (xy 8.415532 -58.564809) (xy 8.40779 -58.583408) (xy 8.4074 -58.593482)
			(xy 8.4074 -60.779914) (xy 8.859012 -60.779914) (xy 8.859529 -60.735741) (xy 8.867385 -60.647746)
			(xy 8.883045 -60.5608) (xy 8.906383 -60.475593) (xy 8.937216 -60.392803) (xy 8.975297 -60.313086)
			(xy 9.020325 -60.237077) (xy 9.071942 -60.165379) (xy 9.129737 -60.098561) (xy 9.193252 -60.037155)
			(xy 9.227312 -60.009024) (xy 9.236202 -60.001658) (xy 9.246108 -59.981084) (xy 9.246108 -59.878722)
			(xy 9.236202 -59.858148) (xy 9.227312 -59.850782) (xy 9.193255 -59.822647) (xy 9.129742 -59.761238)
			(xy 9.071948 -59.694419) (xy 9.020332 -59.622721) (xy 8.975302 -59.546713) (xy 8.937217 -59.466998)
			(xy 8.90638 -59.384209) (xy 8.883034 -59.299004) (xy 8.867365 -59.212059) (xy 8.859498 -59.124065)
			(xy 8.859012 -59.079892) (xy 8.859511 -59.035404) (xy 8.867487 -58.946785) (xy 8.883374 -58.859239)
			(xy 8.907045 -58.773468) (xy 8.938309 -58.690165) (xy 8.976915 -58.61) (xy 9.022551 -58.533618) (xy 9.07485 -58.461635)
			(xy 9.133391 -58.394629) (xy 9.197703 -58.333141) (xy 9.267268 -58.277665) (xy 9.341525 -58.228648)
			(xy 9.419878 -58.186485) (xy 9.501694 -58.151514) (xy 9.586316 -58.124019) (xy 9.673062 -58.10422)
			(xy 9.761233 -58.092276) (xy 9.85012 -58.088285) (xy 9.939007 -58.092276) (xy 10.027178 -58.10422)
			(xy 10.113924 -58.124019) (xy 10.198546 -58.151514) (xy 10.280362 -58.186485) (xy 10.358715 -58.228648)
			(xy 10.432972 -58.277665) (xy 10.502537 -58.333141) (xy 10.566849 -58.394629) (xy 10.62539 -58.461635)
			(xy 10.677689 -58.533618) (xy 10.723325 -58.61) (xy 10.761931 -58.690165) (xy 10.793195 -58.773468)
			(xy 10.816866 -58.859239) (xy 10.832753 -58.946785) (xy 10.840729 -59.035404) (xy 10.841228 -59.079892)
			(xy 10.840737 -59.124065) (xy 10.83288 -59.212062) (xy 10.817219 -59.29901) (xy 10.793879 -59.384217)
			(xy 10.763044 -59.467009) (xy 10.724959 -59.546725) (xy 10.679928 -59.622734) (xy 10.628308 -59.694431)
			(xy 10.570509 -59.761248) (xy 10.50699 -59.822652) (xy 10.472928 -59.850782) (xy 10.464038 -59.858148)
			(xy 10.454132 -59.878722) (xy 10.454132 -59.981084) (xy 10.464038 -60.001658) (xy 10.472928 -60.009024)
			(xy 10.506988 -60.037155) (xy 10.570501 -60.098565) (xy 10.628294 -60.165384) (xy 10.679911 -60.237083)
			(xy 10.72494 -60.313092) (xy 10.763024 -60.392807) (xy 10.793862 -60.475596) (xy 10.817207 -60.560801)
			(xy 10.832875 -60.647746) (xy 10.840742 -60.735741) (xy 10.841228 -60.779914) (xy 11.399012 -60.779914)
			(xy 11.399529 -60.735741) (xy 11.407385 -60.647746) (xy 11.423045 -60.5608) (xy 11.446383 -60.475593)
			(xy 11.477216 -60.392803) (xy 11.515297 -60.313086) (xy 11.560325 -60.237077) (xy 11.611942 -60.165379)
			(xy 11.669737 -60.098561) (xy 11.733252 -60.037155) (xy 11.767312 -60.009024) (xy 11.776202 -60.001658)
			(xy 11.786108 -59.981084) (xy 11.786108 -59.878722) (xy 11.776202 -59.858148) (xy 11.767312 -59.850782)
			(xy 11.733255 -59.822647) (xy 11.669742 -59.761238) (xy 11.611948 -59.694419) (xy 11.560332 -59.622721)
			(xy 11.515302 -59.546713) (xy 11.477217 -59.466998) (xy 11.44638 -59.384209) (xy 11.423034 -59.299004)
			(xy 11.407365 -59.212059) (xy 11.399498 -59.124065) (xy 11.399012 -59.079892) (xy 11.399511 -59.035404)
			(xy 11.407487 -58.946785) (xy 11.423374 -58.859239) (xy 11.447045 -58.773468) (xy 11.478309 -58.690165)
			(xy 11.516915 -58.61) (xy 11.562551 -58.533618) (xy 11.61485 -58.461635) (xy 11.673391 -58.394629)
			(xy 11.737703 -58.333141) (xy 11.807268 -58.277665) (xy 11.881525 -58.228648) (xy 11.959878 -58.186485)
			(xy 12.041694 -58.151514) (xy 12.126316 -58.124019) (xy 12.213062 -58.10422) (xy 12.301233 -58.092276)
			(xy 12.39012 -58.088285) (xy 12.479007 -58.092276) (xy 12.567178 -58.10422) (xy 12.653924 -58.124019)
			(xy 12.738546 -58.151514) (xy 12.820362 -58.186485) (xy 12.898715 -58.228648) (xy 12.972972 -58.277665)
			(xy 13.042537 -58.333141) (xy 13.106849 -58.394629) (xy 13.16539 -58.461635) (xy 13.217689 -58.533618)
			(xy 13.263325 -58.61) (xy 13.301931 -58.690165) (xy 13.333195 -58.773468) (xy 13.356866 -58.859239)
			(xy 13.372753 -58.946785) (xy 13.380729 -59.035404) (xy 13.381228 -59.079892) (xy 13.380737 -59.124065)
			(xy 13.37288 -59.212062) (xy 13.357219 -59.29901) (xy 13.333879 -59.384217) (xy 13.303044 -59.467009)
			(xy 13.264959 -59.546725) (xy 13.219928 -59.622734) (xy 13.168308 -59.694431) (xy 13.110509 -59.761248)
			(xy 13.04699 -59.822652) (xy 13.012928 -59.850782) (xy 13.004038 -59.858148) (xy 12.994132 -59.878722)
			(xy 12.994132 -59.981084) (xy 13.004038 -60.001658) (xy 13.012928 -60.009024) (xy 13.046988 -60.037155)
			(xy 13.110501 -60.098565) (xy 13.168294 -60.165384) (xy 13.219911 -60.237083) (xy 13.26494 -60.313092)
			(xy 13.303024 -60.392807) (xy 13.333862 -60.475596) (xy 13.357207 -60.560801) (xy 13.372875 -60.647746)
			(xy 13.380742 -60.735741) (xy 13.381228 -60.779914) (xy 13.380729 -60.824402) (xy 13.372753 -60.913021)
			(xy 13.356866 -61.000567) (xy 13.333195 -61.086338) (xy 13.301931 -61.169641) (xy 13.263325 -61.249806)
			(xy 13.217689 -61.326188) (xy 13.16539 -61.398171) (xy 13.106849 -61.465177) (xy 13.042537 -61.526665)
			(xy 12.972972 -61.582141) (xy 12.898715 -61.631158) (xy 12.820362 -61.673321) (xy 12.738546 -61.708292)
			(xy 12.653924 -61.735787) (xy 12.567178 -61.755586) (xy 12.479007 -61.76753) (xy 12.39012 -61.771522)
			(xy 12.301233 -61.76753) (xy 12.213062 -61.755586) (xy 12.126316 -61.735787) (xy 12.041694 -61.708292)
			(xy 11.959878 -61.673321) (xy 11.881525 -61.631158) (xy 11.807268 -61.582141) (xy 11.737703 -61.526665)
			(xy 11.673391 -61.465177) (xy 11.61485 -61.398171) (xy 11.562551 -61.326188) (xy 11.516915 -61.249806)
			(xy 11.478309 -61.169641) (xy 11.447045 -61.086338) (xy 11.423374 -61.000567) (xy 11.407487 -60.913021)
			(xy 11.399511 -60.824402) (xy 11.399012 -60.779914) (xy 10.841228 -60.779914) (xy 10.840729 -60.824402)
			(xy 10.832753 -60.913021) (xy 10.816866 -61.000567) (xy 10.793195 -61.086338) (xy 10.761931 -61.169641)
			(xy 10.723325 -61.249806) (xy 10.677689 -61.326188) (xy 10.62539 -61.398171) (xy 10.566849 -61.465177)
			(xy 10.502537 -61.526665) (xy 10.432972 -61.582141) (xy 10.358715 -61.631158) (xy 10.280362 -61.673321)
			(xy 10.198546 -61.708292) (xy 10.113924 -61.735787) (xy 10.027178 -61.755586) (xy 9.939007 -61.76753)
			(xy 9.85012 -61.771522) (xy 9.761233 -61.76753) (xy 9.673062 -61.755586) (xy 9.586316 -61.735787)
			(xy 9.501694 -61.708292) (xy 9.419878 -61.673321) (xy 9.341525 -61.631158) (xy 9.267268 -61.582141)
			(xy 9.197703 -61.526665) (xy 9.133391 -61.465177) (xy 9.07485 -61.398171) (xy 9.022551 -61.326188)
			(xy 8.976915 -61.249806) (xy 8.938309 -61.169641) (xy 8.907045 -61.086338) (xy 8.883374 -61.000567)
			(xy 8.867487 -60.913021) (xy 8.859511 -60.824402) (xy 8.859012 -60.779914) (xy 8.4074 -60.779914)
			(xy 8.4074 -65.859914) (xy 8.859012 -65.859914) (xy 8.859529 -65.815741) (xy 8.867385 -65.727746)
			(xy 8.883045 -65.6408) (xy 8.906383 -65.555593) (xy 8.937216 -65.472803) (xy 8.975297 -65.393086)
			(xy 9.020325 -65.317077) (xy 9.071942 -65.245379) (xy 9.129737 -65.178561) (xy 9.193252 -65.117155)
			(xy 9.227312 -65.089024) (xy 9.236202 -65.081658) (xy 9.246108 -65.061084) (xy 9.246108 -64.958722)
			(xy 9.236202 -64.938148) (xy 9.227312 -64.930782) (xy 9.193255 -64.902647) (xy 9.129742 -64.841238)
			(xy 9.071948 -64.774419) (xy 9.020332 -64.702721) (xy 8.975302 -64.626713) (xy 8.937217 -64.546998)
			(xy 8.90638 -64.464209) (xy 8.883034 -64.379004) (xy 8.867365 -64.292059) (xy 8.859498 -64.204065)
			(xy 8.859012 -64.159892) (xy 8.859511 -64.115404) (xy 8.867487 -64.026785) (xy 8.883374 -63.939239)
			(xy 8.907045 -63.853468) (xy 8.938309 -63.770165) (xy 8.976915 -63.69) (xy 9.022551 -63.613618) (xy 9.07485 -63.541635)
			(xy 9.133391 -63.474629) (xy 9.197703 -63.413141) (xy 9.267268 -63.357665) (xy 9.341525 -63.308648)
			(xy 9.419878 -63.266485) (xy 9.501694 -63.231514) (xy 9.586316 -63.204019) (xy 9.673062 -63.18422)
			(xy 9.761233 -63.172276) (xy 9.85012 -63.168285) (xy 9.939007 -63.172276) (xy 10.027178 -63.18422)
			(xy 10.113924 -63.204019) (xy 10.198546 -63.231514) (xy 10.280362 -63.266485) (xy 10.358715 -63.308648)
			(xy 10.432972 -63.357665) (xy 10.502537 -63.413141) (xy 10.566849 -63.474629) (xy 10.62539 -63.541635)
			(xy 10.677689 -63.613618) (xy 10.723325 -63.69) (xy 10.761931 -63.770165) (xy 10.793195 -63.853468)
			(xy 10.816866 -63.939239) (xy 10.832753 -64.026785) (xy 10.840729 -64.115404) (xy 10.841228 -64.159892)
			(xy 10.840737 -64.204065) (xy 10.83288 -64.292062) (xy 10.817219 -64.37901) (xy 10.793879 -64.464217)
			(xy 10.763044 -64.547009) (xy 10.724959 -64.626725) (xy 10.679928 -64.702734) (xy 10.628308 -64.774431)
			(xy 10.570509 -64.841248) (xy 10.50699 -64.902652) (xy 10.472928 -64.930782) (xy 10.464038 -64.938148)
			(xy 10.454132 -64.958722) (xy 10.454132 -65.061084) (xy 10.464038 -65.081658) (xy 10.472928 -65.089024)
			(xy 10.506988 -65.117155) (xy 10.570501 -65.178565) (xy 10.628294 -65.245384) (xy 10.679911 -65.317083)
			(xy 10.72494 -65.393092) (xy 10.763024 -65.472807) (xy 10.793862 -65.555596) (xy 10.817207 -65.640801)
			(xy 10.832875 -65.727746) (xy 10.840742 -65.815741) (xy 10.841228 -65.859914) (xy 11.399012 -65.859914)
			(xy 11.399529 -65.815741) (xy 11.407385 -65.727746) (xy 11.423045 -65.6408) (xy 11.446383 -65.555593)
			(xy 11.477216 -65.472803) (xy 11.515297 -65.393086) (xy 11.560325 -65.317077) (xy 11.611942 -65.245379)
			(xy 11.669737 -65.178561) (xy 11.733252 -65.117155) (xy 11.767312 -65.089024) (xy 11.776202 -65.081658)
			(xy 11.786108 -65.061084) (xy 11.786108 -64.958722) (xy 11.776202 -64.938148) (xy 11.767312 -64.930782)
			(xy 11.733255 -64.902647) (xy 11.669742 -64.841238) (xy 11.611948 -64.774419) (xy 11.560332 -64.702721)
			(xy 11.515302 -64.626713) (xy 11.477217 -64.546998) (xy 11.44638 -64.464209) (xy 11.423034 -64.379004)
			(xy 11.407365 -64.292059) (xy 11.399498 -64.204065) (xy 11.399012 -64.159892) (xy 11.399511 -64.115404)
			(xy 11.407487 -64.026785) (xy 11.423374 -63.939239) (xy 11.447045 -63.853468) (xy 11.478309 -63.770165)
			(xy 11.516915 -63.69) (xy 11.562551 -63.613618) (xy 11.61485 -63.541635) (xy 11.673391 -63.474629)
			(xy 11.737703 -63.413141) (xy 11.807268 -63.357665) (xy 11.881525 -63.308648) (xy 11.959878 -63.266485)
			(xy 12.041694 -63.231514) (xy 12.126316 -63.204019) (xy 12.213062 -63.18422) (xy 12.301233 -63.172276)
			(xy 12.39012 -63.168285) (xy 12.479007 -63.172276) (xy 12.567178 -63.18422) (xy 12.653924 -63.204019)
			(xy 12.738546 -63.231514) (xy 12.820362 -63.266485) (xy 12.898715 -63.308648) (xy 12.972972 -63.357665)
			(xy 13.042537 -63.413141) (xy 13.106849 -63.474629) (xy 13.16539 -63.541635) (xy 13.217689 -63.613618)
			(xy 13.263325 -63.69) (xy 13.301931 -63.770165) (xy 13.333195 -63.853468) (xy 13.356866 -63.939239)
			(xy 13.372753 -64.026785) (xy 13.380729 -64.115404) (xy 13.381228 -64.159892) (xy 13.380737 -64.204065)
			(xy 13.37288 -64.292062) (xy 13.357219 -64.37901) (xy 13.333879 -64.464217) (xy 13.303044 -64.547009)
			(xy 13.264959 -64.626725) (xy 13.219928 -64.702734) (xy 13.168308 -64.774431) (xy 13.110509 -64.841248)
			(xy 13.04699 -64.902652) (xy 13.012928 -64.930782) (xy 13.004038 -64.938148) (xy 12.994132 -64.958722)
			(xy 12.994132 -65.061084) (xy 13.004038 -65.081658) (xy 13.012928 -65.089024) (xy 13.046988 -65.117155)
			(xy 13.110501 -65.178565) (xy 13.168294 -65.245384) (xy 13.219911 -65.317083) (xy 13.26494 -65.393092)
			(xy 13.303024 -65.472807) (xy 13.333862 -65.555596) (xy 13.357207 -65.640801) (xy 13.372875 -65.727746)
			(xy 13.380742 -65.815741) (xy 13.381228 -65.859914) (xy 13.380729 -65.904402) (xy 13.372753 -65.993021)
			(xy 13.356866 -66.080567) (xy 13.333195 -66.166338) (xy 13.301931 -66.249641) (xy 13.263325 -66.329806)
			(xy 13.217689 -66.406188) (xy 13.16539 -66.478171) (xy 13.106849 -66.545177) (xy 13.042537 -66.606665)
			(xy 12.972972 -66.662141) (xy 12.898715 -66.711158) (xy 12.820362 -66.753321) (xy 12.738546 -66.788292)
			(xy 12.653924 -66.815787) (xy 12.567178 -66.835586) (xy 12.479007 -66.84753) (xy 12.39012 -66.851522)
			(xy 12.301233 -66.84753) (xy 12.213062 -66.835586) (xy 12.126316 -66.815787) (xy 12.041694 -66.788292)
			(xy 11.959878 -66.753321) (xy 11.881525 -66.711158) (xy 11.807268 -66.662141) (xy 11.737703 -66.606665)
			(xy 11.673391 -66.545177) (xy 11.61485 -66.478171) (xy 11.562551 -66.406188) (xy 11.516915 -66.329806)
			(xy 11.478309 -66.249641) (xy 11.447045 -66.166338) (xy 11.423374 -66.080567) (xy 11.407487 -65.993021)
			(xy 11.399511 -65.904402) (xy 11.399012 -65.859914) (xy 10.841228 -65.859914) (xy 10.840729 -65.904402)
			(xy 10.832753 -65.993021) (xy 10.816866 -66.080567) (xy 10.793195 -66.166338) (xy 10.761931 -66.249641)
			(xy 10.723325 -66.329806) (xy 10.677689 -66.406188) (xy 10.62539 -66.478171) (xy 10.566849 -66.545177)
			(xy 10.502537 -66.606665) (xy 10.432972 -66.662141) (xy 10.358715 -66.711158) (xy 10.280362 -66.753321)
			(xy 10.198546 -66.788292) (xy 10.113924 -66.815787) (xy 10.027178 -66.835586) (xy 9.939007 -66.84753)
			(xy 9.85012 -66.851522) (xy 9.761233 -66.84753) (xy 9.673062 -66.835586) (xy 9.586316 -66.815787)
			(xy 9.501694 -66.788292) (xy 9.419878 -66.753321) (xy 9.341525 -66.711158) (xy 9.267268 -66.662141)
			(xy 9.197703 -66.606665) (xy 9.133391 -66.545177) (xy 9.07485 -66.478171) (xy 9.022551 -66.406188)
			(xy 8.976915 -66.329806) (xy 8.938309 -66.249641) (xy 8.907045 -66.166338) (xy 8.883374 -66.080567)
			(xy 8.867487 -65.993021) (xy 8.859511 -65.904402) (xy 8.859012 -65.859914) (xy 8.4074 -65.859914)
			(xy 8.4074 -66.831718) (xy 8.407827 -66.841787) (xy 8.415546 -66.860386) (xy 8.422386 -66.867786)
			(xy 8.697214 -67.142614) (xy 8.704609 -67.149468) (xy 8.723208 -67.15721) (xy 8.733282 -67.1576)
			(xy 26.81097 -67.1576) (xy 26.820494 -67.157209) (xy 26.838227 -67.150256) (xy 26.852192 -67.137302)
			(xy 26.85669 -67.128898) (xy 26.902664 -67.032886) (xy 26.899362 -67.00393) (xy 26.890218 -66.9925)
			(xy 26.863781 -66.958671) (xy 26.816806 -66.886799) (xy 26.776973 -66.810736) (xy 26.744652 -66.73119)
			(xy 26.720143 -66.648901) (xy 26.703675 -66.564633) (xy 26.6954 -66.479171) (xy 26.694892 -66.43624)
			(xy 26.695475 -66.389843) (xy 26.705104 -66.297552) (xy 26.724293 -66.206765) (xy 26.752834 -66.118471)
			(xy 26.771092 -66.075814) (xy 26.775005 -66.065892) (xy 26.775021 -66.044581) (xy 26.771092 -66.034666)
			(xy 26.752857 -65.992001) (xy 26.724325 -65.903707) (xy 26.705135 -65.812923) (xy 26.695496 -65.720635)
			(xy 26.694892 -65.67424) (xy 26.695475 -65.627843) (xy 26.705104 -65.535552) (xy 26.724293 -65.444765)
			(xy 26.752834 -65.356471) (xy 26.771092 -65.313814) (xy 26.775005 -65.303892) (xy 26.775021 -65.282581)
			(xy 26.771092 -65.272666) (xy 26.752857 -65.230001) (xy 26.724325 -65.141707) (xy 26.705135 -65.050923)
			(xy 26.695496 -64.958635) (xy 26.694892 -64.91224) (xy 26.69535 -64.871136) (xy 26.702932 -64.789277)
			(xy 26.718035 -64.708468) (xy 26.740529 -64.629397) (xy 26.770224 -64.552738) (xy 26.806865 -64.479147)
			(xy 26.85014 -64.40925) (xy 26.89968 -64.343645) (xy 26.955063 -64.282891) (xy 27.015814 -64.227506)
			(xy 27.081417 -64.177963) (xy 27.151312 -64.134685) (xy 27.224902 -64.09804) (xy 27.301559 -64.068342)
			(xy 27.380629 -64.045844) (xy 27.461438 -64.030738) (xy 27.543296 -64.023152) (xy 27.5844 -64.022732)
			(xy 27.630796 -64.023317) (xy 27.723086 -64.032951) (xy 27.813871 -64.052144) (xy 27.902163 -64.08069)
			(xy 27.944826 -64.098932) (xy 27.954766 -64.102752) (xy 27.976034 -64.102752) (xy 27.985974 -64.098932)
			(xy 28.028639 -64.080693) (xy 28.116932 -64.052154) (xy 28.207716 -64.032957) (xy 28.300004 -64.023311)
			(xy 28.3464 -64.022732) (xy 28.387502 -64.023192) (xy 28.469357 -64.030777) (xy 28.550162 -64.045883)
			(xy 28.629229 -64.06838) (xy 28.705882 -64.098077) (xy 28.779469 -64.13472) (xy 28.84936 -64.177996)
			(xy 28.91496 -64.227537) (xy 28.975709 -64.282919) (xy 29.031089 -64.343671) (xy 29.080627 -64.409273)
			(xy 29.1239 -64.479166) (xy 29.16054 -64.552754) (xy 29.190233 -64.629409) (xy 29.212726 -64.708477)
			(xy 29.227828 -64.789283) (xy 29.23541 -64.871137) (xy 29.235908 -64.91224) (xy 29.235321 -64.958636)
			(xy 29.225684 -65.050925) (xy 29.206487 -65.141708) (xy 29.17794 -65.229998) (xy 29.159708 -65.272666)
			(xy 29.155812 -65.282587) (xy 29.155827 -65.303885) (xy 29.159708 -65.313814) (xy 29.177944 -65.356479)
			(xy 29.206478 -65.444773) (xy 29.22567 -65.535557) (xy 29.235311 -65.627845) (xy 29.235908 -65.67424)
			(xy 29.235321 -65.720636) (xy 29.225684 -65.812925) (xy 29.206487 -65.903708) (xy 29.17794 -65.991998)
			(xy 29.159708 -66.034666) (xy 29.155812 -66.044587) (xy 29.155827 -66.065885) (xy 29.159708 -66.075814)
			(xy 29.177944 -66.118479) (xy 29.206478 -66.206773) (xy 29.22567 -66.297557) (xy 29.235311 -66.389845)
			(xy 29.235908 -66.43624) (xy 29.235381 -66.479703) (xy 29.2269 -66.566213) (xy 29.210022 -66.651484)
			(xy 29.184908 -66.734702) (xy 29.151799 -66.815074) (xy 29.111009 -66.891835) (xy 29.062927 -66.964251)
			(xy 29.008012 -67.031633) (xy 28.946787 -67.093338) (xy 28.879837 -67.148778) (xy 28.807798 -67.197424)
			(xy 28.769818 -67.21856) (xy 28.758896 -67.224402) (xy 28.745434 -67.243706) (xy 28.731972 -67.336416)
			(xy 28.730863 -67.348236) (xy 28.73827 -67.370759) (xy 28.746196 -67.379596) (xy 29.106114 -67.739514)
			(xy 29.113509 -67.746368) (xy 29.132108 -67.75411) (xy 29.142182 -67.7545)
		)
		(stroke
			(width 0)
			(type solid)
		)
		(fill yes)
		(layer "In2.Cu")
		(net "GND")
	)
	(gr_poly
		(pts
			(xy 36.068 -145.984468)
			(arc
				(start 4.99999 -145.984468)
				(mid 2.182524 -144.817436)
				(end 1.015492 -141.99997)
			)
			(arc
				(start 1.015492 -131.729988)
				(mid 1.596724 -130.326643)
				(end 2.999994 -129.745232)
			)
			(arc
				(start 9.600184 -129.745232)
				(mid 10.671529 -129.301467)
				(end 11.115294 -128.230122)
			)
			(xy 11.115548 -128.230122)
			(arc
				(start 11.115548 -116.730018)
				(mid 10.671634 -115.658314)
				(end 9.59993 -115.2144)
			)
			(arc
				(start 2.999994 -115.2144)
				(mid 1.596739 -114.633153)
				(end 1.015492 -113.229898)
			)
			(arc
				(start 1.015492 -34.569908)
				(mid 1.596724 -33.166563)
				(end 2.999994 -32.585152)
			)
			(arc
				(start 9.600184 -32.585152)
				(mid 10.671454 -32.141312)
				(end 11.115294 -31.070042)
			)
			(xy 11.115548 -31.070042) (xy 11.115548 -19.569938)
			(arc
				(start 11.115294 -19.569938)
				(mid 10.671439 -18.498758)
				(end 9.600184 -18.054828)
			)
			(arc
				(start 2.999994 -18.054828)
				(mid 1.596829 -17.473671)
				(end 1.015492 -16.07058)
			)
			(arc
				(start 1.015492 -4.99999)
				(mid 2.182524 -2.182524)
				(end 4.99999 -1.015492)
			)
			(arc
				(start 323.000116 -1.015492)
				(mid 325.817582 -2.182524)
				(end 326.984614 -4.99999)
			)
			(arc
				(start 326.984614 -141.99997)
				(mid 325.817582 -144.817436)
				(end 323.000116 -145.984468)
			)
			(xy 236.728 -145.984468) (xy 236.728 -146.49196)
			(arc
				(start 323.000116 -146.49196)
				(mid 326.176433 -145.176287)
				(end 327.492106 -141.99997)
			)
			(arc
				(start 327.492106 -4.99999)
				(mid 326.176433 -1.823673)
				(end 323.000116 -0.508)
			)
			(arc
				(start 4.99999 -0.508)
				(mid 1.823673 -1.823673)
				(end 0.508 -4.99999)
			)
			(arc
				(start 0.508 -16.070072)
				(mid 1.237888 -17.832178)
				(end 2.999994 -18.562066)
			)
			(arc
				(start 9.600184 -18.562066)
				(mid 10.312947 -18.857249)
				(end 10.608056 -19.569938)
			)
			(arc
				(start 10.608056 -31.070042)
				(mid 10.312783 -31.782641)
				(end 9.600184 -32.077914)
			)
			(arc
				(start 2.999994 -32.077914)
				(mid 1.237888 -32.807802)
				(end 0.508 -34.569908)
			)
			(arc
				(start 0.508 -113.229898)
				(mid 1.237888 -114.992004)
				(end 2.999994 -115.721892)
			)
			(arc
				(start 9.59993 -115.721892)
				(mid 10.312783 -116.017165)
				(end 10.608056 -116.730018)
			)
			(arc
				(start 10.608056 -128.230122)
				(mid 10.312857 -128.942795)
				(end 9.600184 -129.237994)
			)
			(arc
				(start 2.999994 -129.237994)
				(mid 1.237888 -129.967882)
				(end 0.508 -131.729988)
			)
			(arc
				(start 0.508 -141.99997)
				(mid 1.823673 -145.176287)
				(end 4.99999 -146.49196)
			)
			(xy 36.068 -146.49196)
		)
		(stroke
			(width 0)
			(type solid)
		)
		(fill yes)
		(layer "In2.Cu")
		(net "GND")
	)
	(gr_poly
		(pts
			(xy 274.303744 -144.703546) (xy 274.313809 -144.703113) (xy 274.332397 -144.695382) (xy 274.339812 -144.68856)
			(xy 274.965922 -144.06245) (xy 274.972769 -144.055053) (xy 274.980498 -144.036453) (xy 274.980908 -144.026382)
			(xy 274.980908 -95.77578) (xy 274.980511 -95.767129) (xy 274.974653 -95.750843) (xy 274.963713 -95.737432)
			(xy 274.956524 -95.7326) (xy 274.870926 -95.680276) (xy 274.845018 -95.67926) (xy 274.832826 -95.68561)
			(xy 274.795024 -95.704465) (xy 274.716557 -95.735767) (xy 274.635477 -95.759493) (xy 274.552513 -95.775429)
			(xy 274.468412 -95.783431) (xy 274.426172 -95.783908) (xy 274.383824 -95.783403) (xy 274.299513 -95.77535)
			(xy 274.216348 -95.759319) (xy 274.135085 -95.735455) (xy 274.056457 -95.703975) (xy 273.981178 -95.665164)
			(xy 273.909928 -95.619373) (xy 273.843354 -95.567017) (xy 273.782058 -95.508569) (xy 273.726596 -95.44456)
			(xy 273.677468 -95.375569) (xy 273.635121 -95.30222) (xy 273.599938 -95.225178) (xy 273.572238 -95.145141)
			(xy 273.552271 -95.062833) (xy 273.540217 -94.978999) (xy 273.536187 -94.8944) (xy 273.540217 -94.809801)
			(xy 273.552271 -94.725967) (xy 273.572238 -94.643659) (xy 273.599938 -94.563622) (xy 273.635121 -94.48658)
			(xy 273.677468 -94.413231) (xy 273.726596 -94.34424) (xy 273.782058 -94.280231) (xy 273.843354 -94.221783)
			(xy 273.909928 -94.169427) (xy 273.981178 -94.123636) (xy 274.056457 -94.084825) (xy 274.135085 -94.053345)
			(xy 274.216348 -94.029481) (xy 274.299513 -94.01345) (xy 274.383824 -94.005397) (xy 274.426172 -94.004892)
			(xy 274.468413 -94.005376) (xy 274.552517 -94.01336) (xy 274.635483 -94.029286) (xy 274.716565 -94.053011)
			(xy 274.79503 -94.084322) (xy 274.832826 -94.10319) (xy 274.845018 -94.10954) (xy 274.870926 -94.108524)
			(xy 274.956524 -94.0562) (xy 274.963741 -94.051405) (xy 274.97468 -94.037983) (xy 274.980505 -94.021677)
			(xy 274.980908 -94.01302) (xy 274.980908 -62.27699) (xy 274.980484 -62.26692) (xy 274.972767 -62.248318)
			(xy 274.965922 -62.240922) (xy 274.080986 -61.355986) (xy 274.073591 -61.349132) (xy 274.054992 -61.34139)
			(xy 274.044918 -61.341) (xy 256.002282 -61.341) (xy 255.992213 -61.341427) (xy 255.973614 -61.349146)
			(xy 255.966214 -61.355986) (xy 253.760986 -63.561214) (xy 253.753591 -63.568068) (xy 253.734992 -63.57581)
			(xy 253.724918 -63.5762) (xy 243.623846 -63.5762) (xy 243.61378 -63.576633) (xy 243.59519 -63.584361)
			(xy 243.587778 -63.591186) (xy 242.83035 -64.348614) (xy 242.8235 -64.356011) (xy 242.815763 -64.374609)
			(xy 242.815364 -64.384682) (xy 242.815364 -68.734616) (xy 270.30705 -68.734616) (xy 270.30705 -68.64992)
			(xy 270.315101 -68.565606) (xy 270.33113 -68.48244) (xy 270.354991 -68.401173) (xy 270.38647 -68.322543)
			(xy 270.425281 -68.247262) (xy 270.471071 -68.17601) (xy 270.523427 -68.109434) (xy 270.581875 -68.048136)
			(xy 270.645885 -67.992671) (xy 270.714877 -67.943542) (xy 270.788227 -67.901193) (xy 270.86527 -67.866009)
			(xy 270.945309 -67.838307) (xy 271.027618 -67.818339) (xy 271.111453 -67.806286) (xy 271.196054 -67.802256)
			(xy 271.280655 -67.806286) (xy 271.36449 -67.818339) (xy 271.446799 -67.838307) (xy 271.526838 -67.866009)
			(xy 271.603881 -67.901193) (xy 271.677231 -67.943542) (xy 271.746223 -67.992671) (xy 271.810233 -68.048136)
			(xy 271.868681 -68.109434) (xy 271.921037 -68.17601) (xy 271.966827 -68.247262) (xy 272.005638 -68.322543)
			(xy 272.037117 -68.401173) (xy 272.060978 -68.48244) (xy 272.077007 -68.565606) (xy 272.085058 -68.64992)
			(xy 272.085562 -68.692268) (xy 272.085058 -68.734616) (xy 272.077007 -68.81893) (xy 272.060978 -68.902096)
			(xy 272.037117 -68.983363) (xy 272.005638 -69.061993) (xy 271.966827 -69.137274) (xy 271.921037 -69.208526)
			(xy 271.868681 -69.275102) (xy 271.810233 -69.3364) (xy 271.746223 -69.391865) (xy 271.677231 -69.440994)
			(xy 271.603881 -69.483343) (xy 271.526838 -69.518527) (xy 271.446799 -69.546229) (xy 271.36449 -69.566197)
			(xy 271.280655 -69.57825) (xy 271.196054 -69.582281) (xy 271.111453 -69.57825) (xy 271.027618 -69.566197)
			(xy 270.945309 -69.546229) (xy 270.86527 -69.518527) (xy 270.788227 -69.483343) (xy 270.714877 -69.440994)
			(xy 270.645885 -69.391865) (xy 270.581875 -69.3364) (xy 270.523427 -69.275102) (xy 270.471071 -69.208526)
			(xy 270.425281 -69.137274) (xy 270.38647 -69.061993) (xy 270.354991 -68.983363) (xy 270.33113 -68.902096)
			(xy 270.315101 -68.81893) (xy 270.30705 -68.734616) (xy 242.815364 -68.734616) (xy 242.815364 -70.207816)
			(xy 268.757396 -70.207816) (xy 268.757396 -70.12312) (xy 268.765447 -70.038806) (xy 268.781476 -69.95564)
			(xy 268.805337 -69.874373) (xy 268.836816 -69.795743) (xy 268.875627 -69.720462) (xy 268.921417 -69.64921)
			(xy 268.973773 -69.582634) (xy 269.032221 -69.521336) (xy 269.096231 -69.465871) (xy 269.165223 -69.416742)
			(xy 269.238573 -69.374393) (xy 269.315616 -69.339209) (xy 269.395655 -69.311507) (xy 269.477964 -69.291539)
			(xy 269.561799 -69.279486) (xy 269.6464 -69.275456) (xy 269.731001 -69.279486) (xy 269.814836 -69.291539)
			(xy 269.897145 -69.311507) (xy 269.977184 -69.339209) (xy 270.054227 -69.374393) (xy 270.127577 -69.416742)
			(xy 270.196569 -69.465871) (xy 270.260579 -69.521336) (xy 270.319027 -69.582634) (xy 270.371383 -69.64921)
			(xy 270.417173 -69.720462) (xy 270.455984 -69.795743) (xy 270.487463 -69.874373) (xy 270.511324 -69.95564)
			(xy 270.527353 -70.038806) (xy 270.535404 -70.12312) (xy 270.535908 -70.165468) (xy 270.535404 -70.207816)
			(xy 270.527353 -70.29213) (xy 270.511324 -70.375296) (xy 270.487463 -70.456563) (xy 270.455984 -70.535193)
			(xy 270.417173 -70.610474) (xy 270.371383 -70.681726) (xy 270.319027 -70.748302) (xy 270.260579 -70.8096)
			(xy 270.196569 -70.865065) (xy 270.127577 -70.914194) (xy 270.054227 -70.956543) (xy 269.977184 -70.991727)
			(xy 269.897145 -71.019429) (xy 269.814836 -71.039397) (xy 269.731001 -71.05145) (xy 269.6464 -71.055481)
			(xy 269.561799 -71.05145) (xy 269.477964 -71.039397) (xy 269.395655 -71.019429) (xy 269.315616 -70.991727)
			(xy 269.238573 -70.956543) (xy 269.165223 -70.914194) (xy 269.096231 -70.865065) (xy 269.032221 -70.8096)
			(xy 268.973773 -70.748302) (xy 268.921417 -70.681726) (xy 268.875627 -70.610474) (xy 268.836816 -70.535193)
			(xy 268.805337 -70.456563) (xy 268.781476 -70.375296) (xy 268.765447 -70.29213) (xy 268.757396 -70.207816)
			(xy 242.815364 -70.207816) (xy 242.815364 -80.799616) (xy 270.301462 -80.799616) (xy 270.301462 -80.71492)
			(xy 270.309513 -80.630606) (xy 270.325542 -80.54744) (xy 270.349403 -80.466173) (xy 270.380882 -80.387543)
			(xy 270.419693 -80.312262) (xy 270.465483 -80.24101) (xy 270.517839 -80.174434) (xy 270.576287 -80.113136)
			(xy 270.640297 -80.057671) (xy 270.709289 -80.008542) (xy 270.782639 -79.966193) (xy 270.859682 -79.931009)
			(xy 270.939721 -79.903307) (xy 271.02203 -79.883339) (xy 271.105865 -79.871286) (xy 271.190466 -79.867256)
			(xy 271.275067 -79.871286) (xy 271.358902 -79.883339) (xy 271.441211 -79.903307) (xy 271.52125 -79.931009)
			(xy 271.598293 -79.966193) (xy 271.671643 -80.008542) (xy 271.740635 -80.057671) (xy 271.804645 -80.113136)
			(xy 271.863093 -80.174434) (xy 271.915449 -80.24101) (xy 271.961239 -80.312262) (xy 272.00005 -80.387543)
			(xy 272.031529 -80.466173) (xy 272.05539 -80.54744) (xy 272.071419 -80.630606) (xy 272.07947 -80.71492)
			(xy 272.079974 -80.757268) (xy 272.07947 -80.799616) (xy 272.071419 -80.88393) (xy 272.05539 -80.967096)
			(xy 272.031529 -81.048363) (xy 272.00005 -81.126993) (xy 271.961239 -81.202274) (xy 271.915449 -81.273526)
			(xy 271.863093 -81.340102) (xy 271.804645 -81.4014) (xy 271.740635 -81.456865) (xy 271.671643 -81.505994)
			(xy 271.598293 -81.548343) (xy 271.52125 -81.583527) (xy 271.441211 -81.611229) (xy 271.358902 -81.631197)
			(xy 271.275067 -81.64325) (xy 271.190466 -81.647281) (xy 271.105865 -81.64325) (xy 271.02203 -81.631197)
			(xy 270.939721 -81.611229) (xy 270.859682 -81.583527) (xy 270.782639 -81.548343) (xy 270.709289 -81.505994)
			(xy 270.640297 -81.456865) (xy 270.576287 -81.4014) (xy 270.517839 -81.340102) (xy 270.465483 -81.273526)
			(xy 270.419693 -81.202274) (xy 270.380882 -81.126993) (xy 270.349403 -81.048363) (xy 270.325542 -80.967096)
			(xy 270.309513 -80.88393) (xy 270.301462 -80.799616) (xy 242.815364 -80.799616) (xy 242.815364 -82.272816)
			(xy 268.757396 -82.272816) (xy 268.757396 -82.18812) (xy 268.765447 -82.103806) (xy 268.781476 -82.02064)
			(xy 268.805337 -81.939373) (xy 268.836816 -81.860743) (xy 268.875627 -81.785462) (xy 268.921417 -81.71421)
			(xy 268.973773 -81.647634) (xy 269.032221 -81.586336) (xy 269.096231 -81.530871) (xy 269.165223 -81.481742)
			(xy 269.238573 -81.439393) (xy 269.315616 -81.404209) (xy 269.395655 -81.376507) (xy 269.477964 -81.356539)
			(xy 269.561799 -81.344486) (xy 269.6464 -81.340456) (xy 269.731001 -81.344486) (xy 269.814836 -81.356539)
			(xy 269.897145 -81.376507) (xy 269.977184 -81.404209) (xy 270.054227 -81.439393) (xy 270.127577 -81.481742)
			(xy 270.196569 -81.530871) (xy 270.260579 -81.586336) (xy 270.319027 -81.647634) (xy 270.371383 -81.71421)
			(xy 270.417173 -81.785462) (xy 270.455984 -81.860743) (xy 270.487463 -81.939373) (xy 270.511324 -82.02064)
			(xy 270.527353 -82.103806) (xy 270.535404 -82.18812) (xy 270.535908 -82.230468) (xy 270.535404 -82.272816)
			(xy 270.527353 -82.35713) (xy 270.511324 -82.440296) (xy 270.487463 -82.521563) (xy 270.455984 -82.600193)
			(xy 270.417173 -82.675474) (xy 270.371383 -82.746726) (xy 270.319027 -82.813302) (xy 270.260579 -82.8746)
			(xy 270.196569 -82.930065) (xy 270.127577 -82.979194) (xy 270.054227 -83.021543) (xy 269.977184 -83.056727)
			(xy 269.897145 -83.084429) (xy 269.814836 -83.104397) (xy 269.731001 -83.11645) (xy 269.6464 -83.120481)
			(xy 269.561799 -83.11645) (xy 269.477964 -83.104397) (xy 269.395655 -83.084429) (xy 269.315616 -83.056727)
			(xy 269.238573 -83.021543) (xy 269.165223 -82.979194) (xy 269.096231 -82.930065) (xy 269.032221 -82.8746)
			(xy 268.973773 -82.813302) (xy 268.921417 -82.746726) (xy 268.875627 -82.675474) (xy 268.836816 -82.600193)
			(xy 268.805337 -82.521563) (xy 268.781476 -82.440296) (xy 268.765447 -82.35713) (xy 268.757396 -82.272816)
			(xy 242.815364 -82.272816) (xy 242.815364 -91.391416) (xy 268.757396 -91.391416) (xy 268.757396 -91.30672)
			(xy 268.765447 -91.222406) (xy 268.781476 -91.13924) (xy 268.805337 -91.057973) (xy 268.836816 -90.979343)
			(xy 268.875627 -90.904062) (xy 268.921417 -90.83281) (xy 268.973773 -90.766234) (xy 269.032221 -90.704936)
			(xy 269.096231 -90.649471) (xy 269.165223 -90.600342) (xy 269.238573 -90.557993) (xy 269.315616 -90.522809)
			(xy 269.395655 -90.495107) (xy 269.477964 -90.475139) (xy 269.561799 -90.463086) (xy 269.6464 -90.459056)
			(xy 269.731001 -90.463086) (xy 269.814836 -90.475139) (xy 269.897145 -90.495107) (xy 269.977184 -90.522809)
			(xy 270.054227 -90.557993) (xy 270.127577 -90.600342) (xy 270.196569 -90.649471) (xy 270.260579 -90.704936)
			(xy 270.319027 -90.766234) (xy 270.371383 -90.83281) (xy 270.417173 -90.904062) (xy 270.455984 -90.979343)
			(xy 270.487463 -91.057973) (xy 270.511324 -91.13924) (xy 270.527353 -91.222406) (xy 270.535404 -91.30672)
			(xy 270.535908 -91.349068) (xy 270.535404 -91.391416) (xy 270.527353 -91.47573) (xy 270.511324 -91.558896)
			(xy 270.487463 -91.640163) (xy 270.455984 -91.718793) (xy 270.417173 -91.794074) (xy 270.371383 -91.865326)
			(xy 270.319027 -91.931902) (xy 270.260579 -91.9932) (xy 270.196569 -92.048665) (xy 270.127577 -92.097794)
			(xy 270.054227 -92.140143) (xy 269.977184 -92.175327) (xy 269.897145 -92.203029) (xy 269.814836 -92.222997)
			(xy 269.731001 -92.23505) (xy 269.6464 -92.239081) (xy 269.561799 -92.23505) (xy 269.477964 -92.222997)
			(xy 269.395655 -92.203029) (xy 269.315616 -92.175327) (xy 269.238573 -92.140143) (xy 269.165223 -92.097794)
			(xy 269.096231 -92.048665) (xy 269.032221 -91.9932) (xy 268.973773 -91.931902) (xy 268.921417 -91.865326)
			(xy 268.875627 -91.794074) (xy 268.836816 -91.718793) (xy 268.805337 -91.640163) (xy 268.781476 -91.558896)
			(xy 268.765447 -91.47573) (xy 268.757396 -91.391416) (xy 242.815364 -91.391416) (xy 242.815364 -92.062554)
			(xy 242.81493 -92.072619) (xy 242.807198 -92.091206) (xy 242.800378 -92.098622) (xy 242.760754 -92.138246)
			(xy 242.753614 -92.146072) (xy 242.74585 -92.165755) (xy 242.745768 -92.176346) (xy 242.74907 -92.26169)
			(xy 242.758214 -92.280486) (xy 242.766596 -92.287344) (xy 242.798752 -92.315471) (xy 242.858102 -92.376928)
			(xy 242.911288 -92.443792) (xy 242.957819 -92.515446) (xy 242.997267 -92.591231) (xy 243.029269 -92.670448)
			(xy 243.053529 -92.752368) (xy 243.069824 -92.836237) (xy 243.072554 -92.864616) (xy 270.308574 -92.864616)
			(xy 270.308574 -92.77992) (xy 270.316625 -92.695606) (xy 270.332654 -92.61244) (xy 270.356515 -92.531173)
			(xy 270.387994 -92.452543) (xy 270.426805 -92.377262) (xy 270.472595 -92.30601) (xy 270.524951 -92.239434)
			(xy 270.583399 -92.178136) (xy 270.647409 -92.122671) (xy 270.716401 -92.073542) (xy 270.789751 -92.031193)
			(xy 270.866794 -91.996009) (xy 270.946833 -91.968307) (xy 271.029142 -91.948339) (xy 271.112977 -91.936286)
			(xy 271.197578 -91.932256) (xy 271.282179 -91.936286) (xy 271.366014 -91.948339) (xy 271.448323 -91.968307)
			(xy 271.528362 -91.996009) (xy 271.605405 -92.031193) (xy 271.678755 -92.073542) (xy 271.747747 -92.122671)
			(xy 271.811757 -92.178136) (xy 271.870205 -92.239434) (xy 271.922561 -92.30601) (xy 271.968351 -92.377262)
			(xy 272.007162 -92.452543) (xy 272.038641 -92.531173) (xy 272.062502 -92.61244) (xy 272.078531 -92.695606)
			(xy 272.086582 -92.77992) (xy 272.087086 -92.822268) (xy 272.086582 -92.864616) (xy 272.078531 -92.94893)
			(xy 272.062502 -93.032096) (xy 272.038641 -93.113363) (xy 272.007162 -93.191993) (xy 271.968351 -93.267274)
			(xy 271.922561 -93.338526) (xy 271.870205 -93.405102) (xy 271.811757 -93.4664) (xy 271.747747 -93.521865)
			(xy 271.678755 -93.570994) (xy 271.605405 -93.613343) (xy 271.528362 -93.648527) (xy 271.448323 -93.676229)
			(xy 271.366014 -93.696197) (xy 271.282179 -93.70825) (xy 271.197578 -93.712281) (xy 271.112977 -93.70825)
			(xy 271.029142 -93.696197) (xy 270.946833 -93.676229) (xy 270.866794 -93.648527) (xy 270.789751 -93.613343)
			(xy 270.716401 -93.570994) (xy 270.647409 -93.521865) (xy 270.583399 -93.4664) (xy 270.524951 -93.405102)
			(xy 270.472595 -93.338526) (xy 270.426805 -93.267274) (xy 270.387994 -93.191993) (xy 270.356515 -93.113363)
			(xy 270.332654 -93.032096) (xy 270.316625 -92.94893) (xy 270.308574 -92.864616) (xy 243.072554 -92.864616)
			(xy 243.078005 -92.921281) (xy 243.078508 -92.964) (xy 243.078033 -93.005102) (xy 243.070448 -93.086957)
			(xy 243.055343 -93.167762) (xy 243.032847 -93.246829) (xy 243.003151 -93.323483) (xy 242.966509 -93.39707)
			(xy 242.923234 -93.466962) (xy 242.873694 -93.532563) (xy 242.818313 -93.593313) (xy 242.757563 -93.648694)
			(xy 242.691962 -93.698234) (xy 242.62207 -93.741509) (xy 242.548483 -93.778151) (xy 242.471829 -93.807847)
			(xy 242.392762 -93.830343) (xy 242.311957 -93.845448) (xy 242.230102 -93.853033) (xy 242.189 -93.853508)
			(xy 242.142604 -93.852923) (xy 242.050314 -93.84329) (xy 241.959529 -93.824097) (xy 241.871236 -93.795553)
			(xy 241.828574 -93.777308) (xy 241.818634 -93.773488) (xy 241.797366 -93.773488) (xy 241.787426 -93.777308)
			(xy 241.744761 -93.795546) (xy 241.656468 -93.824084) (xy 241.565684 -93.84328) (xy 241.473396 -93.852925)
			(xy 241.427 -93.853508) (xy 241.384979 -93.85302) (xy 241.301311 -93.845093) (xy 241.218763 -93.829309)
			(xy 241.138073 -93.80581) (xy 241.098832 -93.79077) (xy 241.09438 -93.789103) (xy 241.085043 -93.787314)
			(xy 241.08029 -93.787214) (xy 240.12271 -93.787214) (xy 240.117961 -93.787355) (xy 240.108633 -93.789146)
			(xy 240.104168 -93.79077) (xy 240.064929 -93.805815) (xy 239.984237 -93.829308) (xy 239.901689 -93.845087)
			(xy 239.818021 -93.853012) (xy 239.733979 -93.853012) (xy 239.650311 -93.845087) (xy 239.567763 -93.829308)
			(xy 239.487071 -93.805815) (xy 239.447832 -93.79077) (xy 239.438942 -93.787214) (xy 239.351058 -93.787214)
			(xy 239.342168 -93.79077) (xy 239.302929 -93.805815) (xy 239.222237 -93.829308) (xy 239.139689 -93.845087)
			(xy 239.056021 -93.853012) (xy 238.971979 -93.853012) (xy 238.888311 -93.845087) (xy 238.805763 -93.829308)
			(xy 238.725071 -93.805815) (xy 238.685832 -93.79077) (xy 238.68138 -93.789103) (xy 238.672043 -93.787314)
			(xy 238.66729 -93.787214) (xy 237.70971 -93.787214) (xy 237.704961 -93.787355) (xy 237.695633 -93.789146)
			(xy 237.691168 -93.79077) (xy 237.651929 -93.805815) (xy 237.571237 -93.829308) (xy 237.488689 -93.845087)
			(xy 237.405021 -93.853012) (xy 237.320979 -93.853012) (xy 237.237311 -93.845087) (xy 237.154763 -93.829308)
			(xy 237.074071 -93.805815) (xy 237.034832 -93.79077) (xy 237.025942 -93.787214) (xy 236.938058 -93.787214)
			(xy 236.929168 -93.79077) (xy 236.889929 -93.805815) (xy 236.809237 -93.829308) (xy 236.726689 -93.845087)
			(xy 236.643021 -93.853012) (xy 236.558979 -93.853012) (xy 236.475311 -93.845087) (xy 236.392763 -93.829308)
			(xy 236.312071 -93.805815) (xy 236.272832 -93.79077) (xy 236.26838 -93.789103) (xy 236.259043 -93.787314)
			(xy 236.25429 -93.787214) (xy 235.29671 -93.787214) (xy 235.291961 -93.787355) (xy 235.282633 -93.789146)
			(xy 235.278168 -93.79077) (xy 235.238929 -93.805815) (xy 235.158237 -93.829308) (xy 235.075689 -93.845087)
			(xy 234.992021 -93.853012) (xy 234.907979 -93.853012) (xy 234.824311 -93.845087) (xy 234.741763 -93.829308)
			(xy 234.661071 -93.805815) (xy 234.621832 -93.79077) (xy 234.612942 -93.787214) (xy 234.525058 -93.787214)
			(xy 234.516168 -93.79077) (xy 234.476929 -93.805815) (xy 234.396237 -93.829308) (xy 234.313689 -93.845087)
			(xy 234.230021 -93.853012) (xy 234.145979 -93.853012) (xy 234.062311 -93.845087) (xy 233.979763 -93.829308)
			(xy 233.899071 -93.805815) (xy 233.859832 -93.79077) (xy 233.85538 -93.789103) (xy 233.846043 -93.787314)
			(xy 233.84129 -93.787214) (xy 232.88371 -93.787214) (xy 232.878961 -93.787355) (xy 232.869633 -93.789146)
			(xy 232.865168 -93.79077) (xy 232.825929 -93.805815) (xy 232.745237 -93.829308) (xy 232.662689 -93.845087)
			(xy 232.579021 -93.853012) (xy 232.494979 -93.853012) (xy 232.411311 -93.845087) (xy 232.328763 -93.829308)
			(xy 232.248071 -93.805815) (xy 232.208832 -93.79077) (xy 232.199942 -93.787214) (xy 232.112058 -93.787214)
			(xy 232.103168 -93.79077) (xy 232.063929 -93.805815) (xy 231.983237 -93.829308) (xy 231.900689 -93.845087)
			(xy 231.817021 -93.853012) (xy 231.732979 -93.853012) (xy 231.649311 -93.845087) (xy 231.566763 -93.829308)
			(xy 231.486071 -93.805815) (xy 231.446832 -93.79077) (xy 231.44238 -93.789103) (xy 231.433043 -93.787314)
			(xy 231.42829 -93.787214) (xy 230.47071 -93.787214) (xy 230.465961 -93.787355) (xy 230.456633 -93.789146)
			(xy 230.452168 -93.79077) (xy 230.412929 -93.805815) (xy 230.332237 -93.829308) (xy 230.249689 -93.845087)
			(xy 230.166021 -93.853012) (xy 230.081979 -93.853012) (xy 229.998311 -93.845087) (xy 229.915763 -93.829308)
			(xy 229.835071 -93.805815) (xy 229.795832 -93.79077) (xy 229.786942 -93.787214) (xy 229.699058 -93.787214)
			(xy 229.690168 -93.79077) (xy 229.650929 -93.805815) (xy 229.570237 -93.829308) (xy 229.487689 -93.845087)
			(xy 229.404021 -93.853012) (xy 229.319979 -93.853012) (xy 229.236311 -93.845087) (xy 229.153763 -93.829308)
			(xy 229.073071 -93.805815) (xy 229.033832 -93.79077) (xy 229.02938 -93.789103) (xy 229.020043 -93.787314)
			(xy 229.01529 -93.787214) (xy 228.05771 -93.787214) (xy 228.052961 -93.787355) (xy 228.043633 -93.789146)
			(xy 228.039168 -93.79077) (xy 227.999929 -93.805815) (xy 227.919237 -93.829308) (xy 227.836689 -93.845087)
			(xy 227.753021 -93.853012) (xy 227.668979 -93.853012) (xy 227.585311 -93.845087) (xy 227.502763 -93.829308)
			(xy 227.422071 -93.805815) (xy 227.382832 -93.79077) (xy 227.373942 -93.787214) (xy 227.286058 -93.787214)
			(xy 227.277168 -93.79077) (xy 227.237929 -93.805815) (xy 227.157237 -93.829308) (xy 227.074689 -93.845087)
			(xy 226.991021 -93.853012) (xy 226.906979 -93.853012) (xy 226.823311 -93.845087) (xy 226.740763 -93.829308)
			(xy 226.660071 -93.805815) (xy 226.620832 -93.79077) (xy 226.61638 -93.789103) (xy 226.607043 -93.787314)
			(xy 226.60229 -93.787214) (xy 225.64471 -93.787214) (xy 225.639961 -93.787355) (xy 225.630633 -93.789146)
			(xy 225.626168 -93.79077) (xy 225.586929 -93.805815) (xy 225.506237 -93.829308) (xy 225.423689 -93.845087)
			(xy 225.340021 -93.853012) (xy 225.255979 -93.853012) (xy 225.172311 -93.845087) (xy 225.089763 -93.829308)
			(xy 225.009071 -93.805815) (xy 224.969832 -93.79077) (xy 224.960942 -93.787214) (xy 224.873058 -93.787214)
			(xy 224.864168 -93.79077) (xy 224.824929 -93.805815) (xy 224.744237 -93.829308) (xy 224.661689 -93.845087)
			(xy 224.578021 -93.853012) (xy 224.493979 -93.853012) (xy 224.410311 -93.845087) (xy 224.327763 -93.829308)
			(xy 224.247071 -93.805815) (xy 224.207832 -93.79077) (xy 224.20338 -93.789103) (xy 224.194043 -93.787314)
			(xy 224.18929 -93.787214) (xy 223.23171 -93.787214) (xy 223.226961 -93.787355) (xy 223.217633 -93.789146)
			(xy 223.213168 -93.79077) (xy 223.173929 -93.805815) (xy 223.093237 -93.829308) (xy 223.010689 -93.845087)
			(xy 222.927021 -93.853012) (xy 222.842979 -93.853012) (xy 222.759311 -93.845087) (xy 222.676763 -93.829308)
			(xy 222.596071 -93.805815) (xy 222.556832 -93.79077) (xy 222.547942 -93.787214) (xy 222.460058 -93.787214)
			(xy 222.451168 -93.79077) (xy 222.411929 -93.805815) (xy 222.331237 -93.829308) (xy 222.248689 -93.845087)
			(xy 222.165021 -93.853012) (xy 222.080979 -93.853012) (xy 221.997311 -93.845087) (xy 221.914763 -93.829308)
			(xy 221.834071 -93.805815) (xy 221.794832 -93.79077) (xy 221.79038 -93.789103) (xy 221.781043 -93.787314)
			(xy 221.77629 -93.787214) (xy 220.94571 -93.787214) (xy 220.940961 -93.787355) (xy 220.931633 -93.789146)
			(xy 220.927168 -93.79077) (xy 220.887929 -93.805815) (xy 220.807237 -93.829308) (xy 220.724689 -93.845087)
			(xy 220.641021 -93.853012) (xy 220.556979 -93.853012) (xy 220.473311 -93.845087) (xy 220.390763 -93.829308)
			(xy 220.310071 -93.805815) (xy 220.270832 -93.79077) (xy 220.261942 -93.787214) (xy 220.174058 -93.787214)
			(xy 220.165168 -93.79077) (xy 220.125929 -93.805815) (xy 220.045237 -93.829308) (xy 219.962689 -93.845087)
			(xy 219.879021 -93.853012) (xy 219.794979 -93.853012) (xy 219.711311 -93.845087) (xy 219.628763 -93.829308)
			(xy 219.548071 -93.805815) (xy 219.508832 -93.79077) (xy 219.50438 -93.789103) (xy 219.495043 -93.787314)
			(xy 219.49029 -93.787214) (xy 218.65971 -93.787214) (xy 218.654961 -93.787355) (xy 218.645633 -93.789146)
			(xy 218.641168 -93.79077) (xy 218.601929 -93.805815) (xy 218.521237 -93.829308) (xy 218.438689 -93.845087)
			(xy 218.355021 -93.853012) (xy 218.270979 -93.853012) (xy 218.187311 -93.845087) (xy 218.104763 -93.829308)
			(xy 218.024071 -93.805815) (xy 217.984832 -93.79077) (xy 217.975942 -93.787214) (xy 217.888058 -93.787214)
			(xy 217.879168 -93.79077) (xy 217.839929 -93.805815) (xy 217.759237 -93.829308) (xy 217.676689 -93.845087)
			(xy 217.593021 -93.853012) (xy 217.508979 -93.853012) (xy 217.425311 -93.845087) (xy 217.342763 -93.829308)
			(xy 217.262071 -93.805815) (xy 217.222832 -93.79077) (xy 217.21838 -93.789103) (xy 217.209043 -93.787314)
			(xy 217.20429 -93.787214) (xy 216.37371 -93.787214) (xy 216.368961 -93.787355) (xy 216.359633 -93.789146)
			(xy 216.355168 -93.79077) (xy 216.315929 -93.805815) (xy 216.235237 -93.829308) (xy 216.152689 -93.845087)
			(xy 216.069021 -93.853012) (xy 215.984979 -93.853012) (xy 215.901311 -93.845087) (xy 215.818763 -93.829308)
			(xy 215.738071 -93.805815) (xy 215.698832 -93.79077) (xy 215.689942 -93.787214) (xy 215.602058 -93.787214)
			(xy 215.593168 -93.79077) (xy 215.553929 -93.805815) (xy 215.473237 -93.829308) (xy 215.390689 -93.845087)
			(xy 215.307021 -93.853012) (xy 215.222979 -93.853012) (xy 215.139311 -93.845087) (xy 215.056763 -93.829308)
			(xy 214.976071 -93.805815) (xy 214.936832 -93.79077) (xy 214.93238 -93.789103) (xy 214.923043 -93.787314)
			(xy 214.91829 -93.787214) (xy 190.582042 -93.787214) (xy 190.573764 -93.787541) (xy 190.55809 -93.792868)
			(xy 190.551308 -93.797628) (xy 190.518065 -93.822443) (xy 190.447754 -93.866476) (xy 190.373647 -93.90377)
			(xy 190.296391 -93.934003) (xy 190.216654 -93.95691) (xy 190.135132 -93.972292) (xy 190.052531 -93.980017)
			(xy 189.969569 -93.980017) (xy 189.886968 -93.972292) (xy 189.805446 -93.95691) (xy 189.725709 -93.934003)
			(xy 189.648453 -93.90377) (xy 189.574346 -93.866476) (xy 189.504035 -93.822443) (xy 189.470792 -93.797628)
			(xy 189.464011 -93.792869) (xy 189.448335 -93.787543) (xy 189.440058 -93.787214) (xy 158.768796 -93.787214)
			(xy 158.758726 -93.786791) (xy 158.740121 -93.779077) (xy 158.732728 -93.772228) (xy 148.858986 -83.898486)
			(xy 148.851591 -83.891632) (xy 148.832992 -83.88389) (xy 148.822918 -83.8835) (xy 38.044882 -83.8835)
			(xy 38.034813 -83.883927) (xy 38.016214 -83.891646) (xy 38.008814 -83.898486) (xy 37.886386 -84.020914)
			(xy 37.879532 -84.028309) (xy 37.87179 -84.046908) (xy 37.8714 -84.056982) (xy 37.8714 -86.542556)
			(xy 43.120306 -86.542556) (xy 43.120306 -86.45786) (xy 43.128357 -86.373546) (xy 43.144386 -86.29038)
			(xy 43.168247 -86.209113) (xy 43.199726 -86.130483) (xy 43.238537 -86.055202) (xy 43.284327 -85.98395)
			(xy 43.336683 -85.917374) (xy 43.395131 -85.856076) (xy 43.459141 -85.800611) (xy 43.528133 -85.751482)
			(xy 43.601483 -85.709133) (xy 43.678526 -85.673949) (xy 43.758565 -85.646247) (xy 43.840874 -85.626279)
			(xy 43.924709 -85.614226) (xy 44.00931 -85.610196) (xy 44.093911 -85.614226) (xy 44.177746 -85.626279)
			(xy 44.260055 -85.646247) (xy 44.340094 -85.673949) (xy 44.417137 -85.709133) (xy 44.490487 -85.751482)
			(xy 44.559479 -85.800611) (xy 44.623489 -85.856076) (xy 44.681937 -85.917374) (xy 44.734293 -85.98395)
			(xy 44.780083 -86.055202) (xy 44.818894 -86.130483) (xy 44.850373 -86.209113) (xy 44.874234 -86.29038)
			(xy 44.890263 -86.373546) (xy 44.898314 -86.45786) (xy 44.898675 -86.4882) (xy 72.953876 -86.4882)
			(xy 72.953876 -86.403504) (xy 72.961927 -86.31919) (xy 72.977956 -86.236024) (xy 73.001817 -86.154757)
			(xy 73.033296 -86.076127) (xy 73.072107 -86.000846) (xy 73.117897 -85.929594) (xy 73.170253 -85.863018)
			(xy 73.228701 -85.80172) (xy 73.292711 -85.746255) (xy 73.361703 -85.697126) (xy 73.435053 -85.654777)
			(xy 73.512096 -85.619593) (xy 73.592135 -85.591891) (xy 73.674444 -85.571923) (xy 73.758279 -85.55987)
			(xy 73.84288 -85.55584) (xy 73.927481 -85.55987) (xy 74.011316 -85.571923) (xy 74.093625 -85.591891)
			(xy 74.173664 -85.619593) (xy 74.250707 -85.654777) (xy 74.324057 -85.697126) (xy 74.393049 -85.746255)
			(xy 74.457059 -85.80172) (xy 74.515507 -85.863018) (xy 74.567863 -85.929594) (xy 74.613653 -86.000846)
			(xy 74.652464 -86.076127) (xy 74.683943 -86.154757) (xy 74.707804 -86.236024) (xy 74.723833 -86.31919)
			(xy 74.731884 -86.403504) (xy 74.732388 -86.445852) (xy 74.731884 -86.4882) (xy 74.726694 -86.542556)
			(xy 78.75803 -86.542556) (xy 78.75803 -86.45786) (xy 78.766081 -86.373546) (xy 78.78211 -86.29038)
			(xy 78.805971 -86.209113) (xy 78.83745 -86.130483) (xy 78.876261 -86.055202) (xy 78.922051 -85.98395)
			(xy 78.974407 -85.917374) (xy 79.032855 -85.856076) (xy 79.096865 -85.800611) (xy 79.165857 -85.751482)
			(xy 79.239207 -85.709133) (xy 79.31625 -85.673949) (xy 79.396289 -85.646247) (xy 79.478598 -85.626279)
			(xy 79.562433 -85.614226) (xy 79.647034 -85.610196) (xy 79.731635 -85.614226) (xy 79.81547 -85.626279)
			(xy 79.897779 -85.646247) (xy 79.977818 -85.673949) (xy 80.054861 -85.709133) (xy 80.128211 -85.751482)
			(xy 80.197203 -85.800611) (xy 80.261213 -85.856076) (xy 80.319661 -85.917374) (xy 80.372017 -85.98395)
			(xy 80.417807 -86.055202) (xy 80.456618 -86.130483) (xy 80.488097 -86.209113) (xy 80.511958 -86.29038)
			(xy 80.527987 -86.373546) (xy 80.536038 -86.45786) (xy 80.536402 -86.488454) (xy 112.713766 -86.488454)
			(xy 112.713766 -86.403758) (xy 112.721817 -86.319444) (xy 112.737846 -86.236278) (xy 112.761707 -86.155011)
			(xy 112.793186 -86.076381) (xy 112.831997 -86.0011) (xy 112.877787 -85.929848) (xy 112.930143 -85.863272)
			(xy 112.988591 -85.801974) (xy 113.052601 -85.746509) (xy 113.121593 -85.69738) (xy 113.194943 -85.655031)
			(xy 113.271986 -85.619847) (xy 113.352025 -85.592145) (xy 113.434334 -85.572177) (xy 113.518169 -85.560124)
			(xy 113.60277 -85.556094) (xy 113.687371 -85.560124) (xy 113.771206 -85.572177) (xy 113.853515 -85.592145)
			(xy 113.933554 -85.619847) (xy 114.010597 -85.655031) (xy 114.083947 -85.69738) (xy 114.152939 -85.746509)
			(xy 114.216949 -85.801974) (xy 114.275397 -85.863272) (xy 114.327753 -85.929848) (xy 114.373543 -86.0011)
			(xy 114.412354 -86.076381) (xy 114.443833 -86.155011) (xy 114.467694 -86.236278) (xy 114.483723 -86.319444)
			(xy 114.491774 -86.403758) (xy 114.492278 -86.446106) (xy 114.491774 -86.488454) (xy 119.277126 -86.488454)
			(xy 119.277126 -86.403758) (xy 119.285177 -86.319444) (xy 119.301206 -86.236278) (xy 119.325067 -86.155011)
			(xy 119.356546 -86.076381) (xy 119.395357 -86.0011) (xy 119.441147 -85.929848) (xy 119.493503 -85.863272)
			(xy 119.551951 -85.801974) (xy 119.615961 -85.746509) (xy 119.684953 -85.69738) (xy 119.758303 -85.655031)
			(xy 119.835346 -85.619847) (xy 119.915385 -85.592145) (xy 119.997694 -85.572177) (xy 120.081529 -85.560124)
			(xy 120.16613 -85.556094) (xy 120.250731 -85.560124) (xy 120.334566 -85.572177) (xy 120.416875 -85.592145)
			(xy 120.496914 -85.619847) (xy 120.573957 -85.655031) (xy 120.647307 -85.69738) (xy 120.716299 -85.746509)
			(xy 120.780309 -85.801974) (xy 120.838757 -85.863272) (xy 120.891113 -85.929848) (xy 120.936903 -86.0011)
			(xy 120.975714 -86.076381) (xy 121.007193 -86.155011) (xy 121.031054 -86.236278) (xy 121.047083 -86.319444)
			(xy 121.055134 -86.403758) (xy 121.055638 -86.446106) (xy 121.055134 -86.488454) (xy 137.556998 -86.488454)
			(xy 137.556998 -86.403758) (xy 137.565049 -86.319444) (xy 137.581078 -86.236278) (xy 137.604939 -86.155011)
			(xy 137.636418 -86.076381) (xy 137.675229 -86.0011) (xy 137.721019 -85.929848) (xy 137.773375 -85.863272)
			(xy 137.831823 -85.801974) (xy 137.895833 -85.746509) (xy 137.964825 -85.69738) (xy 138.038175 -85.655031)
			(xy 138.115218 -85.619847) (xy 138.195257 -85.592145) (xy 138.277566 -85.572177) (xy 138.361401 -85.560124)
			(xy 138.446002 -85.556094) (xy 138.530603 -85.560124) (xy 138.614438 -85.572177) (xy 138.696747 -85.592145)
			(xy 138.776786 -85.619847) (xy 138.853829 -85.655031) (xy 138.927179 -85.69738) (xy 138.996171 -85.746509)
			(xy 139.060181 -85.801974) (xy 139.118629 -85.863272) (xy 139.170985 -85.929848) (xy 139.216775 -86.0011)
			(xy 139.255586 -86.076381) (xy 139.287065 -86.155011) (xy 139.310926 -86.236278) (xy 139.326955 -86.319444)
			(xy 139.335006 -86.403758) (xy 139.33551 -86.446106) (xy 139.335006 -86.488454) (xy 139.326955 -86.572768)
			(xy 139.310926 -86.655934) (xy 139.287065 -86.737201) (xy 139.255586 -86.815831) (xy 139.216775 -86.891112)
			(xy 139.170985 -86.962364) (xy 139.118629 -87.02894) (xy 139.060181 -87.090238) (xy 138.996171 -87.145703)
			(xy 138.927179 -87.194832) (xy 138.853829 -87.237181) (xy 138.776786 -87.272365) (xy 138.696747 -87.300067)
			(xy 138.614438 -87.320035) (xy 138.530603 -87.332088) (xy 138.446002 -87.336119) (xy 138.361401 -87.332088)
			(xy 138.277566 -87.320035) (xy 138.195257 -87.300067) (xy 138.115218 -87.272365) (xy 138.038175 -87.237181)
			(xy 137.964825 -87.194832) (xy 137.895833 -87.145703) (xy 137.831823 -87.090238) (xy 137.773375 -87.02894)
			(xy 137.721019 -86.962364) (xy 137.675229 -86.891112) (xy 137.636418 -86.815831) (xy 137.604939 -86.737201)
			(xy 137.581078 -86.655934) (xy 137.565049 -86.572768) (xy 137.556998 -86.488454) (xy 121.055134 -86.488454)
			(xy 121.047083 -86.572768) (xy 121.031054 -86.655934) (xy 121.007193 -86.737201) (xy 120.975714 -86.815831)
			(xy 120.936903 -86.891112) (xy 120.891113 -86.962364) (xy 120.838757 -87.02894) (xy 120.780309 -87.090238)
			(xy 120.716299 -87.145703) (xy 120.647307 -87.194832) (xy 120.573957 -87.237181) (xy 120.496914 -87.272365)
			(xy 120.416875 -87.300067) (xy 120.334566 -87.320035) (xy 120.250731 -87.332088) (xy 120.16613 -87.336119)
			(xy 120.081529 -87.332088) (xy 119.997694 -87.320035) (xy 119.915385 -87.300067) (xy 119.835346 -87.272365)
			(xy 119.758303 -87.237181) (xy 119.684953 -87.194832) (xy 119.615961 -87.145703) (xy 119.551951 -87.090238)
			(xy 119.493503 -87.02894) (xy 119.441147 -86.962364) (xy 119.395357 -86.891112) (xy 119.356546 -86.815831)
			(xy 119.325067 -86.737201) (xy 119.301206 -86.655934) (xy 119.285177 -86.572768) (xy 119.277126 -86.488454)
			(xy 114.491774 -86.488454) (xy 114.483723 -86.572768) (xy 114.467694 -86.655934) (xy 114.443833 -86.737201)
			(xy 114.412354 -86.815831) (xy 114.373543 -86.891112) (xy 114.327753 -86.962364) (xy 114.275397 -87.02894)
			(xy 114.216949 -87.090238) (xy 114.152939 -87.145703) (xy 114.083947 -87.194832) (xy 114.010597 -87.237181)
			(xy 113.933554 -87.272365) (xy 113.853515 -87.300067) (xy 113.771206 -87.320035) (xy 113.687371 -87.332088)
			(xy 113.60277 -87.336119) (xy 113.518169 -87.332088) (xy 113.434334 -87.320035) (xy 113.352025 -87.300067)
			(xy 113.271986 -87.272365) (xy 113.194943 -87.237181) (xy 113.121593 -87.194832) (xy 113.052601 -87.145703)
			(xy 112.988591 -87.090238) (xy 112.930143 -87.02894) (xy 112.877787 -86.962364) (xy 112.831997 -86.891112)
			(xy 112.793186 -86.815831) (xy 112.761707 -86.737201) (xy 112.737846 -86.655934) (xy 112.721817 -86.572768)
			(xy 112.713766 -86.488454) (xy 80.536402 -86.488454) (xy 80.536542 -86.500208) (xy 80.536038 -86.542556)
			(xy 80.527987 -86.62687) (xy 80.511958 -86.710036) (xy 80.488097 -86.791303) (xy 80.456618 -86.869933)
			(xy 80.417807 -86.945214) (xy 80.372017 -87.016466) (xy 80.319661 -87.083042) (xy 80.261213 -87.14434)
			(xy 80.197203 -87.199805) (xy 80.128211 -87.248934) (xy 80.054861 -87.291283) (xy 79.977818 -87.326467)
			(xy 79.897779 -87.354169) (xy 79.81547 -87.374137) (xy 79.731635 -87.38619) (xy 79.647034 -87.390221)
			(xy 79.562433 -87.38619) (xy 79.478598 -87.374137) (xy 79.396289 -87.354169) (xy 79.31625 -87.326467)
			(xy 79.239207 -87.291283) (xy 79.165857 -87.248934) (xy 79.096865 -87.199805) (xy 79.032855 -87.14434)
			(xy 78.974407 -87.083042) (xy 78.922051 -87.016466) (xy 78.876261 -86.945214) (xy 78.83745 -86.869933)
			(xy 78.805971 -86.791303) (xy 78.78211 -86.710036) (xy 78.766081 -86.62687) (xy 78.75803 -86.542556)
			(xy 74.726694 -86.542556) (xy 74.723833 -86.572514) (xy 74.707804 -86.65568) (xy 74.683943 -86.736947)
			(xy 74.652464 -86.815577) (xy 74.613653 -86.890858) (xy 74.567863 -86.96211) (xy 74.515507 -87.028686)
			(xy 74.457059 -87.089984) (xy 74.393049 -87.145449) (xy 74.324057 -87.194578) (xy 74.250707 -87.236927)
			(xy 74.173664 -87.272111) (xy 74.093625 -87.299813) (xy 74.011316 -87.319781) (xy 73.927481 -87.331834)
			(xy 73.84288 -87.335865) (xy 73.758279 -87.331834) (xy 73.674444 -87.319781) (xy 73.592135 -87.299813)
			(xy 73.512096 -87.272111) (xy 73.435053 -87.236927) (xy 73.361703 -87.194578) (xy 73.292711 -87.145449)
			(xy 73.228701 -87.089984) (xy 73.170253 -87.028686) (xy 73.117897 -86.96211) (xy 73.072107 -86.890858)
			(xy 73.033296 -86.815577) (xy 73.001817 -86.736947) (xy 72.977956 -86.65568) (xy 72.961927 -86.572514)
			(xy 72.953876 -86.4882) (xy 44.898675 -86.4882) (xy 44.898818 -86.500208) (xy 44.898314 -86.542556)
			(xy 44.890263 -86.62687) (xy 44.874234 -86.710036) (xy 44.850373 -86.791303) (xy 44.818894 -86.869933)
			(xy 44.780083 -86.945214) (xy 44.734293 -87.016466) (xy 44.681937 -87.083042) (xy 44.623489 -87.14434)
			(xy 44.559479 -87.199805) (xy 44.490487 -87.248934) (xy 44.417137 -87.291283) (xy 44.340094 -87.326467)
			(xy 44.260055 -87.354169) (xy 44.177746 -87.374137) (xy 44.093911 -87.38619) (xy 44.00931 -87.390221)
			(xy 43.924709 -87.38619) (xy 43.840874 -87.374137) (xy 43.758565 -87.354169) (xy 43.678526 -87.326467)
			(xy 43.601483 -87.291283) (xy 43.528133 -87.248934) (xy 43.459141 -87.199805) (xy 43.395131 -87.14434)
			(xy 43.336683 -87.083042) (xy 43.284327 -87.016466) (xy 43.238537 -86.945214) (xy 43.199726 -86.869933)
			(xy 43.168247 -86.791303) (xy 43.144386 -86.710036) (xy 43.128357 -86.62687) (xy 43.120306 -86.542556)
			(xy 37.8714 -86.542556) (xy 37.8714 -103.401298) (xy 271.98726 -103.401298) (xy 271.98726 -103.316602)
			(xy 271.995311 -103.232288) (xy 272.01134 -103.149122) (xy 272.035201 -103.067855) (xy 272.06668 -102.989225)
			(xy 272.105491 -102.913944) (xy 272.151281 -102.842692) (xy 272.203637 -102.776116) (xy 272.262085 -102.714818)
			(xy 272.326095 -102.659353) (xy 272.395087 -102.610224) (xy 272.468437 -102.567875) (xy 272.54548 -102.532691)
			(xy 272.625519 -102.504989) (xy 272.707828 -102.485021) (xy 272.791663 -102.472968) (xy 272.876264 -102.468938)
			(xy 272.960865 -102.472968) (xy 273.0447 -102.485021) (xy 273.127009 -102.504989) (xy 273.207048 -102.532691)
			(xy 273.284091 -102.567875) (xy 273.357441 -102.610224) (xy 273.426433 -102.659353) (xy 273.490443 -102.714818)
			(xy 273.548891 -102.776116) (xy 273.601247 -102.842692) (xy 273.647037 -102.913944) (xy 273.685848 -102.989225)
			(xy 273.717327 -103.067855) (xy 273.741188 -103.149122) (xy 273.757217 -103.232288) (xy 273.765268 -103.316602)
			(xy 273.765772 -103.35895) (xy 273.765268 -103.401298) (xy 273.757217 -103.485612) (xy 273.741188 -103.568778)
			(xy 273.717327 -103.650045) (xy 273.685848 -103.728675) (xy 273.647037 -103.803956) (xy 273.601247 -103.875208)
			(xy 273.548891 -103.941784) (xy 273.490443 -104.003082) (xy 273.426433 -104.058547) (xy 273.357441 -104.107676)
			(xy 273.284091 -104.150025) (xy 273.207048 -104.185209) (xy 273.127009 -104.212911) (xy 273.0447 -104.232879)
			(xy 272.960865 -104.244932) (xy 272.876264 -104.248963) (xy 272.791663 -104.244932) (xy 272.707828 -104.232879)
			(xy 272.625519 -104.212911) (xy 272.54548 -104.185209) (xy 272.468437 -104.150025) (xy 272.395087 -104.107676)
			(xy 272.326095 -104.058547) (xy 272.262085 -104.003082) (xy 272.203637 -103.941784) (xy 272.151281 -103.875208)
			(xy 272.105491 -103.803956) (xy 272.06668 -103.728675) (xy 272.035201 -103.650045) (xy 272.01134 -103.568778)
			(xy 271.995311 -103.485612) (xy 271.98726 -103.401298) (xy 37.8714 -103.401298) (xy 37.8714 -104.929616)
			(xy 270.26387 -104.929616) (xy 270.26387 -104.84492) (xy 270.271921 -104.760606) (xy 270.28795 -104.67744)
			(xy 270.311811 -104.596173) (xy 270.34329 -104.517543) (xy 270.382101 -104.442262) (xy 270.427891 -104.37101)
			(xy 270.480247 -104.304434) (xy 270.538695 -104.243136) (xy 270.602705 -104.187671) (xy 270.671697 -104.138542)
			(xy 270.745047 -104.096193) (xy 270.82209 -104.061009) (xy 270.902129 -104.033307) (xy 270.984438 -104.013339)
			(xy 271.068273 -104.001286) (xy 271.152874 -103.997256) (xy 271.237475 -104.001286) (xy 271.32131 -104.013339)
			(xy 271.403619 -104.033307) (xy 271.483658 -104.061009) (xy 271.560701 -104.096193) (xy 271.634051 -104.138542)
			(xy 271.703043 -104.187671) (xy 271.767053 -104.243136) (xy 271.825501 -104.304434) (xy 271.877857 -104.37101)
			(xy 271.923647 -104.442262) (xy 271.962458 -104.517543) (xy 271.993937 -104.596173) (xy 272.017798 -104.67744)
			(xy 272.033827 -104.760606) (xy 272.041878 -104.84492) (xy 272.042382 -104.887268) (xy 272.041878 -104.929616)
			(xy 272.033827 -105.01393) (xy 272.017798 -105.097096) (xy 271.993937 -105.178363) (xy 271.962458 -105.256993)
			(xy 271.923647 -105.332274) (xy 271.877857 -105.403526) (xy 271.825501 -105.470102) (xy 271.767053 -105.5314)
			(xy 271.703043 -105.586865) (xy 271.634051 -105.635994) (xy 271.560701 -105.678343) (xy 271.483658 -105.713527)
			(xy 271.403619 -105.741229) (xy 271.32131 -105.761197) (xy 271.237475 -105.77325) (xy 271.152874 -105.777281)
			(xy 271.068273 -105.77325) (xy 270.984438 -105.761197) (xy 270.902129 -105.741229) (xy 270.82209 -105.713527)
			(xy 270.745047 -105.678343) (xy 270.671697 -105.635994) (xy 270.602705 -105.586865) (xy 270.538695 -105.5314)
			(xy 270.480247 -105.470102) (xy 270.427891 -105.403526) (xy 270.382101 -105.332274) (xy 270.34329 -105.256993)
			(xy 270.311811 -105.178363) (xy 270.28795 -105.097096) (xy 270.271921 -105.01393) (xy 270.26387 -104.929616)
			(xy 37.8714 -104.929616) (xy 37.8714 -106.402816) (xy 268.600932 -106.402816) (xy 268.600932 -106.31812)
			(xy 268.608983 -106.233806) (xy 268.625012 -106.15064) (xy 268.648873 -106.069373) (xy 268.680352 -105.990743)
			(xy 268.719163 -105.915462) (xy 268.764953 -105.84421) (xy 268.817309 -105.777634) (xy 268.875757 -105.716336)
			(xy 268.939767 -105.660871) (xy 269.008759 -105.611742) (xy 269.082109 -105.569393) (xy 269.159152 -105.534209)
			(xy 269.239191 -105.506507) (xy 269.3215 -105.486539) (xy 269.405335 -105.474486) (xy 269.489936 -105.470456)
			(xy 269.574537 -105.474486) (xy 269.658372 -105.486539) (xy 269.740681 -105.506507) (xy 269.82072 -105.534209)
			(xy 269.897763 -105.569393) (xy 269.971113 -105.611742) (xy 270.040105 -105.660871) (xy 270.104115 -105.716336)
			(xy 270.162563 -105.777634) (xy 270.214919 -105.84421) (xy 270.260709 -105.915462) (xy 270.29952 -105.990743)
			(xy 270.330999 -106.069373) (xy 270.35486 -106.15064) (xy 270.370889 -106.233806) (xy 270.37894 -106.31812)
			(xy 270.379444 -106.360468) (xy 270.37894 -106.402816) (xy 270.370889 -106.48713) (xy 270.35486 -106.570296)
			(xy 270.330999 -106.651563) (xy 270.29952 -106.730193) (xy 270.260709 -106.805474) (xy 270.214919 -106.876726)
			(xy 270.162563 -106.943302) (xy 270.104115 -107.0046) (xy 270.040105 -107.060065) (xy 269.971113 -107.109194)
			(xy 269.897763 -107.151543) (xy 269.82072 -107.186727) (xy 269.740681 -107.214429) (xy 269.658372 -107.234397)
			(xy 269.574537 -107.24645) (xy 269.489936 -107.250481) (xy 269.405335 -107.24645) (xy 269.3215 -107.234397)
			(xy 269.239191 -107.214429) (xy 269.159152 -107.186727) (xy 269.082109 -107.151543) (xy 269.008759 -107.109194)
			(xy 268.939767 -107.060065) (xy 268.875757 -107.0046) (xy 268.817309 -106.943302) (xy 268.764953 -106.876726)
			(xy 268.719163 -106.805474) (xy 268.680352 -106.730193) (xy 268.648873 -106.651563) (xy 268.625012 -106.570296)
			(xy 268.608983 -106.48713) (xy 268.600932 -106.402816) (xy 37.8714 -106.402816) (xy 37.8714 -113.078698)
			(xy 55.961022 -113.078698) (xy 55.961022 -112.994002) (xy 55.969073 -112.909688) (xy 55.985102 -112.826522)
			(xy 56.008963 -112.745255) (xy 56.040442 -112.666625) (xy 56.079253 -112.591344) (xy 56.125043 -112.520092)
			(xy 56.177399 -112.453516) (xy 56.235847 -112.392218) (xy 56.299857 -112.336753) (xy 56.368849 -112.287624)
			(xy 56.442199 -112.245275) (xy 56.519242 -112.210091) (xy 56.599281 -112.182389) (xy 56.68159 -112.162421)
			(xy 56.765425 -112.150368) (xy 56.850026 -112.146338) (xy 56.934627 -112.150368) (xy 57.018462 -112.162421)
			(xy 57.100771 -112.182389) (xy 57.18081 -112.210091) (xy 57.257853 -112.245275) (xy 57.331203 -112.287624)
			(xy 57.400195 -112.336753) (xy 57.464205 -112.392218) (xy 57.522653 -112.453516) (xy 57.575009 -112.520092)
			(xy 57.620799 -112.591344) (xy 57.65961 -112.666625) (xy 57.691089 -112.745255) (xy 57.71495 -112.826522)
			(xy 57.730979 -112.909688) (xy 57.73903 -112.994002) (xy 57.739534 -113.03635) (xy 57.73903 -113.078698)
			(xy 95.960942 -113.078698) (xy 95.960942 -112.994002) (xy 95.968993 -112.909688) (xy 95.985022 -112.826522)
			(xy 96.008883 -112.745255) (xy 96.040362 -112.666625) (xy 96.079173 -112.591344) (xy 96.124963 -112.520092)
			(xy 96.177319 -112.453516) (xy 96.235767 -112.392218) (xy 96.299777 -112.336753) (xy 96.368769 -112.287624)
			(xy 96.442119 -112.245275) (xy 96.519162 -112.210091) (xy 96.599201 -112.182389) (xy 96.68151 -112.162421)
			(xy 96.765345 -112.150368) (xy 96.849946 -112.146338) (xy 96.934547 -112.150368) (xy 97.018382 -112.162421)
			(xy 97.100691 -112.182389) (xy 97.18073 -112.210091) (xy 97.257773 -112.245275) (xy 97.331123 -112.287624)
			(xy 97.400115 -112.336753) (xy 97.464125 -112.392218) (xy 97.522573 -112.453516) (xy 97.574929 -112.520092)
			(xy 97.620719 -112.591344) (xy 97.65953 -112.666625) (xy 97.691009 -112.745255) (xy 97.71487 -112.826522)
			(xy 97.726023 -112.884388) (xy 108.335822 -112.884388) (xy 108.335822 -112.799692) (xy 108.343873 -112.715378)
			(xy 108.359902 -112.632212) (xy 108.383763 -112.550945) (xy 108.415242 -112.472315) (xy 108.454053 -112.397034)
			(xy 108.499843 -112.325782) (xy 108.552199 -112.259206) (xy 108.610647 -112.197908) (xy 108.674657 -112.142443)
			(xy 108.743649 -112.093314) (xy 108.816999 -112.050965) (xy 108.894042 -112.015781) (xy 108.974081 -111.988079)
			(xy 109.05639 -111.968111) (xy 109.140225 -111.956058) (xy 109.224826 -111.952028) (xy 109.309427 -111.956058)
			(xy 109.393262 -111.968111) (xy 109.475571 -111.988079) (xy 109.55561 -112.015781) (xy 109.632653 -112.050965)
			(xy 109.706003 -112.093314) (xy 109.774995 -112.142443) (xy 109.839005 -112.197908) (xy 109.897453 -112.259206)
			(xy 109.949809 -112.325782) (xy 109.995599 -112.397034) (xy 110.03441 -112.472315) (xy 110.065889 -112.550945)
			(xy 110.08975 -112.632212) (xy 110.105779 -112.715378) (xy 110.11383 -112.799692) (xy 110.114334 -112.84204)
			(xy 110.11383 -112.884388) (xy 110.105779 -112.968702) (xy 110.08975 -113.051868) (xy 110.081872 -113.078698)
			(xy 135.961116 -113.078698) (xy 135.961116 -112.994002) (xy 135.969167 -112.909688) (xy 135.985196 -112.826522)
			(xy 136.009057 -112.745255) (xy 136.040536 -112.666625) (xy 136.079347 -112.591344) (xy 136.125137 -112.520092)
			(xy 136.177493 -112.453516) (xy 136.235941 -112.392218) (xy 136.299951 -112.336753) (xy 136.368943 -112.287624)
			(xy 136.442293 -112.245275) (xy 136.519336 -112.210091) (xy 136.599375 -112.182389) (xy 136.681684 -112.162421)
			(xy 136.765519 -112.150368) (xy 136.85012 -112.146338) (xy 136.934721 -112.150368) (xy 137.018556 -112.162421)
			(xy 137.100865 -112.182389) (xy 137.180904 -112.210091) (xy 137.257947 -112.245275) (xy 137.331297 -112.287624)
			(xy 137.400289 -112.336753) (xy 137.464299 -112.392218) (xy 137.522747 -112.453516) (xy 137.575103 -112.520092)
			(xy 137.620893 -112.591344) (xy 137.659704 -112.666625) (xy 137.691183 -112.745255) (xy 137.715044 -112.826522)
			(xy 137.731073 -112.909688) (xy 137.739124 -112.994002) (xy 137.739628 -113.03635) (xy 137.739127 -113.078444)
			(xy 138.683996 -113.078444) (xy 138.683996 -112.993748) (xy 138.692047 -112.909434) (xy 138.708076 -112.826268)
			(xy 138.731937 -112.745001) (xy 138.763416 -112.666371) (xy 138.802227 -112.59109) (xy 138.848017 -112.519838)
			(xy 138.900373 -112.453262) (xy 138.958821 -112.391964) (xy 139.022831 -112.336499) (xy 139.091823 -112.28737)
			(xy 139.165173 -112.245021) (xy 139.242216 -112.209837) (xy 139.322255 -112.182135) (xy 139.404564 -112.162167)
			(xy 139.488399 -112.150114) (xy 139.573 -112.146084) (xy 139.657601 -112.150114) (xy 139.741436 -112.162167)
			(xy 139.823745 -112.182135) (xy 139.903784 -112.209837) (xy 139.980827 -112.245021) (xy 140.054177 -112.28737)
			(xy 140.123169 -112.336499) (xy 140.187179 -112.391964) (xy 140.245627 -112.453262) (xy 140.297983 -112.519838)
			(xy 140.343773 -112.59109) (xy 140.382584 -112.666371) (xy 140.414063 -112.745001) (xy 140.437924 -112.826268)
			(xy 140.440964 -112.84204) (xy 148.335492 -112.84204) (xy 148.33599 -112.800937) (xy 148.343572 -112.719083)
			(xy 148.358674 -112.638277) (xy 148.381167 -112.559209) (xy 148.41086 -112.482554) (xy 148.4475 -112.408966)
			(xy 148.490773 -112.339073) (xy 148.540311 -112.273471) (xy 148.595691 -112.212719) (xy 148.65644 -112.157337)
			(xy 148.72204 -112.107796) (xy 148.791931 -112.06452) (xy 148.865518 -112.027877) (xy 148.942171 -111.99818)
			(xy 149.021238 -111.975683) (xy 149.102043 -111.960577) (xy 149.183898 -111.952992) (xy 149.225 -111.952532)
			(xy 149.268106 -111.953076) (xy 149.353915 -111.961408) (xy 149.438514 -111.978004) (xy 149.521111 -112.002707)
			(xy 149.600931 -112.035286) (xy 149.677223 -112.075436) (xy 149.749273 -112.122779) (xy 149.816403 -112.176872)
			(xy 149.877985 -112.237206) (xy 149.93344 -112.303215) (xy 149.982248 -112.37428) (xy 150.023951 -112.449735)
			(xy 150.058158 -112.52887) (xy 150.071836 -112.569752) (xy 150.075502 -112.579781) (xy 150.089727 -112.595687)
			(xy 150.099268 -112.600486) (xy 150.137783 -112.618446) (xy 150.211541 -112.660668) (xy 150.280935 -112.709732)
			(xy 150.345334 -112.765192) (xy 150.404149 -112.826541) (xy 150.456844 -112.89322) (xy 150.502939 -112.964621)
			(xy 150.542014 -113.040093) (xy 150.55743 -113.078444) (xy 175.96129 -113.078444) (xy 175.96129 -112.993748)
			(xy 175.969341 -112.909434) (xy 175.98537 -112.826268) (xy 176.009231 -112.745001) (xy 176.04071 -112.666371)
			(xy 176.079521 -112.59109) (xy 176.125311 -112.519838) (xy 176.177667 -112.453262) (xy 176.236115 -112.391964)
			(xy 176.300125 -112.336499) (xy 176.369117 -112.28737) (xy 176.442467 -112.245021) (xy 176.51951 -112.209837)
			(xy 176.599549 -112.182135) (xy 176.681858 -112.162167) (xy 176.765693 -112.150114) (xy 176.850294 -112.146084)
			(xy 176.934895 -112.150114) (xy 177.01873 -112.162167) (xy 177.101039 -112.182135) (xy 177.181078 -112.209837)
			(xy 177.258121 -112.245021) (xy 177.331471 -112.28737) (xy 177.400463 -112.336499) (xy 177.464473 -112.391964)
			(xy 177.522921 -112.453262) (xy 177.575277 -112.519838) (xy 177.621067 -112.59109) (xy 177.659878 -112.666371)
			(xy 177.691357 -112.745001) (xy 177.715218 -112.826268) (xy 177.731247 -112.909434) (xy 177.739298 -112.993748)
			(xy 177.739802 -113.036096) (xy 177.739298 -113.078444) (xy 177.731247 -113.162758) (xy 177.715218 -113.245924)
			(xy 177.691357 -113.327191) (xy 177.659878 -113.405821) (xy 177.621067 -113.481102) (xy 177.575277 -113.552354)
			(xy 177.522921 -113.61893) (xy 177.464473 -113.680228) (xy 177.400463 -113.735693) (xy 177.331471 -113.784822)
			(xy 177.258121 -113.827171) (xy 177.181078 -113.862355) (xy 177.101039 -113.890057) (xy 177.01873 -113.910025)
			(xy 176.934895 -113.922078) (xy 176.850294 -113.926109) (xy 176.765693 -113.922078) (xy 176.681858 -113.910025)
			(xy 176.599549 -113.890057) (xy 176.51951 -113.862355) (xy 176.442467 -113.827171) (xy 176.369117 -113.784822)
			(xy 176.300125 -113.735693) (xy 176.236115 -113.680228) (xy 176.177667 -113.61893) (xy 176.125311 -113.552354)
			(xy 176.079521 -113.481102) (xy 176.04071 -113.405821) (xy 176.009231 -113.327191) (xy 175.98537 -113.245924)
			(xy 175.969341 -113.162758) (xy 175.96129 -113.078444) (xy 150.55743 -113.078444) (xy 150.573712 -113.118948)
			(xy 150.597745 -113.200467) (xy 150.613893 -113.283907) (xy 150.622008 -113.368506) (xy 150.622508 -113.411)
			(xy 150.622033 -113.452102) (xy 150.614448 -113.533957) (xy 150.599343 -113.614762) (xy 150.576847 -113.693829)
			(xy 150.547151 -113.770483) (xy 150.510509 -113.84407) (xy 150.467234 -113.913962) (xy 150.417694 -113.979563)
			(xy 150.362313 -114.040313) (xy 150.301563 -114.095694) (xy 150.235962 -114.145234) (xy 150.16607 -114.188509)
			(xy 150.092483 -114.225151) (xy 150.015829 -114.254847) (xy 149.936762 -114.277343) (xy 149.855957 -114.292448)
			(xy 149.774102 -114.300033) (xy 149.733 -114.300508) (xy 149.689895 -114.299936) (xy 149.604088 -114.291605)
			(xy 149.51949 -114.27501) (xy 149.436894 -114.250308) (xy 149.357076 -114.21773) (xy 149.280785 -114.177583)
			(xy 149.208736 -114.130242) (xy 149.141605 -114.076152) (xy 149.080023 -114.015821) (xy 149.024567 -113.949815)
			(xy 148.975757 -113.878752) (xy 148.934052 -113.803301) (xy 148.899844 -113.724168) (xy 148.886164 -113.683288)
			(xy 148.882482 -113.673266) (xy 148.868269 -113.657356) (xy 148.858732 -113.652554) (xy 148.820193 -113.634642)
			(xy 148.746434 -113.592416) (xy 148.677039 -113.543348) (xy 148.612641 -113.487884) (xy 148.553826 -113.42653)
			(xy 148.501132 -113.359847) (xy 148.455039 -113.288441) (xy 148.415966 -113.212964) (xy 148.384271 -113.134105)
			(xy 148.360243 -113.052581) (xy 148.344099 -112.969138) (xy 148.335989 -112.884535) (xy 148.335492 -112.84204)
			(xy 140.440964 -112.84204) (xy 140.453953 -112.909434) (xy 140.462004 -112.993748) (xy 140.462508 -113.036096)
			(xy 140.462004 -113.078444) (xy 140.453953 -113.162758) (xy 140.437924 -113.245924) (xy 140.414063 -113.327191)
			(xy 140.382584 -113.405821) (xy 140.343773 -113.481102) (xy 140.297983 -113.552354) (xy 140.245627 -113.61893)
			(xy 140.187179 -113.680228) (xy 140.123169 -113.735693) (xy 140.054177 -113.784822) (xy 139.980827 -113.827171)
			(xy 139.903784 -113.862355) (xy 139.823745 -113.890057) (xy 139.741436 -113.910025) (xy 139.657601 -113.922078)
			(xy 139.573 -113.926109) (xy 139.488399 -113.922078) (xy 139.404564 -113.910025) (xy 139.322255 -113.890057)
			(xy 139.242216 -113.862355) (xy 139.165173 -113.827171) (xy 139.091823 -113.784822) (xy 139.022831 -113.735693)
			(xy 138.958821 -113.680228) (xy 138.900373 -113.61893) (xy 138.848017 -113.552354) (xy 138.802227 -113.481102)
			(xy 138.763416 -113.405821) (xy 138.731937 -113.327191) (xy 138.708076 -113.245924) (xy 138.692047 -113.162758)
			(xy 138.683996 -113.078444) (xy 137.739127 -113.078444) (xy 137.739124 -113.078698) (xy 137.731073 -113.163012)
			(xy 137.715044 -113.246178) (xy 137.691183 -113.327445) (xy 137.659704 -113.406075) (xy 137.620893 -113.481356)
			(xy 137.575103 -113.552608) (xy 137.522747 -113.619184) (xy 137.464299 -113.680482) (xy 137.400289 -113.735947)
			(xy 137.331297 -113.785076) (xy 137.257947 -113.827425) (xy 137.180904 -113.862609) (xy 137.100865 -113.890311)
			(xy 137.018556 -113.910279) (xy 136.934721 -113.922332) (xy 136.85012 -113.926363) (xy 136.765519 -113.922332)
			(xy 136.681684 -113.910279) (xy 136.599375 -113.890311) (xy 136.519336 -113.862609) (xy 136.442293 -113.827425)
			(xy 136.368943 -113.785076) (xy 136.299951 -113.735947) (xy 136.235941 -113.680482) (xy 136.177493 -113.619184)
			(xy 136.125137 -113.552608) (xy 136.079347 -113.481356) (xy 136.040536 -113.406075) (xy 136.009057 -113.327445)
			(xy 135.985196 -113.246178) (xy 135.969167 -113.163012) (xy 135.961116 -113.078698) (xy 110.081872 -113.078698)
			(xy 110.065889 -113.133135) (xy 110.03441 -113.211765) (xy 109.995599 -113.287046) (xy 109.949809 -113.358298)
			(xy 109.897453 -113.424874) (xy 109.839005 -113.486172) (xy 109.774995 -113.541637) (xy 109.706003 -113.590766)
			(xy 109.632653 -113.633115) (xy 109.55561 -113.668299) (xy 109.475571 -113.696001) (xy 109.393262 -113.715969)
			(xy 109.309427 -113.728022) (xy 109.224826 -113.732053) (xy 109.140225 -113.728022) (xy 109.05639 -113.715969)
			(xy 108.974081 -113.696001) (xy 108.894042 -113.668299) (xy 108.816999 -113.633115) (xy 108.743649 -113.590766)
			(xy 108.674657 -113.541637) (xy 108.610647 -113.486172) (xy 108.552199 -113.424874) (xy 108.499843 -113.358298)
			(xy 108.454053 -113.287046) (xy 108.415242 -113.211765) (xy 108.383763 -113.133135) (xy 108.359902 -113.051868)
			(xy 108.343873 -112.968702) (xy 108.335822 -112.884388) (xy 97.726023 -112.884388) (xy 97.730899 -112.909688)
			(xy 97.73895 -112.994002) (xy 97.739454 -113.03635) (xy 97.73895 -113.078698) (xy 97.730899 -113.163012)
			(xy 97.71487 -113.246178) (xy 97.691009 -113.327445) (xy 97.65953 -113.406075) (xy 97.620719 -113.481356)
			(xy 97.574929 -113.552608) (xy 97.522573 -113.619184) (xy 97.464125 -113.680482) (xy 97.400115 -113.735947)
			(xy 97.331123 -113.785076) (xy 97.257773 -113.827425) (xy 97.18073 -113.862609) (xy 97.100691 -113.890311)
			(xy 97.018382 -113.910279) (xy 96.934547 -113.922332) (xy 96.849946 -113.926363) (xy 96.765345 -113.922332)
			(xy 96.68151 -113.910279) (xy 96.599201 -113.890311) (xy 96.519162 -113.862609) (xy 96.442119 -113.827425)
			(xy 96.368769 -113.785076) (xy 96.299777 -113.735947) (xy 96.235767 -113.680482) (xy 96.177319 -113.619184)
			(xy 96.124963 -113.552608) (xy 96.079173 -113.481356) (xy 96.040362 -113.406075) (xy 96.008883 -113.327445)
			(xy 95.985022 -113.246178) (xy 95.968993 -113.163012) (xy 95.960942 -113.078698) (xy 57.73903 -113.078698)
			(xy 57.730979 -113.163012) (xy 57.71495 -113.246178) (xy 57.691089 -113.327445) (xy 57.65961 -113.406075)
			(xy 57.620799 -113.481356) (xy 57.575009 -113.552608) (xy 57.522653 -113.619184) (xy 57.464205 -113.680482)
			(xy 57.400195 -113.735947) (xy 57.331203 -113.785076) (xy 57.257853 -113.827425) (xy 57.18081 -113.862609)
			(xy 57.100771 -113.890311) (xy 57.018462 -113.910279) (xy 56.934627 -113.922332) (xy 56.850026 -113.926363)
			(xy 56.765425 -113.922332) (xy 56.68159 -113.910279) (xy 56.599281 -113.890311) (xy 56.519242 -113.862609)
			(xy 56.442199 -113.827425) (xy 56.368849 -113.785076) (xy 56.299857 -113.735947) (xy 56.235847 -113.680482)
			(xy 56.177399 -113.619184) (xy 56.125043 -113.552608) (xy 56.079253 -113.481356) (xy 56.040442 -113.406075)
			(xy 56.008963 -113.327445) (xy 55.985102 -113.246178) (xy 55.969073 -113.163012) (xy 55.961022 -113.078698)
			(xy 37.8714 -113.078698) (xy 37.8714 -114.856698) (xy 108.843822 -114.856698) (xy 108.843822 -114.772002)
			(xy 108.851873 -114.687688) (xy 108.867902 -114.604522) (xy 108.891763 -114.523255) (xy 108.923242 -114.444625)
			(xy 108.962053 -114.369344) (xy 109.007843 -114.298092) (xy 109.060199 -114.231516) (xy 109.118647 -114.170218)
			(xy 109.182657 -114.114753) (xy 109.251649 -114.065624) (xy 109.324999 -114.023275) (xy 109.402042 -113.988091)
			(xy 109.482081 -113.960389) (xy 109.56439 -113.940421) (xy 109.648225 -113.928368) (xy 109.732826 -113.924338)
			(xy 109.817427 -113.928368) (xy 109.901262 -113.940421) (xy 109.983571 -113.960389) (xy 110.06361 -113.988091)
			(xy 110.140653 -114.023275) (xy 110.214003 -114.065624) (xy 110.282995 -114.114753) (xy 110.347005 -114.170218)
			(xy 110.405453 -114.231516) (xy 110.457809 -114.298092) (xy 110.503599 -114.369344) (xy 110.54241 -114.444625)
			(xy 110.573889 -114.523255) (xy 110.59775 -114.604522) (xy 110.613779 -114.687688) (xy 110.62183 -114.772002)
			(xy 110.622334 -114.81435) (xy 110.62183 -114.856698) (xy 110.613779 -114.941012) (xy 110.59775 -115.024178)
			(xy 110.573889 -115.105445) (xy 110.54241 -115.184075) (xy 110.503599 -115.259356) (xy 110.457809 -115.330608)
			(xy 110.405453 -115.397184) (xy 110.347005 -115.458482) (xy 110.282995 -115.513947) (xy 110.214003 -115.563076)
			(xy 110.140653 -115.605425) (xy 110.06361 -115.640609) (xy 109.983571 -115.668311) (xy 109.901262 -115.688279)
			(xy 109.817427 -115.700332) (xy 109.732826 -115.704363) (xy 109.648225 -115.700332) (xy 109.56439 -115.688279)
			(xy 109.482081 -115.668311) (xy 109.402042 -115.640609) (xy 109.324999 -115.605425) (xy 109.251649 -115.563076)
			(xy 109.182657 -115.513947) (xy 109.118647 -115.458482) (xy 109.060199 -115.397184) (xy 109.007843 -115.330608)
			(xy 108.962053 -115.259356) (xy 108.923242 -115.184075) (xy 108.891763 -115.105445) (xy 108.867902 -115.024178)
			(xy 108.851873 -114.941012) (xy 108.843822 -114.856698) (xy 37.8714 -114.856698) (xy 37.8714 -115.853718)
			(xy 37.871827 -115.863787) (xy 37.879546 -115.882386) (xy 37.886386 -115.889786) (xy 38.186614 -116.190014)
			(xy 38.194009 -116.196868) (xy 38.212608 -116.20461) (xy 38.222682 -116.205) (xy 183.209184 -116.205)
			(xy 183.219247 -116.205439) (xy 183.23783 -116.213174) (xy 183.245252 -116.219986) (xy 224.202244 -116.219986)
			(xy 224.212311 -116.220417) (xy 224.230905 -116.228141) (xy 224.238312 -116.234972) (xy 224.975096 -116.971756)
			(xy 270.314416 -116.971756) (xy 270.314416 -116.88706) (xy 270.322467 -116.802746) (xy 270.338496 -116.71958)
			(xy 270.362357 -116.638313) (xy 270.393836 -116.559683) (xy 270.432647 -116.484402) (xy 270.478437 -116.41315)
			(xy 270.530793 -116.346574) (xy 270.589241 -116.285276) (xy 270.653251 -116.229811) (xy 270.722243 -116.180682)
			(xy 270.795593 -116.138333) (xy 270.872636 -116.103149) (xy 270.952675 -116.075447) (xy 271.034984 -116.055479)
			(xy 271.118819 -116.043426) (xy 271.20342 -116.039396) (xy 271.288021 -116.043426) (xy 271.371856 -116.055479)
			(xy 271.454165 -116.075447) (xy 271.534204 -116.103149) (xy 271.611247 -116.138333) (xy 271.684597 -116.180682)
			(xy 271.753589 -116.229811) (xy 271.817599 -116.285276) (xy 271.876047 -116.346574) (xy 271.928403 -116.41315)
			(xy 271.974193 -116.484402) (xy 272.013004 -116.559683) (xy 272.044483 -116.638313) (xy 272.068344 -116.71958)
			(xy 272.084373 -116.802746) (xy 272.092424 -116.88706) (xy 272.092928 -116.929408) (xy 272.092424 -116.971756)
			(xy 272.084373 -117.05607) (xy 272.068344 -117.139236) (xy 272.044483 -117.220503) (xy 272.013004 -117.299133)
			(xy 271.974193 -117.374414) (xy 271.928403 -117.445666) (xy 271.876047 -117.512242) (xy 271.817599 -117.57354)
			(xy 271.753589 -117.629005) (xy 271.684597 -117.678134) (xy 271.611247 -117.720483) (xy 271.534204 -117.755667)
			(xy 271.454165 -117.783369) (xy 271.371856 -117.803337) (xy 271.288021 -117.81539) (xy 271.20342 -117.819421)
			(xy 271.118819 -117.81539) (xy 271.034984 -117.803337) (xy 270.952675 -117.783369) (xy 270.872636 -117.755667)
			(xy 270.795593 -117.720483) (xy 270.722243 -117.678134) (xy 270.653251 -117.629005) (xy 270.589241 -117.57354)
			(xy 270.530793 -117.512242) (xy 270.478437 -117.445666) (xy 270.432647 -117.374414) (xy 270.393836 -117.299133)
			(xy 270.362357 -117.220503) (xy 270.338496 -117.139236) (xy 270.322467 -117.05607) (xy 270.314416 -116.971756)
			(xy 224.975096 -116.971756) (xy 225.948494 -117.945154) (xy 225.955333 -117.952555) (xy 225.963048 -117.971153)
			(xy 225.96348 -117.981222) (xy 225.96348 -118.467816) (xy 268.757396 -118.467816) (xy 268.757396 -118.38312)
			(xy 268.765447 -118.298806) (xy 268.781476 -118.21564) (xy 268.805337 -118.134373) (xy 268.836816 -118.055743)
			(xy 268.875627 -117.980462) (xy 268.921417 -117.90921) (xy 268.973773 -117.842634) (xy 269.032221 -117.781336)
			(xy 269.096231 -117.725871) (xy 269.165223 -117.676742) (xy 269.238573 -117.634393) (xy 269.315616 -117.599209)
			(xy 269.395655 -117.571507) (xy 269.477964 -117.551539) (xy 269.561799 -117.539486) (xy 269.6464 -117.535456)
			(xy 269.731001 -117.539486) (xy 269.814836 -117.551539) (xy 269.897145 -117.571507) (xy 269.977184 -117.599209)
			(xy 270.054227 -117.634393) (xy 270.127577 -117.676742) (xy 270.196569 -117.725871) (xy 270.260579 -117.781336)
			(xy 270.319027 -117.842634) (xy 270.371383 -117.90921) (xy 270.417173 -117.980462) (xy 270.455984 -118.055743)
			(xy 270.487463 -118.134373) (xy 270.511324 -118.21564) (xy 270.527353 -118.298806) (xy 270.535404 -118.38312)
			(xy 270.535908 -118.425468) (xy 270.535404 -118.467816) (xy 270.527353 -118.55213) (xy 270.511324 -118.635296)
			(xy 270.487463 -118.716563) (xy 270.455984 -118.795193) (xy 270.417173 -118.870474) (xy 270.371383 -118.941726)
			(xy 270.319027 -119.008302) (xy 270.260579 -119.0696) (xy 270.196569 -119.125065) (xy 270.127577 -119.174194)
			(xy 270.054227 -119.216543) (xy 269.977184 -119.251727) (xy 269.897145 -119.279429) (xy 269.814836 -119.299397)
			(xy 269.731001 -119.31145) (xy 269.6464 -119.315481) (xy 269.561799 -119.31145) (xy 269.477964 -119.299397)
			(xy 269.395655 -119.279429) (xy 269.315616 -119.251727) (xy 269.238573 -119.216543) (xy 269.165223 -119.174194)
			(xy 269.096231 -119.125065) (xy 269.032221 -119.0696) (xy 268.973773 -119.008302) (xy 268.921417 -118.941726)
			(xy 268.875627 -118.870474) (xy 268.836816 -118.795193) (xy 268.805337 -118.716563) (xy 268.781476 -118.635296)
			(xy 268.765447 -118.55213) (xy 268.757396 -118.467816) (xy 225.96348 -118.467816) (xy 225.96348 -128.980114)
			(xy 270.34896 -128.980114) (xy 270.34896 -128.895418) (xy 270.357011 -128.811104) (xy 270.37304 -128.727938)
			(xy 270.396901 -128.646671) (xy 270.42838 -128.568041) (xy 270.467191 -128.49276) (xy 270.512981 -128.421508)
			(xy 270.565337 -128.354932) (xy 270.623785 -128.293634) (xy 270.687795 -128.238169) (xy 270.756787 -128.18904)
			(xy 270.830137 -128.146691) (xy 270.90718 -128.111507) (xy 270.987219 -128.083805) (xy 271.069528 -128.063837)
			(xy 271.153363 -128.051784) (xy 271.237964 -128.047754) (xy 271.322565 -128.051784) (xy 271.4064 -128.063837)
			(xy 271.488709 -128.083805) (xy 271.568748 -128.111507) (xy 271.645791 -128.146691) (xy 271.719141 -128.18904)
			(xy 271.788133 -128.238169) (xy 271.852143 -128.293634) (xy 271.910591 -128.354932) (xy 271.962947 -128.421508)
			(xy 272.008737 -128.49276) (xy 272.047548 -128.568041) (xy 272.079027 -128.646671) (xy 272.102888 -128.727938)
			(xy 272.118917 -128.811104) (xy 272.126968 -128.895418) (xy 272.127472 -128.937766) (xy 272.126968 -128.980114)
			(xy 272.118917 -129.064428) (xy 272.102888 -129.147594) (xy 272.079027 -129.228861) (xy 272.047548 -129.307491)
			(xy 272.008737 -129.382772) (xy 271.962947 -129.454024) (xy 271.910591 -129.5206) (xy 271.852143 -129.581898)
			(xy 271.788133 -129.637363) (xy 271.719141 -129.686492) (xy 271.645791 -129.728841) (xy 271.568748 -129.764025)
			(xy 271.488709 -129.791727) (xy 271.4064 -129.811695) (xy 271.322565 -129.823748) (xy 271.237964 -129.827779)
			(xy 271.153363 -129.823748) (xy 271.069528 -129.811695) (xy 270.987219 -129.791727) (xy 270.90718 -129.764025)
			(xy 270.830137 -129.728841) (xy 270.756787 -129.686492) (xy 270.687795 -129.637363) (xy 270.623785 -129.581898)
			(xy 270.565337 -129.5206) (xy 270.512981 -129.454024) (xy 270.467191 -129.382772) (xy 270.42838 -129.307491)
			(xy 270.396901 -129.228861) (xy 270.37304 -129.147594) (xy 270.357011 -129.064428) (xy 270.34896 -128.980114)
			(xy 225.96348 -128.980114) (xy 225.96348 -130.532816) (xy 268.757396 -130.532816) (xy 268.757396 -130.44812)
			(xy 268.765447 -130.363806) (xy 268.781476 -130.28064) (xy 268.805337 -130.199373) (xy 268.836816 -130.120743)
			(xy 268.875627 -130.045462) (xy 268.921417 -129.97421) (xy 268.973773 -129.907634) (xy 269.032221 -129.846336)
			(xy 269.096231 -129.790871) (xy 269.165223 -129.741742) (xy 269.238573 -129.699393) (xy 269.315616 -129.664209)
			(xy 269.395655 -129.636507) (xy 269.477964 -129.616539) (xy 269.561799 -129.604486) (xy 269.6464 -129.600456)
			(xy 269.731001 -129.604486) (xy 269.814836 -129.616539) (xy 269.897145 -129.636507) (xy 269.977184 -129.664209)
			(xy 270.054227 -129.699393) (xy 270.127577 -129.741742) (xy 270.196569 -129.790871) (xy 270.260579 -129.846336)
			(xy 270.319027 -129.907634) (xy 270.371383 -129.97421) (xy 270.417173 -130.045462) (xy 270.455984 -130.120743)
			(xy 270.487463 -130.199373) (xy 270.511324 -130.28064) (xy 270.527353 -130.363806) (xy 270.535404 -130.44812)
			(xy 270.535908 -130.490468) (xy 270.535404 -130.532816) (xy 270.527353 -130.61713) (xy 270.511324 -130.700296)
			(xy 270.487463 -130.781563) (xy 270.455984 -130.860193) (xy 270.417173 -130.935474) (xy 270.371383 -131.006726)
			(xy 270.319027 -131.073302) (xy 270.260579 -131.1346) (xy 270.196569 -131.190065) (xy 270.127577 -131.239194)
			(xy 270.054227 -131.281543) (xy 269.977184 -131.316727) (xy 269.897145 -131.344429) (xy 269.814836 -131.364397)
			(xy 269.731001 -131.37645) (xy 269.6464 -131.380481) (xy 269.561799 -131.37645) (xy 269.477964 -131.364397)
			(xy 269.395655 -131.344429) (xy 269.315616 -131.316727) (xy 269.238573 -131.281543) (xy 269.165223 -131.239194)
			(xy 269.096231 -131.190065) (xy 269.032221 -131.1346) (xy 268.973773 -131.073302) (xy 268.921417 -131.006726)
			(xy 268.875627 -130.935474) (xy 268.836816 -130.860193) (xy 268.805337 -130.781563) (xy 268.781476 -130.700296)
			(xy 268.765447 -130.61713) (xy 268.757396 -130.532816) (xy 225.96348 -130.532816) (xy 225.96348 -137.795)
			(xy 234.110777 -137.795) (xy 234.114814 -137.581715) (xy 234.126919 -137.368736) (xy 234.147075 -137.156368)
			(xy 234.175253 -136.944914) (xy 234.211412 -136.734678) (xy 234.255501 -136.525961) (xy 234.307457 -136.319062)
			(xy 234.367204 -136.114277) (xy 234.434659 -135.9119) (xy 234.509723 -135.712221) (xy 234.59229 -135.515524)
			(xy 234.68224 -135.322094) (xy 234.779447 -135.132205) (xy 234.883769 -134.946131) (xy 234.995057 -134.764138)
			(xy 235.113153 -134.586487) (xy 235.237887 -134.413432) (xy 235.369081 -134.245221) (xy 235.506545 -134.082095)
			(xy 235.650084 -133.924288) (xy 235.799492 -133.772025) (xy 235.954555 -133.625525) (xy 236.115051 -133.484998)
			(xy 236.280749 -133.350646) (xy 236.451413 -133.222659) (xy 236.626797 -133.101223) (xy 236.806652 -132.98651)
			(xy 236.990718 -132.878685) (xy 237.178733 -132.777903) (xy 237.370427 -132.684308) (xy 237.565525 -132.598034)
			(xy 237.763749 -132.519205) (xy 237.964813 -132.447933) (xy 238.168431 -132.38432) (xy 238.37431 -132.328459)
			(xy 238.582155 -132.280428) (xy 238.791669 -132.240297) (xy 239.002552 -132.208123) (xy 239.214501 -132.183952)
			(xy 239.427213 -132.167819) (xy 239.640383 -132.159746) (xy 239.747044 -132.159248) (xy 261.747 -132.159248)
			(xy 261.853661 -132.159753) (xy 262.066831 -132.167825) (xy 262.279542 -132.183959) (xy 262.491491 -132.20813)
			(xy 262.702373 -132.240304) (xy 262.911887 -132.280435) (xy 263.119732 -132.328466) (xy 263.32561 -132.384328)
			(xy 263.529228 -132.44794) (xy 263.730292 -132.519212) (xy 263.928515 -132.598041) (xy 264.123613 -132.684315)
			(xy 264.315306 -132.77791) (xy 264.503321 -132.878692) (xy 264.687387 -132.986517) (xy 264.867241 -133.101229)
			(xy 265.042626 -133.222666) (xy 265.213289 -133.350652) (xy 265.378987 -133.485005) (xy 265.539482 -133.625532)
			(xy 265.694545 -133.772031) (xy 265.843952 -133.924293) (xy 265.987491 -134.082101) (xy 266.124956 -134.245226)
			(xy 266.256148 -134.413437) (xy 266.380882 -134.586492) (xy 266.498978 -134.764143) (xy 266.610266 -134.946136)
			(xy 266.714588 -135.132209) (xy 266.811794 -135.322097) (xy 266.901745 -135.515528) (xy 266.984311 -135.712224)
			(xy 267.059376 -135.911903) (xy 267.12683 -136.11428) (xy 267.186577 -136.319065) (xy 267.238533 -136.525963)
			(xy 267.282622 -136.73468) (xy 267.318781 -136.944916) (xy 267.346959 -137.156369) (xy 267.367115 -137.368737)
			(xy 267.37922 -137.581716) (xy 267.383257 -137.795) (xy 267.37922 -138.008284) (xy 267.367115 -138.221263)
			(xy 267.346959 -138.433631) (xy 267.318781 -138.645084) (xy 267.282622 -138.85532) (xy 267.238533 -139.064037)
			(xy 267.186577 -139.270935) (xy 267.12683 -139.47572) (xy 267.059376 -139.678097) (xy 266.984311 -139.877776)
			(xy 266.901745 -140.074472) (xy 266.811794 -140.267903) (xy 266.714588 -140.457791) (xy 266.610266 -140.643864)
			(xy 266.498978 -140.825857) (xy 266.380882 -141.003508) (xy 266.256148 -141.176563) (xy 266.124956 -141.344774)
			(xy 265.987491 -141.507899) (xy 265.843952 -141.665707) (xy 265.694545 -141.817969) (xy 265.539482 -141.964468)
			(xy 265.378987 -142.104995) (xy 265.213289 -142.239348) (xy 265.042626 -142.367334) (xy 264.867241 -142.488771)
			(xy 264.687387 -142.603483) (xy 264.503321 -142.711308) (xy 264.315306 -142.81209) (xy 264.123613 -142.905685)
			(xy 263.928515 -142.991959) (xy 263.730292 -143.070788) (xy 263.529228 -143.14206) (xy 263.32561 -143.205672)
			(xy 263.119732 -143.261534) (xy 262.911887 -143.309565) (xy 262.702373 -143.349696) (xy 262.491491 -143.38187)
			(xy 262.279542 -143.406041) (xy 262.066831 -143.422175) (xy 261.853661 -143.430247) (xy 261.747 -143.430752)
			(xy 239.747044 -143.430752) (xy 239.640383 -143.430254) (xy 239.427213 -143.422181) (xy 239.214501 -143.406048)
			(xy 239.002552 -143.381877) (xy 238.791669 -143.349703) (xy 238.582155 -143.309572) (xy 238.37431 -143.261541)
			(xy 238.168431 -143.20568) (xy 237.964813 -143.142067) (xy 237.763749 -143.070795) (xy 237.565525 -142.991966)
			(xy 237.370427 -142.905692) (xy 237.178733 -142.812097) (xy 236.990718 -142.711315) (xy 236.806652 -142.60349)
			(xy 236.626797 -142.488777) (xy 236.451413 -142.367341) (xy 236.280749 -142.239354) (xy 236.115051 -142.105002)
			(xy 235.954555 -141.964475) (xy 235.799492 -141.817975) (xy 235.650084 -141.665712) (xy 235.506545 -141.507905)
			(xy 235.369081 -141.344779) (xy 235.237887 -141.176568) (xy 235.113153 -141.003513) (xy 234.995057 -140.825862)
			(xy 234.883769 -140.643869) (xy 234.779447 -140.457795) (xy 234.68224 -140.267906) (xy 234.59229 -140.074476)
			(xy 234.509723 -139.877779) (xy 234.434659 -139.6781) (xy 234.367204 -139.475723) (xy 234.307457 -139.270938)
			(xy 234.255501 -139.064039) (xy 234.211412 -138.855322) (xy 234.175253 -138.645086) (xy 234.147075 -138.433632)
			(xy 234.126919 -138.221264) (xy 234.114814 -138.008285) (xy 234.110777 -137.795) (xy 225.96348 -137.795)
			(xy 225.96348 -143.321278) (xy 225.963917 -143.331342) (xy 225.971649 -143.349928) (xy 225.978466 -143.357346)
			(xy 227.30968 -144.68856) (xy 227.317081 -144.695398) (xy 227.33568 -144.70311) (xy 227.345748 -144.703546)
		)
		(stroke
			(width 0)
			(type solid)
		)
		(fill yes)
		(layer "In2.Cu")
		(net "P52V_HS")
	)
	(gr_poly
		(pts
			(xy 205.993238 -91.44) (xy 206.005175 -91.439359) (xy 206.026502 -91.428628) (xy 206.034132 -91.419426)
			(xy 206.045276 -91.404458) (xy 206.068652 -91.375366) (xy 206.080868 -91.36126) (xy 206.086643 -91.354103)
			(xy 206.093158 -91.336919) (xy 206.093568 -91.327732) (xy 206.093568 -91.298014) (xy 206.093146 -91.288886)
			(xy 206.086639 -91.271824) (xy 206.080868 -91.26474) (xy 206.054803 -91.234335) (xy 206.007636 -91.169604)
			(xy 205.966474 -91.100897) (xy 205.931652 -91.028771) (xy 205.90345 -90.953808) (xy 205.882097 -90.876615)
			(xy 205.867764 -90.797815) (xy 205.860569 -90.718046) (xy 205.860142 -90.678) (xy 205.860646 -90.635652)
			(xy 205.868697 -90.551338) (xy 205.884726 -90.468172) (xy 205.908587 -90.386905) (xy 205.940066 -90.308275)
			(xy 205.978877 -90.232994) (xy 206.024667 -90.161742) (xy 206.077023 -90.095166) (xy 206.135471 -90.033868)
			(xy 206.199481 -89.978403) (xy 206.268473 -89.929274) (xy 206.341823 -89.886925) (xy 206.418866 -89.851741)
			(xy 206.498905 -89.824039) (xy 206.581214 -89.804071) (xy 206.665049 -89.792018) (xy 206.74965 -89.787988)
			(xy 206.834251 -89.792018) (xy 206.918086 -89.804071) (xy 207.000395 -89.824039) (xy 207.080434 -89.851741)
			(xy 207.157477 -89.886925) (xy 207.230827 -89.929274) (xy 207.299819 -89.978403) (xy 207.363829 -90.033868)
			(xy 207.422277 -90.095166) (xy 207.474633 -90.161742) (xy 207.520423 -90.232994) (xy 207.559234 -90.308275)
			(xy 207.590713 -90.386905) (xy 207.614574 -90.468172) (xy 207.630603 -90.551338) (xy 207.638654 -90.635652)
			(xy 207.639158 -90.678) (xy 207.638731 -90.718047) (xy 207.631556 -90.79782) (xy 207.617237 -90.876624)
			(xy 207.595889 -90.953822) (xy 207.567686 -91.028787) (xy 207.532857 -91.100912) (xy 207.491683 -91.169613)
			(xy 207.444498 -91.234334) (xy 207.418432 -91.26474) (xy 207.41269 -91.271843) (xy 207.406177 -91.288892)
			(xy 207.405732 -91.298014) (xy 207.405732 -91.327732) (xy 207.40612 -91.336925) (xy 207.412628 -91.354121)
			(xy 207.418432 -91.36126) (xy 207.430644 -91.37537) (xy 207.454019 -91.404463) (xy 207.465168 -91.419426)
			(xy 207.472779 -91.428653) (xy 207.494117 -91.43939) (xy 207.506062 -91.44) (xy 209.676492 -91.44)
			(xy 209.701638 -91.42349) (xy 209.707734 -91.409266) (xy 209.719199 -91.383995) (xy 209.748359 -91.336785)
			(xy 209.78405 -91.294296) (xy 209.825519 -91.257425) (xy 209.871891 -91.226949) (xy 209.922188 -91.203511)
			(xy 209.97535 -91.187605) (xy 210.030255 -91.179568) (xy 210.085745 -91.179568) (xy 210.14065 -91.187605)
			(xy 210.193812 -91.203511) (xy 210.244109 -91.226949) (xy 210.290481 -91.257425) (xy 210.33195 -91.294296)
			(xy 210.367641 -91.336785) (xy 210.396801 -91.383995) (xy 210.408266 -91.409266) (xy 210.414362 -91.42349)
			(xy 210.439508 -91.44) (xy 215.089486 -91.44) (xy 215.099021 -91.43962) (xy 215.116778 -91.432668)
			(xy 215.130749 -91.419691) (xy 215.138989 -91.402494) (xy 215.140032 -91.39301) (xy 215.143552 -91.351891)
			(xy 215.157258 -91.270502) (xy 215.178446 -91.190734) (xy 215.206934 -91.113273) (xy 215.242476 -91.038784)
			(xy 215.284768 -90.967908) (xy 215.333445 -90.901257) (xy 215.388088 -90.839402) (xy 215.448228 -90.782877)
			(xy 215.513346 -90.732166) (xy 215.582883 -90.687708) (xy 215.61933 -90.668348) (xy 215.626826 -90.664135)
			(xy 215.638659 -90.651672) (xy 215.64568 -90.635987) (xy 215.646762 -90.627454) (xy 215.649465 -90.600536)
			(xy 215.661501 -90.547793) (xy 215.680868 -90.497279) (xy 215.707175 -90.450007) (xy 215.739896 -90.406925)
			(xy 215.778374 -90.368897) (xy 215.821839 -90.336686) (xy 215.869417 -90.310937) (xy 215.920156 -90.292167)
			(xy 215.973037 -90.280753) (xy 216.027 -90.276922) (xy 216.080963 -90.280753) (xy 216.133844 -90.292167)
			(xy 216.184583 -90.310937) (xy 216.232161 -90.336686) (xy 216.275626 -90.368897) (xy 216.314104 -90.406925)
			(xy 216.346825 -90.450007) (xy 216.373132 -90.497279) (xy 216.392499 -90.547793) (xy 216.404535 -90.600536)
			(xy 216.407238 -90.627454) (xy 216.408303 -90.635989) (xy 216.415343 -90.651671) (xy 216.427164 -90.66415)
			(xy 216.43467 -90.668348) (xy 216.471131 -90.687681) (xy 216.540663 -90.732149) (xy 216.605776 -90.782866)
			(xy 216.665911 -90.839396) (xy 216.720551 -90.901255) (xy 216.769226 -90.967908) (xy 216.811516 -91.038785)
			(xy 216.84706 -91.113274) (xy 216.87555 -91.190735) (xy 216.896743 -91.270502) (xy 216.910455 -91.35189)
			(xy 216.913968 -91.39301) (xy 216.915492 -91.413076) (xy 216.944448 -91.44) (xy 218.632024 -91.44)
			(xy 218.643867 -91.439376) (xy 218.66505 -91.428774) (xy 218.672664 -91.41968) (xy 218.721432 -91.354402)
			(xy 218.72805 -91.344555) (xy 218.732299 -91.321241) (xy 218.72956 -91.309698) (xy 218.718085 -91.268913)
			(xy 218.702038 -91.185714) (xy 218.693978 -91.101366) (xy 218.693492 -91.059) (xy 218.693967 -91.017898)
			(xy 218.701552 -90.936043) (xy 218.716657 -90.855238) (xy 218.739153 -90.776171) (xy 218.768849 -90.699517)
			(xy 218.805491 -90.62593) (xy 218.848766 -90.556038) (xy 218.898306 -90.490437) (xy 218.953687 -90.429687)
			(xy 219.014437 -90.374306) (xy 219.080038 -90.324766) (xy 219.14993 -90.281491) (xy 219.223517 -90.244849)
			(xy 219.300171 -90.215153) (xy 219.379238 -90.192657) (xy 219.460043 -90.177552) (xy 219.541898 -90.169967)
			(xy 219.583 -90.169492) (xy 219.625472 -90.169986) (xy 219.710028 -90.178085) (xy 219.793427 -90.194208)
			(xy 219.874909 -90.218209) (xy 219.953732 -90.24987) (xy 220.029176 -90.288901) (xy 220.100556 -90.334947)
			(xy 220.167221 -90.38759) (xy 220.228563 -90.446348) (xy 220.284024 -90.510687) (xy 220.333097 -90.58002)
			(xy 220.375337 -90.653717) (xy 220.39326 -90.692224) (xy 220.397471 -90.700482) (xy 220.410632 -90.713515)
			(xy 220.427553 -90.721049) (xy 220.446045 -90.72211) (xy 220.454982 -90.719656) (xy 220.498772 -90.706296)
			(xy 220.588391 -90.687555) (xy 220.67946 -90.678106) (xy 220.725238 -90.677492) (xy 220.726 -90.677492)
			(xy 220.766945 -90.677959) (xy 220.848487 -90.685485) (xy 220.928993 -90.700473) (xy 221.007781 -90.722797)
			(xy 221.084184 -90.752267) (xy 221.157554 -90.788634) (xy 221.227272 -90.831591) (xy 221.292747 -90.880773)
			(xy 221.353425 -90.935764) (xy 221.408793 -90.996099) (xy 221.45838 -91.061267) (xy 221.501769 -91.130717)
			(xy 221.538591 -91.203861) (xy 221.568536 -91.280079) (xy 221.591349 -91.358726) (xy 221.599506 -91.398852)
			(xy 221.603062 -91.416886) (xy 221.631002 -91.44) (xy 222.063056 -91.44) (xy 222.07492 -91.439301)
			(xy 222.096087 -91.428558) (xy 222.103696 -91.419426) (xy 222.159576 -91.344496) (xy 222.163894 -91.32062)
			(xy 222.160338 -91.30919) (xy 222.148313 -91.267504) (xy 222.131479 -91.182386) (xy 222.123024 -91.096033)
			(xy 222.122492 -91.05265) (xy 222.122969 -91.011549) (xy 222.130558 -90.929698) (xy 222.145666 -90.848896)
			(xy 222.168166 -90.769833) (xy 222.197864 -90.693184) (xy 222.234507 -90.619601) (xy 222.277784 -90.549713)
			(xy 222.327324 -90.484116) (xy 222.382705 -90.423369) (xy 222.443454 -90.367992) (xy 222.509054 -90.318455)
			(xy 222.578944 -90.275183) (xy 222.652529 -90.238544) (xy 222.729181 -90.20885) (xy 222.808245 -90.186355)
			(xy 222.889048 -90.171251) (xy 222.970899 -90.163667) (xy 223.012 -90.163142) (xy 223.052325 -90.163594)
			(xy 223.132645 -90.170892) (xy 223.211974 -90.185429) (xy 223.289663 -90.207085) (xy 223.365073 -90.235682)
			(xy 223.437586 -90.270986) (xy 223.506606 -90.312707) (xy 223.571568 -90.360503) (xy 223.602042 -90.386916)
			(xy 223.609198 -90.392695) (xy 223.626382 -90.399217) (xy 223.63557 -90.399616) (xy 223.665288 -90.39987)
			(xy 223.674458 -90.399534) (xy 223.69165 -90.393156) (xy 223.698816 -90.387424) (xy 223.729123 -90.361685)
			(xy 223.793573 -90.315109) (xy 223.861924 -90.274472) (xy 223.933629 -90.240098) (xy 224.008116 -90.212262)
			(xy 224.084791 -90.191186) (xy 224.163041 -90.177038) (xy 224.242241 -90.169931) (xy 224.282 -90.169492)
			(xy 224.323102 -90.169967) (xy 224.404957 -90.177552) (xy 224.485762 -90.192657) (xy 224.564829 -90.215153)
			(xy 224.641483 -90.244849) (xy 224.71507 -90.281491) (xy 224.784962 -90.324766) (xy 224.850563 -90.374306)
			(xy 224.911313 -90.429687) (xy 224.966694 -90.490437) (xy 225.016234 -90.556038) (xy 225.059509 -90.62593)
			(xy 225.096151 -90.699517) (xy 225.125847 -90.776171) (xy 225.148343 -90.855238) (xy 225.163448 -90.936043)
			(xy 225.171033 -91.017898) (xy 225.171508 -91.059) (xy 225.171019 -91.101366) (xy 225.162961 -91.185714)
			(xy 225.146917 -91.268913) (xy 225.13544 -91.309698) (xy 225.132138 -91.321382) (xy 225.136202 -91.34475)
			(xy 225.192336 -91.41968) (xy 225.199937 -91.428789) (xy 225.221128 -91.439395) (xy 225.232976 -91.44)
			(xy 230.509064 -91.44) (xy 230.519431 -91.439504) (xy 230.53848 -91.431312) (xy 230.552763 -91.416281)
			(xy 230.556816 -91.406726) (xy 230.571629 -91.367718) (xy 230.607574 -91.29241) (xy 230.650415 -91.2208)
			(xy 230.699773 -91.153516) (xy 230.755216 -91.091151) (xy 230.816256 -91.034252) (xy 230.882356 -90.98332)
			(xy 230.952935 -90.938801) (xy 231.027374 -90.901088) (xy 231.105017 -90.870512) (xy 231.185182 -90.847342)
			(xy 231.267165 -90.831781) (xy 231.350245 -90.823966) (xy 231.433691 -90.823966) (xy 231.516771 -90.831781)
			(xy 231.598754 -90.847342) (xy 231.678919 -90.870512) (xy 231.756562 -90.901088) (xy 231.831001 -90.938801)
			(xy 231.90158 -90.98332) (xy 231.96768 -91.034252) (xy 232.02872 -91.091151) (xy 232.084163 -91.153516)
			(xy 232.133521 -91.2208) (xy 232.176362 -91.29241) (xy 232.212307 -91.367718) (xy 232.22712 -91.406726)
			(xy 232.231152 -91.416296) (xy 232.245425 -91.43135) (xy 232.264498 -91.439511) (xy 232.274872 -91.44)
			(xy 234.575096 -91.44) (xy 234.585459 -91.439498) (xy 234.604498 -91.4313) (xy 234.618771 -91.416268)
			(xy 234.622848 -91.406726) (xy 234.637527 -91.36809) (xy 234.673074 -91.293468) (xy 234.715387 -91.222465)
			(xy 234.764102 -91.155691) (xy 234.818799 -91.093721) (xy 234.879007 -91.037091) (xy 234.944206 -90.986288)
			(xy 235.013836 -90.941749) (xy 235.05033 -90.922348) (xy 235.057826 -90.918135) (xy 235.069659 -90.905672)
			(xy 235.07668 -90.889987) (xy 235.077762 -90.881454) (xy 235.080465 -90.854536) (xy 235.092501 -90.801793)
			(xy 235.111868 -90.751279) (xy 235.138175 -90.704007) (xy 235.170896 -90.660925) (xy 235.209374 -90.622897)
			(xy 235.252839 -90.590686) (xy 235.300417 -90.564937) (xy 235.351156 -90.546167) (xy 235.404037 -90.534753)
			(xy 235.458 -90.530922) (xy 235.511963 -90.534753) (xy 235.564844 -90.546167) (xy 235.615583 -90.564937)
			(xy 235.663161 -90.590686) (xy 235.706626 -90.622897) (xy 235.745104 -90.660925) (xy 235.777825 -90.704007)
			(xy 235.804132 -90.751279) (xy 235.823499 -90.801793) (xy 235.835535 -90.854536) (xy 235.838238 -90.881454)
			(xy 235.839303 -90.889989) (xy 235.846343 -90.905671) (xy 235.858164 -90.91815) (xy 235.86567 -90.922348)
			(xy 235.902191 -90.941704) (xy 235.971833 -90.986234) (xy 236.037041 -91.037034) (xy 236.097255 -91.093666)
			(xy 236.151952 -91.155642) (xy 236.200663 -91.222427) (xy 236.242965 -91.293443) (xy 236.278495 -91.368079)
			(xy 236.293152 -91.406726) (xy 236.297186 -91.416292) (xy 236.311461 -91.431337) (xy 236.330532 -91.439486)
			(xy 236.340904 -91.44) (xy 236.73816 -91.44) (xy 236.748528 -91.439504) (xy 236.767578 -91.431314)
			(xy 236.781862 -91.416282) (xy 236.785912 -91.406726) (xy 236.800725 -91.367718) (xy 236.83667 -91.29241)
			(xy 236.879511 -91.2208) (xy 236.928869 -91.153516) (xy 236.984312 -91.091151) (xy 237.045352 -91.034252)
			(xy 237.111452 -90.98332) (xy 237.182031 -90.938801) (xy 237.25647 -90.901088) (xy 237.334113 -90.870512)
			(xy 237.414278 -90.847342) (xy 237.496261 -90.831781) (xy 237.579341 -90.823966) (xy 237.662787 -90.823966)
			(xy 237.745867 -90.831781) (xy 237.82785 -90.847342) (xy 237.908015 -90.870512) (xy 237.985658 -90.901088)
			(xy 238.060097 -90.938801) (xy 238.130676 -90.98332) (xy 238.196776 -91.034252) (xy 238.257816 -91.091151)
			(xy 238.313259 -91.153516) (xy 238.362617 -91.2208) (xy 238.405458 -91.29241) (xy 238.441403 -91.367718)
			(xy 238.456216 -91.406726) (xy 238.460248 -91.416296) (xy 238.474521 -91.431351) (xy 238.493593 -91.439514)
			(xy 238.503968 -91.44) (xy 241.024918 -91.44) (xy 241.034987 -91.439573) (xy 241.053586 -91.431854)
			(xy 241.060986 -91.425014) (xy 241.793014 -90.692986) (xy 241.799868 -90.685591) (xy 241.80761 -90.666992)
			(xy 241.808 -90.656918) (xy 241.808 -71.268082) (xy 241.807573 -71.258013) (xy 241.799854 -71.239414)
			(xy 241.793014 -71.232014) (xy 241.314986 -70.753986) (xy 241.307591 -70.747132) (xy 241.288992 -70.73939)
			(xy 241.278918 -70.739) (xy 221.001082 -70.739) (xy 220.991013 -70.739427) (xy 220.972414 -70.747146)
			(xy 220.965014 -70.753986) (xy 220.486986 -71.232014) (xy 220.480132 -71.239409) (xy 220.47239 -71.258008)
			(xy 220.472 -71.268082) (xy 220.472 -72.0026) (xy 221.995038 -72.0026) (xy 221.999067 -71.918004)
			(xy 222.01112 -71.834173) (xy 222.031087 -71.751869) (xy 222.058787 -71.671834) (xy 222.09397 -71.594796)
			(xy 222.136316 -71.52145) (xy 222.185442 -71.452462) (xy 222.240904 -71.388456) (xy 222.302199 -71.330011)
			(xy 222.368771 -71.277658) (xy 222.440019 -71.23187) (xy 222.515296 -71.193062) (xy 222.593922 -71.161585)
			(xy 222.675183 -71.137724) (xy 222.758345 -71.121696) (xy 222.842654 -71.113646) (xy 222.885 -71.113142)
			(xy 222.92879 -71.113696) (xy 223.015948 -71.122294) (xy 223.101838 -71.139418) (xy 223.18563 -71.1649)
			(xy 223.266511 -71.198495) (xy 223.343698 -71.239877) (xy 223.416445 -71.288645) (xy 223.484045 -71.344327)
			(xy 223.545846 -71.406384) (xy 223.601248 -71.474214) (xy 223.625918 -71.510398) (xy 223.63303 -71.520812)
			(xy 223.655382 -71.533004) (xy 223.765618 -71.533004) (xy 223.78797 -71.520812) (xy 223.795082 -71.510398)
			(xy 223.819723 -71.474194) (xy 223.875133 -71.406368) (xy 223.93694 -71.344314) (xy 224.004545 -71.288634)
			(xy 224.077295 -71.239867) (xy 224.154484 -71.198485) (xy 224.235367 -71.164888) (xy 224.319159 -71.139402)
			(xy 224.40505 -71.122273) (xy 224.492209 -71.113666) (xy 224.536 -71.113142) (xy 224.578315 -71.113653)
			(xy 224.662562 -71.121683) (xy 224.745665 -71.13768) (xy 224.826873 -71.1615) (xy 224.905451 -71.192926)
			(xy 224.980689 -71.231675) (xy 225.016568 -71.254112) (xy 225.024957 -71.258995) (xy 225.044 -71.262666)
			(xy 225.063043 -71.258995) (xy 225.071432 -71.254112) (xy 225.107302 -71.23166) (xy 225.182544 -71.192919)
			(xy 225.261125 -71.161497) (xy 225.342334 -71.137679) (xy 225.425438 -71.12168) (xy 225.509685 -71.113644)
			(xy 225.552 -71.113142) (xy 225.59579 -71.113696) (xy 225.682948 -71.122294) (xy 225.768838 -71.139418)
			(xy 225.85263 -71.1649) (xy 225.933511 -71.198495) (xy 226.010698 -71.239877) (xy 226.083445 -71.288645)
			(xy 226.151045 -71.344327) (xy 226.212846 -71.406384) (xy 226.268248 -71.474214) (xy 226.292918 -71.510398)
			(xy 226.30003 -71.520812) (xy 226.322382 -71.533004) (xy 226.432618 -71.533004) (xy 226.45497 -71.520812)
			(xy 226.462082 -71.510398) (xy 226.486723 -71.474194) (xy 226.542133 -71.406368) (xy 226.60394 -71.344314)
			(xy 226.671545 -71.288634) (xy 226.744295 -71.239867) (xy 226.821484 -71.198485) (xy 226.902367 -71.164888)
			(xy 226.986159 -71.139402) (xy 227.07205 -71.122273) (xy 227.159209 -71.113666) (xy 227.203 -71.113142)
			(xy 227.245351 -71.113546) (xy 227.329669 -71.121597) (xy 227.41284 -71.137627) (xy 227.494111 -71.16149)
			(xy 227.572745 -71.192971) (xy 227.648031 -71.231783) (xy 227.719287 -71.277576) (xy 227.785867 -71.329936)
			(xy 227.847169 -71.388387) (xy 227.902636 -71.4524) (xy 227.951768 -71.521396) (xy 227.994119 -71.59475)
			(xy 228.029305 -71.671797) (xy 228.057009 -71.75184) (xy 228.076978 -71.834155) (xy 228.089032 -71.917994)
			(xy 228.093063 -72.0026) (xy 228.980038 -72.0026) (xy 228.984067 -71.918004) (xy 228.99612 -71.834173)
			(xy 229.016087 -71.751869) (xy 229.043787 -71.671834) (xy 229.07897 -71.594796) (xy 229.121316 -71.52145)
			(xy 229.170442 -71.452462) (xy 229.225904 -71.388456) (xy 229.287199 -71.330011) (xy 229.353771 -71.277658)
			(xy 229.425019 -71.23187) (xy 229.500296 -71.193062) (xy 229.578922 -71.161585) (xy 229.660183 -71.137724)
			(xy 229.743345 -71.121696) (xy 229.827654 -71.113646) (xy 229.87 -71.113142) (xy 229.912315 -71.113653)
			(xy 229.996562 -71.121683) (xy 230.079665 -71.13768) (xy 230.160873 -71.1615) (xy 230.239451 -71.192926)
			(xy 230.314689 -71.231675) (xy 230.350568 -71.254112) (xy 230.358957 -71.258995) (xy 230.378 -71.262666)
			(xy 230.397043 -71.258995) (xy 230.405432 -71.254112) (xy 230.441302 -71.23166) (xy 230.516544 -71.192919)
			(xy 230.595125 -71.161497) (xy 230.676334 -71.137679) (xy 230.759438 -71.12168) (xy 230.843685 -71.113644)
			(xy 230.886 -71.113142) (xy 230.92979 -71.113696) (xy 231.016948 -71.122294) (xy 231.102838 -71.139418)
			(xy 231.18663 -71.1649) (xy 231.267511 -71.198495) (xy 231.344698 -71.239877) (xy 231.417445 -71.288645)
			(xy 231.485045 -71.344327) (xy 231.546846 -71.406384) (xy 231.602248 -71.474214) (xy 231.626918 -71.510398)
			(xy 231.63403 -71.520812) (xy 231.656382 -71.533004) (xy 231.766618 -71.533004) (xy 231.78897 -71.520812)
			(xy 231.796082 -71.510398) (xy 231.820723 -71.474194) (xy 231.876133 -71.406368) (xy 231.93794 -71.344314)
			(xy 232.005545 -71.288634) (xy 232.078295 -71.239867) (xy 232.155484 -71.198485) (xy 232.236367 -71.164888)
			(xy 232.320159 -71.139402) (xy 232.40605 -71.122273) (xy 232.493209 -71.113666) (xy 232.537 -71.113142)
			(xy 232.579351 -71.113546) (xy 232.663669 -71.121597) (xy 232.74684 -71.137627) (xy 232.828111 -71.16149)
			(xy 232.906745 -71.192971) (xy 232.982031 -71.231783) (xy 233.053287 -71.277576) (xy 233.119867 -71.329936)
			(xy 233.181169 -71.388387) (xy 233.236636 -71.4524) (xy 233.285768 -71.521396) (xy 233.328119 -71.59475)
			(xy 233.363305 -71.671797) (xy 233.391009 -71.75184) (xy 233.410978 -71.834155) (xy 233.423032 -71.917994)
			(xy 233.427063 -72.0026) (xy 233.423032 -72.087206) (xy 233.417232 -72.127548) (xy 237.870996 -72.127548)
			(xy 237.870996 -72.042852) (xy 237.879047 -71.958538) (xy 237.895076 -71.875372) (xy 237.918937 -71.794105)
			(xy 237.950416 -71.715475) (xy 237.989227 -71.640194) (xy 238.035017 -71.568942) (xy 238.087373 -71.502366)
			(xy 238.145821 -71.441068) (xy 238.209831 -71.385603) (xy 238.278823 -71.336474) (xy 238.352173 -71.294125)
			(xy 238.429216 -71.258941) (xy 238.509255 -71.231239) (xy 238.591564 -71.211271) (xy 238.675399 -71.199218)
			(xy 238.76 -71.195188) (xy 238.844601 -71.199218) (xy 238.928436 -71.211271) (xy 239.010745 -71.231239)
			(xy 239.090784 -71.258941) (xy 239.167827 -71.294125) (xy 239.241177 -71.336474) (xy 239.310169 -71.385603)
			(xy 239.374179 -71.441068) (xy 239.432627 -71.502366) (xy 239.484983 -71.568942) (xy 239.530773 -71.640194)
			(xy 239.569584 -71.715475) (xy 239.601063 -71.794105) (xy 239.624924 -71.875372) (xy 239.640953 -71.958538)
			(xy 239.649004 -72.042852) (xy 239.649508 -72.0852) (xy 239.649004 -72.127548) (xy 239.640953 -72.211862)
			(xy 239.624924 -72.295028) (xy 239.601063 -72.376295) (xy 239.569584 -72.454925) (xy 239.530773 -72.530206)
			(xy 239.484983 -72.601458) (xy 239.432627 -72.668034) (xy 239.374179 -72.729332) (xy 239.310169 -72.784797)
			(xy 239.241177 -72.833926) (xy 239.167827 -72.876275) (xy 239.090784 -72.911459) (xy 239.010745 -72.939161)
			(xy 238.928436 -72.959129) (xy 238.844601 -72.971182) (xy 238.76 -72.975213) (xy 238.675399 -72.971182)
			(xy 238.591564 -72.959129) (xy 238.509255 -72.939161) (xy 238.429216 -72.911459) (xy 238.352173 -72.876275)
			(xy 238.278823 -72.833926) (xy 238.209831 -72.784797) (xy 238.145821 -72.729332) (xy 238.087373 -72.668034)
			(xy 238.035017 -72.601458) (xy 237.989227 -72.530206) (xy 237.950416 -72.454925) (xy 237.918937 -72.376295)
			(xy 237.895076 -72.295028) (xy 237.879047 -72.211862) (xy 237.870996 -72.127548) (xy 233.417232 -72.127548)
			(xy 233.410978 -72.171045) (xy 233.391009 -72.25336) (xy 233.363305 -72.333403) (xy 233.328119 -72.41045)
			(xy 233.285768 -72.483804) (xy 233.236636 -72.5528) (xy 233.181169 -72.616813) (xy 233.119867 -72.675264)
			(xy 233.053287 -72.727624) (xy 232.982031 -72.773417) (xy 232.906745 -72.812229) (xy 232.828111 -72.84371)
			(xy 232.74684 -72.867573) (xy 232.663669 -72.883603) (xy 232.579351 -72.891654) (xy 232.537 -72.892158)
			(xy 232.49321 -72.891604) (xy 232.406052 -72.883006) (xy 232.320162 -72.865882) (xy 232.23637 -72.8404)
			(xy 232.155489 -72.806805) (xy 232.078302 -72.765423) (xy 232.005555 -72.716655) (xy 231.937955 -72.660973)
			(xy 231.876154 -72.598916) (xy 231.820752 -72.531086) (xy 231.796082 -72.494902) (xy 231.78897 -72.484488)
			(xy 231.766618 -72.472296) (xy 231.656382 -72.472296) (xy 231.63403 -72.484488) (xy 231.626918 -72.494902)
			(xy 231.602277 -72.531106) (xy 231.546867 -72.598932) (xy 231.48506 -72.660986) (xy 231.417455 -72.716666)
			(xy 231.344705 -72.765433) (xy 231.267516 -72.806815) (xy 231.186633 -72.840412) (xy 231.102841 -72.865898)
			(xy 231.01695 -72.883027) (xy 230.929791 -72.891634) (xy 230.886 -72.892158) (xy 230.843685 -72.891647)
			(xy 230.759438 -72.883617) (xy 230.676335 -72.86762) (xy 230.595127 -72.8438) (xy 230.516549 -72.812374)
			(xy 230.441311 -72.773625) (xy 230.405432 -72.751188) (xy 230.397043 -72.746305) (xy 230.378 -72.742634)
			(xy 230.358957 -72.746305) (xy 230.350568 -72.751188) (xy 230.314698 -72.77364) (xy 230.239456 -72.812381)
			(xy 230.160875 -72.843803) (xy 230.079666 -72.867621) (xy 229.996562 -72.88362) (xy 229.912315 -72.891656)
			(xy 229.87 -72.892158) (xy 229.827654 -72.891554) (xy 229.743345 -72.883504) (xy 229.660183 -72.867476)
			(xy 229.578922 -72.843615) (xy 229.500296 -72.812138) (xy 229.425019 -72.77333) (xy 229.353771 -72.727542)
			(xy 229.287199 -72.675189) (xy 229.225904 -72.616744) (xy 229.170442 -72.552738) (xy 229.121316 -72.48375)
			(xy 229.07897 -72.410404) (xy 229.043787 -72.333366) (xy 229.016087 -72.253331) (xy 228.99612 -72.171027)
			(xy 228.984067 -72.087196) (xy 228.980038 -72.0026) (xy 228.093063 -72.0026) (xy 228.089032 -72.087206)
			(xy 228.076978 -72.171045) (xy 228.057009 -72.25336) (xy 228.029305 -72.333403) (xy 227.994119 -72.41045)
			(xy 227.951768 -72.483804) (xy 227.902636 -72.5528) (xy 227.847169 -72.616813) (xy 227.785867 -72.675264)
			(xy 227.719287 -72.727624) (xy 227.648031 -72.773417) (xy 227.572745 -72.812229) (xy 227.494111 -72.84371)
			(xy 227.41284 -72.867573) (xy 227.329669 -72.883603) (xy 227.245351 -72.891654) (xy 227.203 -72.892158)
			(xy 227.15921 -72.891604) (xy 227.072052 -72.883006) (xy 226.986162 -72.865882) (xy 226.90237 -72.8404)
			(xy 226.821489 -72.806805) (xy 226.744302 -72.765423) (xy 226.671555 -72.716655) (xy 226.603955 -72.660973)
			(xy 226.542154 -72.598916) (xy 226.486752 -72.531086) (xy 226.462082 -72.494902) (xy 226.45497 -72.484488)
			(xy 226.432618 -72.472296) (xy 226.322382 -72.472296) (xy 226.30003 -72.484488) (xy 226.292918 -72.494902)
			(xy 226.268277 -72.531106) (xy 226.212867 -72.598932) (xy 226.15106 -72.660986) (xy 226.083455 -72.716666)
			(xy 226.010705 -72.765433) (xy 225.933516 -72.806815) (xy 225.852633 -72.840412) (xy 225.768841 -72.865898)
			(xy 225.68295 -72.883027) (xy 225.595791 -72.891634) (xy 225.552 -72.892158) (xy 225.509685 -72.891647)
			(xy 225.425438 -72.883617) (xy 225.342335 -72.86762) (xy 225.261127 -72.8438) (xy 225.182549 -72.812374)
			(xy 225.107311 -72.773625) (xy 225.071432 -72.751188) (xy 225.063043 -72.746305) (xy 225.044 -72.742634)
			(xy 225.024957 -72.746305) (xy 225.016568 -72.751188) (xy 224.980698 -72.77364) (xy 224.905456 -72.812381)
			(xy 224.826875 -72.843803) (xy 224.745666 -72.867621) (xy 224.662562 -72.88362) (xy 224.578315 -72.891656)
			(xy 224.536 -72.892158) (xy 224.49221 -72.891604) (xy 224.405052 -72.883006) (xy 224.319162 -72.865882)
			(xy 224.23537 -72.8404) (xy 224.154489 -72.806805) (xy 224.077302 -72.765423) (xy 224.004555 -72.716655)
			(xy 223.936955 -72.660973) (xy 223.875154 -72.598916) (xy 223.819752 -72.531086) (xy 223.795082 -72.494902)
			(xy 223.78797 -72.484488) (xy 223.765618 -72.472296) (xy 223.655382 -72.472296) (xy 223.63303 -72.484488)
			(xy 223.625918 -72.494902) (xy 223.601277 -72.531106) (xy 223.545867 -72.598932) (xy 223.48406 -72.660986)
			(xy 223.416455 -72.716666) (xy 223.343705 -72.765433) (xy 223.266516 -72.806815) (xy 223.185633 -72.840412)
			(xy 223.101841 -72.865898) (xy 223.01595 -72.883027) (xy 222.928791 -72.891634) (xy 222.885 -72.892158)
			(xy 222.842654 -72.891554) (xy 222.758345 -72.883504) (xy 222.675183 -72.867476) (xy 222.593922 -72.843615)
			(xy 222.515296 -72.812138) (xy 222.440019 -72.77333) (xy 222.368771 -72.727542) (xy 222.302199 -72.675189)
			(xy 222.240904 -72.616744) (xy 222.185442 -72.552738) (xy 222.136316 -72.48375) (xy 222.09397 -72.410404)
			(xy 222.058787 -72.333366) (xy 222.031087 -72.253331) (xy 222.01112 -72.171027) (xy 221.999067 -72.087196)
			(xy 221.995038 -72.0026) (xy 220.472 -72.0026) (xy 220.472 -73.107042) (xy 220.490796 -73.133204)
			(xy 220.50629 -73.138538) (xy 220.546294 -73.152765) (xy 220.623632 -73.187815) (xy 220.697279 -73.230075)
			(xy 220.766563 -73.279162) (xy 220.830853 -73.334628) (xy 220.889566 -73.395968) (xy 220.942166 -73.462624)
			(xy 220.988175 -73.533989) (xy 221.027173 -73.609414) (xy 221.058806 -73.688212) (xy 221.082786 -73.769665)
			(xy 221.098894 -73.853034) (xy 221.106984 -73.937558) (xy 221.106983 -74.022468) (xy 221.09889 -74.106992)
			(xy 221.082779 -74.19036) (xy 221.058797 -74.271813) (xy 221.027162 -74.35061) (xy 220.988162 -74.426034)
			(xy 220.942151 -74.497397) (xy 220.889549 -74.564052) (xy 220.830835 -74.62539) (xy 220.766542 -74.680854)
			(xy 220.740507 -74.699298) (xy 223.392996 -74.699298) (xy 223.392996 -74.614602) (xy 223.401047 -74.530288)
			(xy 223.417076 -74.447122) (xy 223.440937 -74.365855) (xy 223.472416 -74.287225) (xy 223.511227 -74.211944)
			(xy 223.557017 -74.140692) (xy 223.609373 -74.074116) (xy 223.667821 -74.012818) (xy 223.731831 -73.957353)
			(xy 223.800823 -73.908224) (xy 223.874173 -73.865875) (xy 223.951216 -73.830691) (xy 224.031255 -73.802989)
			(xy 224.113564 -73.783021) (xy 224.197399 -73.770968) (xy 224.282 -73.766938) (xy 224.366601 -73.770968)
			(xy 224.450436 -73.783021) (xy 224.532745 -73.802989) (xy 224.612784 -73.830691) (xy 224.689827 -73.865875)
			(xy 224.763177 -73.908224) (xy 224.832169 -73.957353) (xy 224.896179 -74.012818) (xy 224.954627 -74.074116)
			(xy 225.006983 -74.140692) (xy 225.051747 -74.210348) (xy 231.393996 -74.210348) (xy 231.393996 -74.125652)
			(xy 231.402047 -74.041338) (xy 231.418076 -73.958172) (xy 231.441937 -73.876905) (xy 231.473416 -73.798275)
			(xy 231.512227 -73.722994) (xy 231.558017 -73.651742) (xy 231.610373 -73.585166) (xy 231.668821 -73.523868)
			(xy 231.732831 -73.468403) (xy 231.801823 -73.419274) (xy 231.875173 -73.376925) (xy 231.952216 -73.341741)
			(xy 232.032255 -73.314039) (xy 232.114564 -73.294071) (xy 232.198399 -73.282018) (xy 232.283 -73.277988)
			(xy 232.367601 -73.282018) (xy 232.451436 -73.294071) (xy 232.533745 -73.314039) (xy 232.613784 -73.341741)
			(xy 232.690827 -73.376925) (xy 232.764177 -73.419274) (xy 232.833169 -73.468403) (xy 232.897179 -73.523868)
			(xy 232.955627 -73.585166) (xy 233.007983 -73.651742) (xy 233.053773 -73.722994) (xy 233.092584 -73.798275)
			(xy 233.124063 -73.876905) (xy 233.147924 -73.958172) (xy 233.163953 -74.041338) (xy 233.172004 -74.125652)
			(xy 233.172508 -74.168) (xy 233.172004 -74.210348) (xy 233.163953 -74.294662) (xy 233.147924 -74.377828)
			(xy 233.124063 -74.459095) (xy 233.092584 -74.537725) (xy 233.089916 -74.5429) (xy 236.091992 -74.5429)
			(xy 236.096022 -74.458299) (xy 236.108075 -74.374465) (xy 236.128043 -74.292156) (xy 236.155745 -74.212117)
			(xy 236.190929 -74.135075) (xy 236.233277 -74.061725) (xy 236.282406 -73.992733) (xy 236.337871 -73.928724)
			(xy 236.399168 -73.870276) (xy 236.465744 -73.81792) (xy 236.536996 -73.77213) (xy 236.612277 -73.73332)
			(xy 236.690907 -73.701841) (xy 236.772173 -73.677979) (xy 236.855339 -73.661951) (xy 236.939652 -73.6539)
			(xy 236.982 -73.653396) (xy 237.023248 -73.653844) (xy 237.105389 -73.661474) (xy 237.186471 -73.676677)
			(xy 237.265797 -73.699324) (xy 237.342685 -73.729218) (xy 237.416474 -73.766105) (xy 237.486531 -73.809665)
			(xy 237.552252 -73.859526) (xy 237.613074 -73.915259) (xy 237.668474 -73.976384) (xy 237.717976 -74.042377)
			(xy 237.761154 -74.11267) (xy 237.779814 -74.149458) (xy 237.784347 -74.157806) (xy 237.79835 -74.170626)
			(xy 237.816042 -74.177514) (xy 237.825534 -74.177906) (xy 237.916466 -74.177906) (xy 237.925967 -74.177544)
			(xy 237.943685 -74.170684) (xy 237.95767 -74.157825) (xy 237.962186 -74.149458) (xy 237.981683 -74.111087)
			(xy 238.02705 -74.037938) (xy 238.07927 -73.969513) (xy 238.137854 -73.906451) (xy 238.202254 -73.849341)
			(xy 238.271869 -73.798718) (xy 238.346047 -73.755055) (xy 238.424096 -73.718761) (xy 238.505285 -73.690173)
			(xy 238.588855 -73.669561) (xy 238.674026 -73.657116) (xy 238.76 -73.652954) (xy 238.845974 -73.657116)
			(xy 238.931145 -73.669561) (xy 239.014715 -73.690173) (xy 239.095904 -73.718761) (xy 239.173953 -73.755055)
			(xy 239.248131 -73.798718) (xy 239.317746 -73.849341) (xy 239.382146 -73.906451) (xy 239.44073 -73.969513)
			(xy 239.49295 -74.037938) (xy 239.538317 -74.111087) (xy 239.557814 -74.149458) (xy 239.562347 -74.157806)
			(xy 239.57635 -74.170626) (xy 239.594042 -74.177514) (xy 239.603534 -74.177906) (xy 239.694466 -74.177906)
			(xy 239.703967 -74.177544) (xy 239.721685 -74.170684) (xy 239.73567 -74.157825) (xy 239.740186 -74.149458)
			(xy 239.758799 -74.112647) (xy 239.801992 -74.042364) (xy 239.851506 -73.976381) (xy 239.906915 -73.915265)
			(xy 239.967744 -73.859541) (xy 240.03347 -73.809687) (xy 240.103529 -73.766132) (xy 240.177319 -73.729249)
			(xy 240.254207 -73.699355) (xy 240.333532 -73.676707) (xy 240.414612 -73.661499) (xy 240.496753 -73.653863)
			(xy 240.538 -73.653396) (xy 240.580349 -73.653892) (xy 240.664663 -73.661943) (xy 240.747829 -73.677972)
			(xy 240.829096 -73.701834) (xy 240.907726 -73.733313) (xy 240.983008 -73.772123) (xy 241.05426 -73.817914)
			(xy 241.120837 -73.87027) (xy 241.182135 -73.928718) (xy 241.2376 -73.992728) (xy 241.28673 -74.061721)
			(xy 241.329078 -74.135071) (xy 241.364263 -74.212114) (xy 241.391965 -74.292153) (xy 241.411933 -74.374463)
			(xy 241.423986 -74.458299) (xy 241.428017 -74.5429) (xy 241.423986 -74.627501) (xy 241.411933 -74.711337)
			(xy 241.391965 -74.793647) (xy 241.364263 -74.873686) (xy 241.329078 -74.950729) (xy 241.28673 -75.024079)
			(xy 241.2376 -75.093072) (xy 241.182135 -75.157082) (xy 241.120837 -75.21553) (xy 241.05426 -75.267886)
			(xy 240.983008 -75.313677) (xy 240.907726 -75.352487) (xy 240.829096 -75.383966) (xy 240.747829 -75.407828)
			(xy 240.664663 -75.423857) (xy 240.580349 -75.431908) (xy 240.538 -75.432412) (xy 240.496753 -75.43196)
			(xy 240.414611 -75.42433) (xy 240.333529 -75.409127) (xy 240.254204 -75.38648) (xy 240.177316 -75.356586)
			(xy 240.103527 -75.3197) (xy 240.033471 -75.27614) (xy 239.967749 -75.226279) (xy 239.906927 -75.170547)
			(xy 239.851527 -75.109423) (xy 239.802025 -75.04343) (xy 239.758847 -74.973138) (xy 239.740186 -74.93635)
			(xy 239.735651 -74.928003) (xy 239.721649 -74.915183) (xy 239.703958 -74.908294) (xy 239.694466 -74.907902)
			(xy 239.603534 -74.907902) (xy 239.594032 -74.90826) (xy 239.576314 -74.915121) (xy 239.562329 -74.927982)
			(xy 239.557814 -74.93635) (xy 239.538317 -74.974721) (xy 239.49295 -75.04787) (xy 239.44073 -75.116295)
			(xy 239.382146 -75.179357) (xy 239.317746 -75.236467) (xy 239.248131 -75.28709) (xy 239.173953 -75.330753)
			(xy 239.095904 -75.367047) (xy 239.014715 -75.395635) (xy 238.931145 -75.416247) (xy 238.845974 -75.428692)
			(xy 238.76 -75.432854) (xy 238.674026 -75.428692) (xy 238.588855 -75.416247) (xy 238.505285 -75.395635)
			(xy 238.424096 -75.367047) (xy 238.346047 -75.330753) (xy 238.271869 -75.28709) (xy 238.202254 -75.236467)
			(xy 238.137854 -75.179357) (xy 238.07927 -75.116295) (xy 238.02705 -75.04787) (xy 237.981683 -74.974721)
			(xy 237.962186 -74.93635) (xy 237.957651 -74.928003) (xy 237.943649 -74.915183) (xy 237.925958 -74.908294)
			(xy 237.916466 -74.907902) (xy 237.825534 -74.907902) (xy 237.816032 -74.90826) (xy 237.798314 -74.915121)
			(xy 237.784329 -74.927982) (xy 237.779814 -74.93635) (xy 237.761159 -74.973139) (xy 237.717973 -75.043425)
			(xy 237.668465 -75.10941) (xy 237.613061 -75.170528) (xy 237.552237 -75.226255) (xy 237.486514 -75.276112)
			(xy 237.416459 -75.31967) (xy 237.342672 -75.356555) (xy 237.265786 -75.38645) (xy 237.186464 -75.4091)
			(xy 237.105385 -75.424308) (xy 237.023246 -75.431945) (xy 236.982 -75.432412) (xy 236.939652 -75.4319)
			(xy 236.855339 -75.423849) (xy 236.772173 -75.407821) (xy 236.690907 -75.383959) (xy 236.612277 -75.35248)
			(xy 236.536996 -75.31367) (xy 236.465744 -75.26788) (xy 236.399168 -75.215524) (xy 236.337871 -75.157076)
			(xy 236.282406 -75.093067) (xy 236.233277 -75.024075) (xy 236.190929 -74.950725) (xy 236.155745 -74.873683)
			(xy 236.128043 -74.793644) (xy 236.108075 -74.711335) (xy 236.096022 -74.627501) (xy 236.091992 -74.5429)
			(xy 233.089916 -74.5429) (xy 233.053773 -74.613006) (xy 233.007983 -74.684258) (xy 232.955627 -74.750834)
			(xy 232.897179 -74.812132) (xy 232.833169 -74.867597) (xy 232.764177 -74.916726) (xy 232.690827 -74.959075)
			(xy 232.613784 -74.994259) (xy 232.533745 -75.021961) (xy 232.451436 -75.041929) (xy 232.367601 -75.053982)
			(xy 232.283 -75.058013) (xy 232.198399 -75.053982) (xy 232.114564 -75.041929) (xy 232.032255 -75.021961)
			(xy 231.952216 -74.994259) (xy 231.875173 -74.959075) (xy 231.801823 -74.916726) (xy 231.732831 -74.867597)
			(xy 231.668821 -74.812132) (xy 231.610373 -74.750834) (xy 231.558017 -74.684258) (xy 231.512227 -74.613006)
			(xy 231.473416 -74.537725) (xy 231.441937 -74.459095) (xy 231.418076 -74.377828) (xy 231.402047 -74.294662)
			(xy 231.393996 -74.210348) (xy 225.051747 -74.210348) (xy 225.052773 -74.211944) (xy 225.091584 -74.287225)
			(xy 225.123063 -74.365855) (xy 225.146924 -74.447122) (xy 225.162953 -74.530288) (xy 225.171004 -74.614602)
			(xy 225.171508 -74.65695) (xy 225.171004 -74.699298) (xy 225.162953 -74.783612) (xy 225.146924 -74.866778)
			(xy 225.123063 -74.948045) (xy 225.091584 -75.026675) (xy 225.052773 -75.101956) (xy 225.006983 -75.173208)
			(xy 224.954627 -75.239784) (xy 224.896179 -75.301082) (xy 224.832169 -75.356547) (xy 224.763177 -75.405676)
			(xy 224.689827 -75.448025) (xy 224.612784 -75.483209) (xy 224.532745 -75.510911) (xy 224.450436 -75.530879)
			(xy 224.366601 -75.542932) (xy 224.282 -75.546963) (xy 224.197399 -75.542932) (xy 224.113564 -75.530879)
			(xy 224.031255 -75.510911) (xy 223.951216 -75.483209) (xy 223.874173 -75.448025) (xy 223.800823 -75.405676)
			(xy 223.731831 -75.356547) (xy 223.667821 -75.301082) (xy 223.609373 -75.239784) (xy 223.557017 -75.173208)
			(xy 223.511227 -75.101956) (xy 223.472416 -75.026675) (xy 223.440937 -74.948045) (xy 223.417076 -74.866778)
			(xy 223.401047 -74.783612) (xy 223.392996 -74.699298) (xy 220.740507 -74.699298) (xy 220.697257 -74.729938)
			(xy 220.623609 -74.772197) (xy 220.546269 -74.807245) (xy 220.50629 -74.821542) (xy 220.490796 -74.826876)
			(xy 220.472 -74.853038) (xy 220.472 -75.922308) (xy 226.025198 -75.922308) (xy 226.025198 -75.837612)
			(xy 226.033249 -75.753298) (xy 226.049278 -75.670132) (xy 226.073139 -75.588865) (xy 226.104618 -75.510235)
			(xy 226.143429 -75.434954) (xy 226.189219 -75.363702) (xy 226.241575 -75.297126) (xy 226.300023 -75.235828)
			(xy 226.364033 -75.180363) (xy 226.433025 -75.131234) (xy 226.506375 -75.088885) (xy 226.583418 -75.053701)
			(xy 226.663457 -75.025999) (xy 226.745766 -75.006031) (xy 226.829601 -74.993978) (xy 226.914202 -74.989948)
			(xy 226.998803 -74.993978) (xy 227.082638 -75.006031) (xy 227.164947 -75.025999) (xy 227.244986 -75.053701)
			(xy 227.322029 -75.088885) (xy 227.395379 -75.131234) (xy 227.464371 -75.180363) (xy 227.528381 -75.235828)
			(xy 227.586829 -75.297126) (xy 227.639185 -75.363702) (xy 227.684975 -75.434954) (xy 227.723786 -75.510235)
			(xy 227.755265 -75.588865) (xy 227.779126 -75.670132) (xy 227.795155 -75.753298) (xy 227.803206 -75.837612)
			(xy 227.80371 -75.87996) (xy 227.803206 -75.922308) (xy 227.795155 -76.006622) (xy 227.779126 -76.089788)
			(xy 227.755265 -76.171055) (xy 227.723786 -76.249685) (xy 227.684975 -76.324966) (xy 227.639185 -76.396218)
			(xy 227.586829 -76.462794) (xy 227.528381 -76.524092) (xy 227.464371 -76.579557) (xy 227.395379 -76.628686)
			(xy 227.322029 -76.671035) (xy 227.244986 -76.706219) (xy 227.164947 -76.733921) (xy 227.082638 -76.753889)
			(xy 226.998803 -76.765942) (xy 226.914202 -76.769973) (xy 226.829601 -76.765942) (xy 226.745766 -76.753889)
			(xy 226.663457 -76.733921) (xy 226.583418 -76.706219) (xy 226.506375 -76.671035) (xy 226.433025 -76.628686)
			(xy 226.364033 -76.579557) (xy 226.300023 -76.524092) (xy 226.241575 -76.462794) (xy 226.189219 -76.396218)
			(xy 226.143429 -76.324966) (xy 226.104618 -76.249685) (xy 226.073139 -76.171055) (xy 226.049278 -76.089788)
			(xy 226.033249 -76.006622) (xy 226.025198 -75.922308) (xy 220.472 -75.922308) (xy 220.472 -77.893348)
			(xy 229.22001 -77.893348) (xy 229.22001 -77.808652) (xy 229.228061 -77.724338) (xy 229.24409 -77.641172)
			(xy 229.267951 -77.559905) (xy 229.29943 -77.481275) (xy 229.338241 -77.405994) (xy 229.384031 -77.334742)
			(xy 229.436387 -77.268166) (xy 229.494835 -77.206868) (xy 229.558845 -77.151403) (xy 229.627837 -77.102274)
			(xy 229.701187 -77.059925) (xy 229.77823 -77.024741) (xy 229.858269 -76.997039) (xy 229.940578 -76.977071)
			(xy 230.024413 -76.965018) (xy 230.109014 -76.960988) (xy 230.193615 -76.965018) (xy 230.27745 -76.977071)
			(xy 230.359759 -76.997039) (xy 230.439798 -77.024741) (xy 230.516841 -77.059925) (xy 230.590191 -77.102274)
			(xy 230.659183 -77.151403) (xy 230.723193 -77.206868) (xy 230.772279 -77.258348) (xy 238.017046 -77.258348)
			(xy 238.017046 -77.173652) (xy 238.025097 -77.089338) (xy 238.041126 -77.006172) (xy 238.064987 -76.924905)
			(xy 238.096466 -76.846275) (xy 238.135277 -76.770994) (xy 238.181067 -76.699742) (xy 238.233423 -76.633166)
			(xy 238.291871 -76.571868) (xy 238.355881 -76.516403) (xy 238.424873 -76.467274) (xy 238.498223 -76.424925)
			(xy 238.575266 -76.389741) (xy 238.655305 -76.362039) (xy 238.737614 -76.342071) (xy 238.821449 -76.330018)
			(xy 238.90605 -76.325988) (xy 238.990651 -76.330018) (xy 239.074486 -76.342071) (xy 239.156795 -76.362039)
			(xy 239.236834 -76.389741) (xy 239.313877 -76.424925) (xy 239.387227 -76.467274) (xy 239.456219 -76.516403)
			(xy 239.520229 -76.571868) (xy 239.578677 -76.633166) (xy 239.631033 -76.699742) (xy 239.676823 -76.770994)
			(xy 239.715634 -76.846275) (xy 239.747113 -76.924905) (xy 239.770974 -77.006172) (xy 239.787003 -77.089338)
			(xy 239.795054 -77.173652) (xy 239.795558 -77.216) (xy 239.795054 -77.258348) (xy 239.787003 -77.342662)
			(xy 239.770974 -77.425828) (xy 239.747113 -77.507095) (xy 239.715634 -77.585725) (xy 239.676823 -77.661006)
			(xy 239.631033 -77.732258) (xy 239.578677 -77.798834) (xy 239.520229 -77.860132) (xy 239.456219 -77.915597)
			(xy 239.387227 -77.964726) (xy 239.313877 -78.007075) (xy 239.236834 -78.042259) (xy 239.156795 -78.069961)
			(xy 239.074486 -78.089929) (xy 238.990651 -78.101982) (xy 238.90605 -78.106013) (xy 238.821449 -78.101982)
			(xy 238.737614 -78.089929) (xy 238.655305 -78.069961) (xy 238.575266 -78.042259) (xy 238.498223 -78.007075)
			(xy 238.424873 -77.964726) (xy 238.355881 -77.915597) (xy 238.291871 -77.860132) (xy 238.233423 -77.798834)
			(xy 238.181067 -77.732258) (xy 238.135277 -77.661006) (xy 238.096466 -77.585725) (xy 238.064987 -77.507095)
			(xy 238.041126 -77.425828) (xy 238.025097 -77.342662) (xy 238.017046 -77.258348) (xy 230.772279 -77.258348)
			(xy 230.781641 -77.268166) (xy 230.833997 -77.334742) (xy 230.879787 -77.405994) (xy 230.918598 -77.481275)
			(xy 230.950077 -77.559905) (xy 230.973938 -77.641172) (xy 230.989967 -77.724338) (xy 230.998018 -77.808652)
			(xy 230.998522 -77.851) (xy 230.998018 -77.893348) (xy 230.989967 -77.977662) (xy 230.973938 -78.060828)
			(xy 230.950077 -78.142095) (xy 230.918598 -78.220725) (xy 230.879787 -78.296006) (xy 230.833997 -78.367258)
			(xy 230.781641 -78.433834) (xy 230.723193 -78.495132) (xy 230.659183 -78.550597) (xy 230.590191 -78.599726)
			(xy 230.516841 -78.642075) (xy 230.439798 -78.677259) (xy 230.359759 -78.704961) (xy 230.27745 -78.724929)
			(xy 230.193615 -78.736982) (xy 230.109014 -78.741013) (xy 230.024413 -78.736982) (xy 229.940578 -78.724929)
			(xy 229.858269 -78.704961) (xy 229.77823 -78.677259) (xy 229.701187 -78.642075) (xy 229.627837 -78.599726)
			(xy 229.558845 -78.550597) (xy 229.494835 -78.495132) (xy 229.436387 -78.433834) (xy 229.384031 -78.367258)
			(xy 229.338241 -78.296006) (xy 229.29943 -78.220725) (xy 229.267951 -78.142095) (xy 229.24409 -78.060828)
			(xy 229.228061 -77.977662) (xy 229.22001 -77.893348) (xy 220.472 -77.893348) (xy 220.472 -78.544166)
			(xy 220.472699 -78.556901) (xy 220.484825 -78.579302) (xy 220.495114 -78.586838) (xy 220.577664 -78.640178)
			(xy 220.603572 -78.64221) (xy 220.615256 -78.636876) (xy 220.658364 -78.618164) (xy 220.747664 -78.588877)
			(xy 220.839554 -78.569165) (xy 220.93301 -78.559249) (xy 220.98 -78.558644) (xy 221.022351 -78.559148)
			(xy 221.106669 -78.567199) (xy 221.18984 -78.583229) (xy 221.27111 -78.607092) (xy 221.349744 -78.638572)
			(xy 221.42503 -78.677385) (xy 221.496286 -78.723178) (xy 221.562866 -78.775537) (xy 221.624167 -78.833988)
			(xy 221.679635 -78.898001) (xy 221.728767 -78.966997) (xy 221.771117 -79.040351) (xy 221.806304 -79.117398)
			(xy 221.834007 -79.197441) (xy 221.853976 -79.279755) (xy 221.86603 -79.363594) (xy 221.870061 -79.4482)
			(xy 221.867235 -79.507518) (xy 222.630996 -79.507518) (xy 222.630996 -79.422822) (xy 222.639047 -79.338508)
			(xy 222.655076 -79.255342) (xy 222.678937 -79.174075) (xy 222.710416 -79.095445) (xy 222.749227 -79.020164)
			(xy 222.795017 -78.948912) (xy 222.847373 -78.882336) (xy 222.905821 -78.821038) (xy 222.969831 -78.765573)
			(xy 223.038823 -78.716444) (xy 223.112173 -78.674095) (xy 223.189216 -78.638911) (xy 223.269255 -78.611209)
			(xy 223.351564 -78.591241) (xy 223.435399 -78.579188) (xy 223.52 -78.575158) (xy 223.604601 -78.579188)
			(xy 223.688436 -78.591241) (xy 223.770745 -78.611209) (xy 223.850784 -78.638911) (xy 223.927827 -78.674095)
			(xy 224.001177 -78.716444) (xy 224.061624 -78.759488) (xy 236.14278 -78.759488) (xy 236.14278 -78.674792)
			(xy 236.150831 -78.590478) (xy 236.16686 -78.507312) (xy 236.190721 -78.426045) (xy 236.2222 -78.347415)
			(xy 236.261011 -78.272134) (xy 236.306801 -78.200882) (xy 236.359157 -78.134306) (xy 236.417605 -78.073008)
			(xy 236.481615 -78.017543) (xy 236.550607 -77.968414) (xy 236.623957 -77.926065) (xy 236.701 -77.890881)
			(xy 236.781039 -77.863179) (xy 236.863348 -77.843211) (xy 236.947183 -77.831158) (xy 237.031784 -77.827128)
			(xy 237.116385 -77.831158) (xy 237.20022 -77.843211) (xy 237.282529 -77.863179) (xy 237.362568 -77.890881)
			(xy 237.439611 -77.926065) (xy 237.512961 -77.968414) (xy 237.581953 -78.017543) (xy 237.645963 -78.073008)
			(xy 237.704411 -78.134306) (xy 237.756767 -78.200882) (xy 237.802557 -78.272134) (xy 237.841368 -78.347415)
			(xy 237.872847 -78.426045) (xy 237.896708 -78.507312) (xy 237.912737 -78.590478) (xy 237.920788 -78.674792)
			(xy 237.921292 -78.71714) (xy 237.920788 -78.759488) (xy 237.912737 -78.843802) (xy 237.896708 -78.926968)
			(xy 237.872847 -79.008235) (xy 237.841368 -79.086865) (xy 237.802557 -79.162146) (xy 237.756767 -79.233398)
			(xy 237.704411 -79.299974) (xy 237.645963 -79.361272) (xy 237.581953 -79.416737) (xy 237.512961 -79.465866)
			(xy 237.439611 -79.508215) (xy 237.362568 -79.543399) (xy 237.282529 -79.571101) (xy 237.20022 -79.591069)
			(xy 237.116385 -79.603122) (xy 237.031784 -79.607153) (xy 236.947183 -79.603122) (xy 236.863348 -79.591069)
			(xy 236.781039 -79.571101) (xy 236.701 -79.543399) (xy 236.623957 -79.508215) (xy 236.550607 -79.465866)
			(xy 236.481615 -79.416737) (xy 236.417605 -79.361272) (xy 236.359157 -79.299974) (xy 236.306801 -79.233398)
			(xy 236.261011 -79.162146) (xy 236.2222 -79.086865) (xy 236.190721 -79.008235) (xy 236.16686 -78.926968)
			(xy 236.150831 -78.843802) (xy 236.14278 -78.759488) (xy 224.061624 -78.759488) (xy 224.070169 -78.765573)
			(xy 224.134179 -78.821038) (xy 224.192627 -78.882336) (xy 224.244983 -78.948912) (xy 224.290773 -79.020164)
			(xy 224.329584 -79.095445) (xy 224.361063 -79.174075) (xy 224.384924 -79.255342) (xy 224.400953 -79.338508)
			(xy 224.409004 -79.422822) (xy 224.409508 -79.46517) (xy 224.409004 -79.507518) (xy 224.400953 -79.591832)
			(xy 224.384924 -79.674998) (xy 224.361063 -79.756265) (xy 224.329584 -79.834895) (xy 224.290773 -79.910176)
			(xy 224.244983 -79.981428) (xy 224.192627 -80.048004) (xy 224.134179 -80.109302) (xy 224.087052 -80.150138)
			(xy 238.67643 -80.150138) (xy 238.67643 -80.065442) (xy 238.684481 -79.981128) (xy 238.70051 -79.897962)
			(xy 238.724371 -79.816695) (xy 238.75585 -79.738065) (xy 238.794661 -79.662784) (xy 238.840451 -79.591532)
			(xy 238.892807 -79.524956) (xy 238.951255 -79.463658) (xy 239.015265 -79.408193) (xy 239.084257 -79.359064)
			(xy 239.157607 -79.316715) (xy 239.23465 -79.281531) (xy 239.314689 -79.253829) (xy 239.396998 -79.233861)
			(xy 239.480833 -79.221808) (xy 239.565434 -79.217778) (xy 239.650035 -79.221808) (xy 239.73387 -79.233861)
			(xy 239.816179 -79.253829) (xy 239.896218 -79.281531) (xy 239.973261 -79.316715) (xy 240.046611 -79.359064)
			(xy 240.115603 -79.408193) (xy 240.179613 -79.463658) (xy 240.238061 -79.524956) (xy 240.290417 -79.591532)
			(xy 240.336207 -79.662784) (xy 240.375018 -79.738065) (xy 240.406497 -79.816695) (xy 240.430358 -79.897962)
			(xy 240.446387 -79.981128) (xy 240.454438 -80.065442) (xy 240.454942 -80.10779) (xy 240.454438 -80.150138)
			(xy 240.446387 -80.234452) (xy 240.430358 -80.317618) (xy 240.406497 -80.398885) (xy 240.375018 -80.477515)
			(xy 240.336207 -80.552796) (xy 240.290417 -80.624048) (xy 240.238061 -80.690624) (xy 240.179613 -80.751922)
			(xy 240.115603 -80.807387) (xy 240.046611 -80.856516) (xy 239.973261 -80.898865) (xy 239.896218 -80.934049)
			(xy 239.816179 -80.961751) (xy 239.73387 -80.981719) (xy 239.650035 -80.993772) (xy 239.565434 -80.997803)
			(xy 239.480833 -80.993772) (xy 239.396998 -80.981719) (xy 239.314689 -80.961751) (xy 239.23465 -80.934049)
			(xy 239.157607 -80.898865) (xy 239.084257 -80.856516) (xy 239.015265 -80.807387) (xy 238.951255 -80.751922)
			(xy 238.892807 -80.690624) (xy 238.840451 -80.624048) (xy 238.794661 -80.552796) (xy 238.75585 -80.477515)
			(xy 238.724371 -80.398885) (xy 238.70051 -80.317618) (xy 238.684481 -80.234452) (xy 238.67643 -80.150138)
			(xy 224.087052 -80.150138) (xy 224.070169 -80.164767) (xy 224.001177 -80.213896) (xy 223.927827 -80.256245)
			(xy 223.850784 -80.291429) (xy 223.770745 -80.319131) (xy 223.688436 -80.339099) (xy 223.604601 -80.351152)
			(xy 223.52 -80.355183) (xy 223.435399 -80.351152) (xy 223.351564 -80.339099) (xy 223.269255 -80.319131)
			(xy 223.189216 -80.291429) (xy 223.112173 -80.256245) (xy 223.038823 -80.213896) (xy 222.969831 -80.164767)
			(xy 222.905821 -80.109302) (xy 222.847373 -80.048004) (xy 222.795017 -79.981428) (xy 222.749227 -79.910176)
			(xy 222.710416 -79.834895) (xy 222.678937 -79.756265) (xy 222.655076 -79.674998) (xy 222.639047 -79.591832)
			(xy 222.630996 -79.507518) (xy 221.867235 -79.507518) (xy 221.86603 -79.532806) (xy 221.853976 -79.616645)
			(xy 221.834007 -79.698959) (xy 221.806304 -79.779002) (xy 221.771117 -79.856049) (xy 221.728767 -79.929403)
			(xy 221.679635 -79.998399) (xy 221.624167 -80.062412) (xy 221.562866 -80.120863) (xy 221.496286 -80.173222)
			(xy 221.42503 -80.219015) (xy 221.349744 -80.257828) (xy 221.27111 -80.289308) (xy 221.18984 -80.313171)
			(xy 221.106669 -80.329201) (xy 221.022351 -80.337252) (xy 220.98 -80.33766) (xy 220.93301 -80.33705)
			(xy 220.839554 -80.327138) (xy 220.747665 -80.307426) (xy 220.658367 -80.278134) (xy 220.615256 -80.259428)
			(xy 220.603572 -80.254094) (xy 220.577664 -80.256126) (xy 220.495114 -80.309466) (xy 220.488187 -80.31433)
			(xy 220.477783 -80.327669) (xy 220.47232 -80.343678) (xy 220.472 -80.352138) (xy 220.472 -80.934814)
			(xy 220.471574 -80.944883) (xy 220.463856 -80.963484) (xy 220.457014 -80.970882) (xy 220.012584 -81.415312)
			(xy 229.22001 -81.415312) (xy 229.22001 -81.330616) (xy 229.228061 -81.246302) (xy 229.24409 -81.163136)
			(xy 229.267951 -81.081869) (xy 229.29943 -81.003239) (xy 229.338241 -80.927958) (xy 229.384031 -80.856706)
			(xy 229.436387 -80.79013) (xy 229.494835 -80.728832) (xy 229.558845 -80.673367) (xy 229.627837 -80.624238)
			(xy 229.701187 -80.581889) (xy 229.77823 -80.546705) (xy 229.858269 -80.519003) (xy 229.940578 -80.499035)
			(xy 230.024413 -80.486982) (xy 230.109014 -80.482952) (xy 230.193615 -80.486982) (xy 230.27745 -80.499035)
			(xy 230.359759 -80.519003) (xy 230.439798 -80.546705) (xy 230.516841 -80.581889) (xy 230.590191 -80.624238)
			(xy 230.659183 -80.673367) (xy 230.723193 -80.728832) (xy 230.781641 -80.79013) (xy 230.833997 -80.856706)
			(xy 230.879787 -80.927958) (xy 230.918598 -81.003239) (xy 230.950077 -81.081869) (xy 230.973938 -81.163136)
			(xy 230.989967 -81.246302) (xy 230.998018 -81.330616) (xy 230.998522 -81.372964) (xy 230.998018 -81.415312)
			(xy 230.989967 -81.499626) (xy 230.973938 -81.582792) (xy 230.950077 -81.664059) (xy 230.918598 -81.742689)
			(xy 230.879787 -81.81797) (xy 230.833997 -81.889222) (xy 230.781641 -81.955798) (xy 230.723193 -82.017096)
			(xy 230.659183 -82.072561) (xy 230.590191 -82.12169) (xy 230.516841 -82.164039) (xy 230.439798 -82.199223)
			(xy 230.359759 -82.226925) (xy 230.27745 -82.246893) (xy 230.193615 -82.258946) (xy 230.109014 -82.262977)
			(xy 230.024413 -82.258946) (xy 229.940578 -82.246893) (xy 229.858269 -82.226925) (xy 229.77823 -82.199223)
			(xy 229.701187 -82.164039) (xy 229.627837 -82.12169) (xy 229.558845 -82.072561) (xy 229.494835 -82.017096)
			(xy 229.436387 -81.955798) (xy 229.384031 -81.889222) (xy 229.338241 -81.81797) (xy 229.29943 -81.742689)
			(xy 229.267951 -81.664059) (xy 229.24409 -81.582792) (xy 229.228061 -81.499626) (xy 229.22001 -81.415312)
			(xy 220.012584 -81.415312) (xy 219.249244 -82.178652) (xy 219.241845 -82.185495) (xy 219.223246 -82.193216)
			(xy 219.213176 -82.193638) (xy 213.36 -82.193638) (xy 213.350899 -82.194019) (xy 213.333855 -82.200411)
			(xy 213.326726 -82.206084) (xy 213.2944 -82.233473) (xy 213.225397 -82.28265) (xy 213.152031 -82.325041)
			(xy 213.074964 -82.360261) (xy 212.994898 -82.387991) (xy 212.912556 -82.40798) (xy 212.828687 -82.420047)
			(xy 212.74405 -82.424081) (xy 212.659413 -82.420047) (xy 212.575544 -82.40798) (xy 212.493202 -82.387991)
			(xy 212.413136 -82.360261) (xy 212.336069 -82.325041) (xy 212.262703 -82.28265) (xy 212.1937 -82.233473)
			(xy 212.161374 -82.206084) (xy 212.154252 -82.200404) (xy 212.137202 -82.194025) (xy 212.1281 -82.193638)
			(xy 203.784454 -82.193638) (xy 203.774578 -82.194102) (xy 203.756281 -82.201545) (xy 203.748894 -82.208116)
			(xy 203.690982 -82.264758) (xy 203.683108 -82.282792) (xy 203.682854 -82.292698) (xy 203.681268 -82.335654)
			(xy 203.670852 -82.420986) (xy 203.652252 -82.504914) (xy 203.625642 -82.586657) (xy 203.591271 -82.665451)
			(xy 203.549458 -82.740562) (xy 203.500595 -82.811289) (xy 203.445136 -82.876972) (xy 203.383599 -82.936999)
			(xy 203.316559 -82.990809) (xy 203.24464 -83.0379) (xy 203.168513 -83.077834) (xy 203.088889 -83.110237)
			(xy 203.006511 -83.134808) (xy 202.922146 -83.151317) (xy 202.836582 -83.15961) (xy 202.7936 -83.160108)
			(xy 202.750735 -83.159595) (xy 202.665403 -83.151347) (xy 202.581261 -83.134927) (xy 202.499088 -83.110488)
			(xy 202.419648 -83.078257) (xy 202.343678 -83.038532) (xy 202.271882 -82.991682) (xy 202.238102 -82.96529)
			(xy 202.228788 -82.958637) (xy 202.206522 -82.953472) (xy 202.184212 -82.958445) (xy 202.174856 -82.965036)
			(xy 202.141273 -82.990774) (xy 202.070066 -83.036483) (xy 201.99484 -83.075226) (xy 201.916276 -83.106652)
			(xy 201.835083 -83.130477) (xy 201.751995 -83.146486) (xy 201.667762 -83.154534) (xy 201.625454 -83.155028)
			(xy 201.6252 -83.155028) (xy 201.583834 -83.154556) (xy 201.50146 -83.146874) (xy 201.420155 -83.131576)
			(xy 201.340622 -83.108795) (xy 201.263547 -83.078727) (xy 201.189598 -83.041633) (xy 201.119412 -82.997832)
			(xy 201.053597 -82.947703) (xy 200.992721 -82.89168) (xy 200.93731 -82.830246) (xy 200.887842 -82.763932)
			(xy 200.844746 -82.693312) (xy 200.808394 -82.618995) (xy 200.779099 -82.541624) (xy 200.757115 -82.461866)
			(xy 200.749408 -82.421222) (xy 200.747379 -82.412175) (xy 200.737853 -82.396286) (xy 200.723309 -82.384812)
			(xy 200.71461 -82.381598) (xy 200.628758 -82.35442) (xy 200.619768 -82.35202) (xy 200.601209 -82.353131)
			(xy 200.584266 -82.360788) (xy 200.57745 -82.36712) (xy 200.342754 -82.601816) (xy 200.335904 -82.609213)
			(xy 200.328167 -82.627811) (xy 200.327768 -82.637884) (xy 200.327768 -83.608348) (xy 207.263996 -83.608348)
			(xy 207.263996 -83.523652) (xy 207.272047 -83.439338) (xy 207.288076 -83.356172) (xy 207.311937 -83.274905)
			(xy 207.343416 -83.196275) (xy 207.382227 -83.120994) (xy 207.428017 -83.049742) (xy 207.480373 -82.983166)
			(xy 207.538821 -82.921868) (xy 207.602831 -82.866403) (xy 207.671823 -82.817274) (xy 207.745173 -82.774925)
			(xy 207.822216 -82.739741) (xy 207.902255 -82.712039) (xy 207.984564 -82.692071) (xy 208.068399 -82.680018)
			(xy 208.153 -82.675988) (xy 208.237601 -82.680018) (xy 208.321436 -82.692071) (xy 208.403745 -82.712039)
			(xy 208.483784 -82.739741) (xy 208.560827 -82.774925) (xy 208.634177 -82.817274) (xy 208.703169 -82.866403)
			(xy 208.767179 -82.921868) (xy 208.825627 -82.983166) (xy 208.877983 -83.049742) (xy 208.923773 -83.120994)
			(xy 208.962584 -83.196275) (xy 208.994063 -83.274905) (xy 209.017924 -83.356172) (xy 209.033953 -83.439338)
			(xy 209.042004 -83.523652) (xy 209.042508 -83.566) (xy 209.042004 -83.608348) (xy 209.295996 -83.608348)
			(xy 209.295996 -83.523652) (xy 209.304047 -83.439338) (xy 209.320076 -83.356172) (xy 209.343937 -83.274905)
			(xy 209.375416 -83.196275) (xy 209.414227 -83.120994) (xy 209.460017 -83.049742) (xy 209.512373 -82.983166)
			(xy 209.570821 -82.921868) (xy 209.634831 -82.866403) (xy 209.703823 -82.817274) (xy 209.777173 -82.774925)
			(xy 209.854216 -82.739741) (xy 209.934255 -82.712039) (xy 210.016564 -82.692071) (xy 210.100399 -82.680018)
			(xy 210.185 -82.675988) (xy 210.269601 -82.680018) (xy 210.353436 -82.692071) (xy 210.435745 -82.712039)
			(xy 210.515784 -82.739741) (xy 210.592827 -82.774925) (xy 210.666177 -82.817274) (xy 210.735169 -82.866403)
			(xy 210.799179 -82.921868) (xy 210.857627 -82.983166) (xy 210.909983 -83.049742) (xy 210.955773 -83.120994)
			(xy 210.994584 -83.196275) (xy 211.026063 -83.274905) (xy 211.035075 -83.3056) (xy 228.599038 -83.3056)
			(xy 228.603067 -83.221004) (xy 228.61512 -83.137173) (xy 228.635087 -83.054869) (xy 228.662787 -82.974834)
			(xy 228.69797 -82.897796) (xy 228.740316 -82.82445) (xy 228.789442 -82.755462) (xy 228.844904 -82.691456)
			(xy 228.906199 -82.633011) (xy 228.972771 -82.580658) (xy 229.044019 -82.53487) (xy 229.119296 -82.496062)
			(xy 229.197922 -82.464585) (xy 229.279183 -82.440724) (xy 229.362345 -82.424696) (xy 229.446654 -82.416646)
			(xy 229.489 -82.416142) (xy 229.489254 -82.416142) (xy 229.53074 -82.416636) (xy 229.613348 -82.42441)
			(xy 229.694874 -82.439838) (xy 229.77461 -82.462787) (xy 229.851864 -82.493056) (xy 229.925966 -82.530385)
			(xy 229.996272 -82.574448) (xy 230.029512 -82.599276) (xy 230.038711 -82.605619) (xy 230.0605 -82.61045)
			(xy 230.082289 -82.605619) (xy 230.091488 -82.599276) (xy 230.124731 -82.574418) (xy 230.195061 -82.530318)
			(xy 230.269196 -82.492966) (xy 230.34649 -82.462689) (xy 230.42627 -82.439749) (xy 230.507841 -82.424347)
			(xy 230.590494 -82.416617) (xy 230.632 -82.416142) (xy 230.673504 -82.416625) (xy 230.75615 -82.424382)
			(xy 230.837715 -82.4398) (xy 230.91749 -82.462746) (xy 230.994781 -82.493019) (xy 231.068918 -82.530358)
			(xy 231.139257 -82.574437) (xy 231.172512 -82.599276) (xy 231.181711 -82.605619) (xy 231.2035 -82.61045)
			(xy 231.225289 -82.605619) (xy 231.234488 -82.599276) (xy 231.267716 -82.574429) (xy 231.338013 -82.530345)
			(xy 231.412113 -82.493003) (xy 231.489369 -82.462729) (xy 231.569111 -82.439787) (xy 231.650644 -82.424375)
			(xy 231.733258 -82.416628) (xy 231.774746 -82.416142) (xy 231.775 -82.416142) (xy 231.817351 -82.416546)
			(xy 231.901669 -82.424597) (xy 231.98484 -82.440627) (xy 232.066111 -82.46449) (xy 232.144745 -82.495971)
			(xy 232.220031 -82.534783) (xy 232.291287 -82.580576) (xy 232.357867 -82.632936) (xy 232.419169 -82.691387)
			(xy 232.474636 -82.7554) (xy 232.523768 -82.824396) (xy 232.566119 -82.89775) (xy 232.601305 -82.974797)
			(xy 232.629009 -83.05484) (xy 232.648978 -83.137155) (xy 232.661032 -83.220994) (xy 232.665063 -83.3056)
			(xy 232.661032 -83.390206) (xy 232.648978 -83.474045) (xy 232.629009 -83.55636) (xy 232.601305 -83.636403)
			(xy 232.566119 -83.71345) (xy 232.523768 -83.786804) (xy 232.474636 -83.8558) (xy 232.419169 -83.919813)
			(xy 232.357867 -83.978264) (xy 232.291287 -84.030624) (xy 232.220031 -84.076417) (xy 232.144745 -84.115229)
			(xy 232.066111 -84.14671) (xy 231.98484 -84.170573) (xy 231.901669 -84.186603) (xy 231.817351 -84.194654)
			(xy 231.775 -84.195158) (xy 231.774746 -84.195158) (xy 231.73326 -84.194664) (xy 231.650652 -84.18689)
			(xy 231.569126 -84.171462) (xy 231.48939 -84.148513) (xy 231.412136 -84.118244) (xy 231.338034 -84.080915)
			(xy 231.267728 -84.036852) (xy 231.234488 -84.012024) (xy 231.225289 -84.005681) (xy 231.2035 -84.00085)
			(xy 231.181711 -84.005681) (xy 231.172512 -84.012024) (xy 231.139269 -84.036882) (xy 231.068939 -84.080982)
			(xy 230.994804 -84.118334) (xy 230.91751 -84.148611) (xy 230.83773 -84.171551) (xy 230.756159 -84.186953)
			(xy 230.673506 -84.194683) (xy 230.632 -84.195158) (xy 230.590496 -84.194675) (xy 230.50785 -84.186918)
			(xy 230.426285 -84.1715) (xy 230.34651 -84.148554) (xy 230.269219 -84.118281) (xy 230.195082 -84.080942)
			(xy 230.124743 -84.036863) (xy 230.091488 -84.012024) (xy 230.082289 -84.005681) (xy 230.0605 -84.00085)
			(xy 230.038711 -84.005681) (xy 230.029512 -84.012024) (xy 229.996284 -84.036871) (xy 229.925987 -84.080955)
			(xy 229.851887 -84.118297) (xy 229.774631 -84.148571) (xy 229.694889 -84.171513) (xy 229.613356 -84.186925)
			(xy 229.530742 -84.194672) (xy 229.489254 -84.195158) (xy 229.489 -84.195158) (xy 229.446654 -84.194554)
			(xy 229.362345 -84.186504) (xy 229.279183 -84.170476) (xy 229.197922 -84.146615) (xy 229.119296 -84.115138)
			(xy 229.044019 -84.07633) (xy 228.972771 -84.030542) (xy 228.906199 -83.978189) (xy 228.844904 -83.919744)
			(xy 228.789442 -83.855738) (xy 228.740316 -83.78675) (xy 228.69797 -83.713404) (xy 228.662787 -83.636366)
			(xy 228.635087 -83.556331) (xy 228.61512 -83.474027) (xy 228.603067 -83.390196) (xy 228.599038 -83.3056)
			(xy 211.035075 -83.3056) (xy 211.049924 -83.356172) (xy 211.065953 -83.439338) (xy 211.074004 -83.523652)
			(xy 211.074508 -83.566) (xy 211.074004 -83.608348) (xy 211.065953 -83.692662) (xy 211.049924 -83.775828)
			(xy 211.026063 -83.857095) (xy 210.994584 -83.935725) (xy 210.955773 -84.011006) (xy 210.909983 -84.082258)
			(xy 210.857627 -84.148834) (xy 210.799179 -84.210132) (xy 210.735169 -84.265597) (xy 210.666177 -84.314726)
			(xy 210.592827 -84.357075) (xy 210.515784 -84.392259) (xy 210.435745 -84.419961) (xy 210.353436 -84.439929)
			(xy 210.269601 -84.451982) (xy 210.185 -84.456013) (xy 210.100399 -84.451982) (xy 210.016564 -84.439929)
			(xy 209.934255 -84.419961) (xy 209.854216 -84.392259) (xy 209.777173 -84.357075) (xy 209.703823 -84.314726)
			(xy 209.634831 -84.265597) (xy 209.570821 -84.210132) (xy 209.512373 -84.148834) (xy 209.460017 -84.082258)
			(xy 209.414227 -84.011006) (xy 209.375416 -83.935725) (xy 209.343937 -83.857095) (xy 209.320076 -83.775828)
			(xy 209.304047 -83.692662) (xy 209.295996 -83.608348) (xy 209.042004 -83.608348) (xy 209.033953 -83.692662)
			(xy 209.017924 -83.775828) (xy 208.994063 -83.857095) (xy 208.962584 -83.935725) (xy 208.923773 -84.011006)
			(xy 208.877983 -84.082258) (xy 208.825627 -84.148834) (xy 208.767179 -84.210132) (xy 208.703169 -84.265597)
			(xy 208.634177 -84.314726) (xy 208.560827 -84.357075) (xy 208.483784 -84.392259) (xy 208.403745 -84.419961)
			(xy 208.321436 -84.439929) (xy 208.237601 -84.451982) (xy 208.153 -84.456013) (xy 208.068399 -84.451982)
			(xy 207.984564 -84.439929) (xy 207.902255 -84.419961) (xy 207.822216 -84.392259) (xy 207.745173 -84.357075)
			(xy 207.671823 -84.314726) (xy 207.602831 -84.265597) (xy 207.538821 -84.210132) (xy 207.480373 -84.148834)
			(xy 207.428017 -84.082258) (xy 207.382227 -84.011006) (xy 207.343416 -83.935725) (xy 207.311937 -83.857095)
			(xy 207.288076 -83.775828) (xy 207.272047 -83.692662) (xy 207.263996 -83.608348) (xy 200.327768 -83.608348)
			(xy 200.327768 -84.749386) (xy 200.328371 -84.760428) (xy 200.337724 -84.780441) (xy 200.345802 -84.787994)
			(xy 200.378224 -84.81612) (xy 200.438087 -84.877637) (xy 200.438656 -84.878348) (xy 204.450946 -84.878348)
			(xy 204.450946 -84.793652) (xy 204.458997 -84.709338) (xy 204.475026 -84.626172) (xy 204.498887 -84.544905)
			(xy 204.530366 -84.466275) (xy 204.569177 -84.390994) (xy 204.614967 -84.319742) (xy 204.667323 -84.253166)
			(xy 204.725771 -84.191868) (xy 204.789781 -84.136403) (xy 204.858773 -84.087274) (xy 204.932123 -84.044925)
			(xy 205.009166 -84.009741) (xy 205.089205 -83.982039) (xy 205.171514 -83.962071) (xy 205.255349 -83.950018)
			(xy 205.33995 -83.945988) (xy 205.424551 -83.950018) (xy 205.508386 -83.962071) (xy 205.590695 -83.982039)
			(xy 205.670734 -84.009741) (xy 205.747777 -84.044925) (xy 205.821127 -84.087274) (xy 205.890119 -84.136403)
			(xy 205.954129 -84.191868) (xy 206.012577 -84.253166) (xy 206.064933 -84.319742) (xy 206.110723 -84.390994)
			(xy 206.149534 -84.466275) (xy 206.181013 -84.544905) (xy 206.204874 -84.626172) (xy 206.220903 -84.709338)
			(xy 206.228954 -84.793652) (xy 206.229458 -84.836) (xy 206.228954 -84.878348) (xy 206.220903 -84.962662)
			(xy 206.204874 -85.045828) (xy 206.181013 -85.127095) (xy 206.149534 -85.205725) (xy 206.110723 -85.281006)
			(xy 206.064933 -85.352258) (xy 206.012577 -85.418834) (xy 205.954129 -85.480132) (xy 205.890119 -85.535597)
			(xy 205.821127 -85.584726) (xy 205.747777 -85.627075) (xy 205.670734 -85.662259) (xy 205.590695 -85.689961)
			(xy 205.508386 -85.709929) (xy 205.424551 -85.721982) (xy 205.33995 -85.726013) (xy 205.255349 -85.721982)
			(xy 205.171514 -85.709929) (xy 205.089205 -85.689961) (xy 205.009166 -85.662259) (xy 204.932123 -85.627075)
			(xy 204.858773 -85.584726) (xy 204.789781 -85.535597) (xy 204.725771 -85.480132) (xy 204.667323 -85.418834)
			(xy 204.614967 -85.352258) (xy 204.569177 -85.281006) (xy 204.530366 -85.205725) (xy 204.498887 -85.127095)
			(xy 204.475026 -85.045828) (xy 204.458997 -84.962662) (xy 204.450946 -84.878348) (xy 200.438656 -84.878348)
			(xy 200.491746 -84.944634) (xy 200.538701 -85.016488) (xy 200.578517 -85.092532) (xy 200.610823 -85.172056)
			(xy 200.635319 -85.254323) (xy 200.651776 -85.338568) (xy 200.660042 -85.424005) (xy 200.66004 -85.509841)
			(xy 200.65177 -85.595279) (xy 200.635308 -85.679522) (xy 200.610808 -85.761787) (xy 200.578498 -85.841311)
			(xy 200.538678 -85.917352) (xy 200.491718 -85.989204) (xy 200.438056 -86.056198) (xy 200.37819 -86.117712)
			(xy 200.345802 -86.145878) (xy 200.337707 -86.153417) (xy 200.328362 -86.173439) (xy 200.327768 -86.184486)
			(xy 200.327768 -86.290588) (xy 208.90001 -86.290588) (xy 208.90001 -86.205892) (xy 208.908061 -86.121578)
			(xy 208.92409 -86.038412) (xy 208.947951 -85.957145) (xy 208.97943 -85.878515) (xy 209.018241 -85.803234)
			(xy 209.064031 -85.731982) (xy 209.116387 -85.665406) (xy 209.174835 -85.604108) (xy 209.238845 -85.548643)
			(xy 209.307837 -85.499514) (xy 209.381187 -85.457165) (xy 209.45823 -85.421981) (xy 209.538269 -85.394279)
			(xy 209.620578 -85.374311) (xy 209.704413 -85.362258) (xy 209.789014 -85.358228) (xy 209.873615 -85.362258)
			(xy 209.882949 -85.3636) (xy 213.67893 -85.3636) (xy 213.682961 -85.278991) (xy 213.695016 -85.195148)
			(xy 213.714986 -85.112831) (xy 213.742691 -85.032785) (xy 213.77788 -84.955736) (xy 213.820233 -84.88238)
			(xy 213.869368 -84.813382) (xy 213.924839 -84.749367) (xy 213.986145 -84.690916) (xy 214.052729 -84.638556)
			(xy 214.123988 -84.592763) (xy 214.199278 -84.553952) (xy 214.277916 -84.522473) (xy 214.359191 -84.498612)
			(xy 214.442366 -84.482584) (xy 214.526688 -84.474536) (xy 214.56904 -84.47405) (xy 214.60972 -84.474496)
			(xy 214.69074 -84.48194) (xy 214.770741 -84.496753) (xy 214.849054 -84.518811) (xy 214.925026 -84.54793)
			(xy 214.961724 -84.56549) (xy 214.96997 -84.569173) (xy 214.987925 -84.571017) (xy 215.005407 -84.566521)
			(xy 215.013032 -84.56168) (xy 215.050238 -84.536605) (xy 215.128788 -84.493234) (xy 215.211307 -84.457999)
			(xy 215.296956 -84.431256) (xy 215.384864 -84.413278) (xy 215.474136 -84.404248) (xy 215.519 -84.403692)
			(xy 215.561348 -84.404196) (xy 215.645662 -84.412247) (xy 215.728828 -84.428276) (xy 215.810095 -84.452137)
			(xy 215.888725 -84.483616) (xy 215.964006 -84.522427) (xy 216.035258 -84.568217) (xy 216.101834 -84.620573)
			(xy 216.163132 -84.679021) (xy 216.218597 -84.743031) (xy 216.267726 -84.812023) (xy 216.310075 -84.885373)
			(xy 216.345259 -84.962416) (xy 216.372961 -85.042455) (xy 216.392929 -85.124764) (xy 216.404982 -85.208599)
			(xy 216.409013 -85.2932) (xy 216.404982 -85.377801) (xy 216.392929 -85.461636) (xy 216.372961 -85.543945)
			(xy 216.345259 -85.623984) (xy 216.328854 -85.659906) (xy 231.841036 -85.659906) (xy 231.841036 -85.57521)
			(xy 231.849087 -85.490896) (xy 231.865116 -85.40773) (xy 231.888977 -85.326463) (xy 231.920456 -85.247833)
			(xy 231.959267 -85.172552) (xy 232.005057 -85.1013) (xy 232.057413 -85.034724) (xy 232.115861 -84.973426)
			(xy 232.179871 -84.917961) (xy 232.248863 -84.868832) (xy 232.322213 -84.826483) (xy 232.399256 -84.791299)
			(xy 232.479295 -84.763597) (xy 232.561604 -84.743629) (xy 232.645439 -84.731576) (xy 232.73004 -84.727546)
			(xy 232.814641 -84.731576) (xy 232.898476 -84.743629) (xy 232.980785 -84.763597) (xy 233.060824 -84.791299)
			(xy 233.137867 -84.826483) (xy 233.211217 -84.868832) (xy 233.280209 -84.917961) (xy 233.344219 -84.973426)
			(xy 233.402667 -85.034724) (xy 233.455023 -85.1013) (xy 233.500813 -85.172552) (xy 233.539624 -85.247833)
			(xy 233.571103 -85.326463) (xy 233.594964 -85.40773) (xy 233.610993 -85.490896) (xy 233.619044 -85.57521)
			(xy 233.619548 -85.617558) (xy 233.619044 -85.659906) (xy 233.610993 -85.74422) (xy 233.594964 -85.827386)
			(xy 233.571103 -85.908653) (xy 233.539624 -85.987283) (xy 233.500813 -86.062564) (xy 233.455023 -86.133816)
			(xy 233.402667 -86.200392) (xy 233.344219 -86.26169) (xy 233.280209 -86.317155) (xy 233.211217 -86.366284)
			(xy 233.137867 -86.408633) (xy 233.060824 -86.443817) (xy 232.980785 -86.471519) (xy 232.898476 -86.491487)
			(xy 232.814641 -86.50354) (xy 232.73004 -86.507571) (xy 232.645439 -86.50354) (xy 232.561604 -86.491487)
			(xy 232.479295 -86.471519) (xy 232.399256 -86.443817) (xy 232.322213 -86.408633) (xy 232.248863 -86.366284)
			(xy 232.179871 -86.317155) (xy 232.115861 -86.26169) (xy 232.057413 -86.200392) (xy 232.005057 -86.133816)
			(xy 231.959267 -86.062564) (xy 231.920456 -85.987283) (xy 231.888977 -85.908653) (xy 231.865116 -85.827386)
			(xy 231.849087 -85.74422) (xy 231.841036 -85.659906) (xy 216.328854 -85.659906) (xy 216.310075 -85.701027)
			(xy 216.267726 -85.774377) (xy 216.218597 -85.843369) (xy 216.163132 -85.907379) (xy 216.101834 -85.965827)
			(xy 216.035258 -86.018183) (xy 215.964006 -86.063973) (xy 215.888725 -86.102784) (xy 215.810095 -86.134263)
			(xy 215.728828 -86.158124) (xy 215.645662 -86.174153) (xy 215.561348 -86.182204) (xy 215.519 -86.182708)
			(xy 215.47832 -86.18225) (xy 215.397301 -86.174809) (xy 215.3173 -86.159999) (xy 215.238986 -86.137944)
			(xy 215.163014 -86.108827) (xy 215.126316 -86.091268) (xy 215.11806 -86.087609) (xy 215.100111 -86.085752)
			(xy 215.082632 -86.090239) (xy 215.075008 -86.095078) (xy 215.037787 -86.12013) (xy 214.959241 -86.163505)
			(xy 214.876725 -86.198745) (xy 214.791079 -86.225492) (xy 214.703173 -86.243474) (xy 214.613903 -86.252508)
			(xy 214.56904 -86.253066) (xy 214.526688 -86.252664) (xy 214.442366 -86.244616) (xy 214.359191 -86.228588)
			(xy 214.277916 -86.204727) (xy 214.199278 -86.173248) (xy 214.123988 -86.134437) (xy 214.052729 -86.088644)
			(xy 213.986145 -86.036284) (xy 213.924839 -85.977833) (xy 213.869368 -85.913818) (xy 213.820233 -85.84482)
			(xy 213.77788 -85.771464) (xy 213.742691 -85.694415) (xy 213.714986 -85.614369) (xy 213.695016 -85.532052)
			(xy 213.682961 -85.448209) (xy 213.67893 -85.3636) (xy 209.882949 -85.3636) (xy 209.95745 -85.374311)
			(xy 210.039759 -85.394279) (xy 210.119798 -85.421981) (xy 210.196841 -85.457165) (xy 210.270191 -85.499514)
			(xy 210.339183 -85.548643) (xy 210.403193 -85.604108) (xy 210.461641 -85.665406) (xy 210.513997 -85.731982)
			(xy 210.559787 -85.803234) (xy 210.598598 -85.878515) (xy 210.630077 -85.957145) (xy 210.653938 -86.038412)
			(xy 210.669967 -86.121578) (xy 210.678018 -86.205892) (xy 210.678522 -86.24824) (xy 210.678018 -86.290588)
			(xy 210.669967 -86.374902) (xy 210.653938 -86.458068) (xy 210.630077 -86.539335) (xy 210.598598 -86.617965)
			(xy 210.559787 -86.693246) (xy 210.513997 -86.764498) (xy 210.461641 -86.831074) (xy 210.403193 -86.892372)
			(xy 210.339183 -86.947837) (xy 210.270191 -86.996966) (xy 210.196841 -87.039315) (xy 210.119798 -87.074499)
			(xy 210.039759 -87.102201) (xy 209.95745 -87.122169) (xy 209.873615 -87.134222) (xy 209.789014 -87.138253)
			(xy 209.704413 -87.134222) (xy 209.620578 -87.122169) (xy 209.538269 -87.102201) (xy 209.45823 -87.074499)
			(xy 209.381187 -87.039315) (xy 209.307837 -86.996966) (xy 209.238845 -86.947837) (xy 209.174835 -86.892372)
			(xy 209.116387 -86.831074) (xy 209.064031 -86.764498) (xy 209.018241 -86.693246) (xy 208.97943 -86.617965)
			(xy 208.947951 -86.539335) (xy 208.92409 -86.458068) (xy 208.908061 -86.374902) (xy 208.90001 -86.290588)
			(xy 200.327768 -86.290588) (xy 200.327768 -87.391389) (xy 204.450111 -87.391389) (xy 204.452596 -87.307668)
			(xy 204.462939 -87.224552) (xy 204.48105 -87.142776) (xy 204.506768 -87.063065) (xy 204.539865 -86.986124)
			(xy 204.580048 -86.912635) (xy 204.626961 -86.843249) (xy 204.680189 -86.77858) (xy 204.73926 -86.719201)
			(xy 204.803652 -86.665638) (xy 204.872793 -86.618365) (xy 204.946072 -86.577801) (xy 205.02284 -86.544304)
			(xy 205.102417 -86.518173) (xy 205.184097 -86.499637) (xy 205.267159 -86.488862) (xy 205.350865 -86.485943)
			(xy 205.434475 -86.490905) (xy 205.517249 -86.503705) (xy 205.598453 -86.524229) (xy 205.677368 -86.552295)
			(xy 205.753295 -86.587656) (xy 205.825562 -86.629997) (xy 205.893528 -86.678944) (xy 205.956593 -86.734063)
			(xy 206.014197 -86.794867) (xy 206.06583 -86.860816) (xy 206.111036 -86.931327) (xy 206.130652 -86.96833)
			(xy 206.13485 -86.975836) (xy 206.147329 -86.987657) (xy 206.163011 -86.994697) (xy 206.171546 -86.995762)
			(xy 206.198462 -86.998468) (xy 206.251199 -87.01051) (xy 206.301707 -87.02988) (xy 206.348973 -87.05619)
			(xy 206.392049 -87.088912) (xy 206.430071 -87.12739) (xy 206.462278 -87.170853) (xy 206.488022 -87.218428)
			(xy 206.506789 -87.269164) (xy 206.518202 -87.322041) (xy 206.522032 -87.376) (xy 206.518202 -87.429959)
			(xy 206.506789 -87.482836) (xy 206.488022 -87.533572) (xy 206.462278 -87.581147) (xy 206.430071 -87.62461)
			(xy 206.392049 -87.663088) (xy 206.348973 -87.69581) (xy 206.301707 -87.72212) (xy 206.251199 -87.74149)
			(xy 206.198462 -87.753532) (xy 206.171546 -87.756238) (xy 206.163013 -87.75732) (xy 206.147328 -87.764341)
			(xy 206.134865 -87.776174) (xy 206.130652 -87.78367) (xy 206.111646 -87.819532) (xy 206.068024 -87.887983)
			(xy 206.018347 -87.952175) (xy 205.963029 -88.011575) (xy 205.90253 -88.065689) (xy 205.837352 -88.114066)
			(xy 205.768039 -88.156304) (xy 205.695166 -88.192053) (xy 205.619339 -88.221014) (xy 205.541189 -88.242947)
			(xy 205.504631 -88.24969) (xy 221.360996 -88.24969) (xy 221.360996 -88.164994) (xy 221.369047 -88.08068)
			(xy 221.385076 -87.997514) (xy 221.408937 -87.916247) (xy 221.440416 -87.837617) (xy 221.479227 -87.762336)
			(xy 221.525017 -87.691084) (xy 221.577373 -87.624508) (xy 221.635821 -87.56321) (xy 221.699831 -87.507745)
			(xy 221.768823 -87.458616) (xy 221.842173 -87.416267) (xy 221.919216 -87.381083) (xy 221.999255 -87.353381)
			(xy 222.081564 -87.333413) (xy 222.165399 -87.32136) (xy 222.25 -87.31733) (xy 222.334601 -87.32136)
			(xy 222.418436 -87.333413) (xy 222.500745 -87.353381) (xy 222.580784 -87.381083) (xy 222.657827 -87.416267)
			(xy 222.731177 -87.458616) (xy 222.800169 -87.507745) (xy 222.864179 -87.56321) (xy 222.922627 -87.624508)
			(xy 222.974983 -87.691084) (xy 223.020773 -87.762336) (xy 223.039854 -87.799348) (xy 233.740956 -87.799348)
			(xy 233.740956 -87.714652) (xy 233.749007 -87.630338) (xy 233.765036 -87.547172) (xy 233.788897 -87.465905)
			(xy 233.820376 -87.387275) (xy 233.859187 -87.311994) (xy 233.904977 -87.240742) (xy 233.957333 -87.174166)
			(xy 234.015781 -87.112868) (xy 234.079791 -87.057403) (xy 234.148783 -87.008274) (xy 234.222133 -86.965925)
			(xy 234.299176 -86.930741) (xy 234.379215 -86.903039) (xy 234.461524 -86.883071) (xy 234.545359 -86.871018)
			(xy 234.62996 -86.866988) (xy 234.714561 -86.871018) (xy 234.798396 -86.883071) (xy 234.880705 -86.903039)
			(xy 234.960744 -86.930741) (xy 235.037787 -86.965925) (xy 235.111137 -87.008274) (xy 235.180129 -87.057403)
			(xy 235.244139 -87.112868) (xy 235.302587 -87.174166) (xy 235.354943 -87.240742) (xy 235.400733 -87.311994)
			(xy 235.439544 -87.387275) (xy 235.471023 -87.465905) (xy 235.494884 -87.547172) (xy 235.510913 -87.630338)
			(xy 235.511117 -87.63247) (xy 236.183674 -87.63247) (xy 236.183674 -87.547774) (xy 236.191725 -87.46346)
			(xy 236.207754 -87.380294) (xy 236.231615 -87.299027) (xy 236.263094 -87.220397) (xy 236.301905 -87.145116)
			(xy 236.347695 -87.073864) (xy 236.400051 -87.007288) (xy 236.458499 -86.94599) (xy 236.522509 -86.890525)
			(xy 236.591501 -86.841396) (xy 236.664851 -86.799047) (xy 236.741894 -86.763863) (xy 236.821933 -86.736161)
			(xy 236.904242 -86.716193) (xy 236.988077 -86.70414) (xy 237.072678 -86.70011) (xy 237.157279 -86.70414)
			(xy 237.241114 -86.716193) (xy 237.323423 -86.736161) (xy 237.403462 -86.763863) (xy 237.480505 -86.799047)
			(xy 237.553855 -86.841396) (xy 237.622847 -86.890525) (xy 237.686857 -86.94599) (xy 237.745305 -87.007288)
			(xy 237.797661 -87.073864) (xy 237.843451 -87.145116) (xy 237.882262 -87.220397) (xy 237.913741 -87.299027)
			(xy 237.937602 -87.380294) (xy 237.953631 -87.46346) (xy 237.96082 -87.538744) (xy 238.133886 -87.538744)
			(xy 238.133886 -87.454048) (xy 238.141937 -87.369734) (xy 238.157966 -87.286568) (xy 238.181827 -87.205301)
			(xy 238.213306 -87.126671) (xy 238.252117 -87.05139) (xy 238.297907 -86.980138) (xy 238.350263 -86.913562)
			(xy 238.408711 -86.852264) (xy 238.472721 -86.796799) (xy 238.541713 -86.74767) (xy 238.615063 -86.705321)
			(xy 238.692106 -86.670137) (xy 238.772145 -86.642435) (xy 238.854454 -86.622467) (xy 238.938289 -86.610414)
			(xy 239.02289 -86.606384) (xy 239.107491 -86.610414) (xy 239.191326 -86.622467) (xy 239.273635 -86.642435)
			(xy 239.353674 -86.670137) (xy 239.430717 -86.705321) (xy 239.504067 -86.74767) (xy 239.573059 -86.796799)
			(xy 239.637069 -86.852264) (xy 239.695517 -86.913562) (xy 239.747873 -86.980138) (xy 239.793663 -87.05139)
			(xy 239.832474 -87.126671) (xy 239.863953 -87.205301) (xy 239.887814 -87.286568) (xy 239.903843 -87.369734)
			(xy 239.911894 -87.454048) (xy 239.912398 -87.496396) (xy 239.911894 -87.538744) (xy 239.903843 -87.623058)
			(xy 239.887814 -87.706224) (xy 239.863953 -87.787491) (xy 239.832474 -87.866121) (xy 239.793663 -87.941402)
			(xy 239.747873 -88.012654) (xy 239.695517 -88.07923) (xy 239.637069 -88.140528) (xy 239.573059 -88.195993)
			(xy 239.504067 -88.245122) (xy 239.430717 -88.287471) (xy 239.353674 -88.322655) (xy 239.273635 -88.350357)
			(xy 239.191326 -88.370325) (xy 239.107491 -88.382378) (xy 239.02289 -88.386409) (xy 238.938289 -88.382378)
			(xy 238.854454 -88.370325) (xy 238.772145 -88.350357) (xy 238.692106 -88.322655) (xy 238.615063 -88.287471)
			(xy 238.541713 -88.245122) (xy 238.472721 -88.195993) (xy 238.408711 -88.140528) (xy 238.350263 -88.07923)
			(xy 238.297907 -88.012654) (xy 238.252117 -87.941402) (xy 238.213306 -87.866121) (xy 238.181827 -87.787491)
			(xy 238.157966 -87.706224) (xy 238.141937 -87.623058) (xy 238.133886 -87.538744) (xy 237.96082 -87.538744)
			(xy 237.961682 -87.547774) (xy 237.962186 -87.590122) (xy 237.961682 -87.63247) (xy 237.953631 -87.716784)
			(xy 237.937602 -87.79995) (xy 237.913741 -87.881217) (xy 237.882262 -87.959847) (xy 237.843451 -88.035128)
			(xy 237.797661 -88.10638) (xy 237.745305 -88.172956) (xy 237.686857 -88.234254) (xy 237.622847 -88.289719)
			(xy 237.553855 -88.338848) (xy 237.480505 -88.381197) (xy 237.403462 -88.416381) (xy 237.323423 -88.444083)
			(xy 237.241114 -88.464051) (xy 237.157279 -88.476104) (xy 237.072678 -88.480135) (xy 236.988077 -88.476104)
			(xy 236.904242 -88.464051) (xy 236.821933 -88.444083) (xy 236.741894 -88.416381) (xy 236.664851 -88.381197)
			(xy 236.591501 -88.338848) (xy 236.522509 -88.289719) (xy 236.458499 -88.234254) (xy 236.400051 -88.172956)
			(xy 236.347695 -88.10638) (xy 236.301905 -88.035128) (xy 236.263094 -87.959847) (xy 236.231615 -87.881217)
			(xy 236.207754 -87.79995) (xy 236.191725 -87.716784) (xy 236.183674 -87.63247) (xy 235.511117 -87.63247)
			(xy 235.518964 -87.714652) (xy 235.519468 -87.757) (xy 235.518964 -87.799348) (xy 235.510913 -87.883662)
			(xy 235.494884 -87.966828) (xy 235.471023 -88.048095) (xy 235.439544 -88.126725) (xy 235.400733 -88.202006)
			(xy 235.354943 -88.273258) (xy 235.302587 -88.339834) (xy 235.244139 -88.401132) (xy 235.180129 -88.456597)
			(xy 235.111137 -88.505726) (xy 235.037787 -88.548075) (xy 234.960744 -88.583259) (xy 234.880705 -88.610961)
			(xy 234.798396 -88.630929) (xy 234.714561 -88.642982) (xy 234.62996 -88.647013) (xy 234.545359 -88.642982)
			(xy 234.461524 -88.630929) (xy 234.379215 -88.610961) (xy 234.299176 -88.583259) (xy 234.222133 -88.548075)
			(xy 234.148783 -88.505726) (xy 234.079791 -88.456597) (xy 234.015781 -88.401132) (xy 233.957333 -88.339834)
			(xy 233.904977 -88.273258) (xy 233.859187 -88.202006) (xy 233.820376 -88.126725) (xy 233.788897 -88.048095)
			(xy 233.765036 -87.966828) (xy 233.749007 -87.883662) (xy 233.740956 -87.799348) (xy 223.039854 -87.799348)
			(xy 223.059584 -87.837617) (xy 223.091063 -87.916247) (xy 223.114924 -87.997514) (xy 223.130953 -88.08068)
			(xy 223.139004 -88.164994) (xy 223.139508 -88.207342) (xy 223.139004 -88.24969) (xy 223.130953 -88.334004)
			(xy 223.114924 -88.41717) (xy 223.091063 -88.498437) (xy 223.059584 -88.577067) (xy 223.020773 -88.652348)
			(xy 222.974983 -88.7236) (xy 222.922627 -88.790176) (xy 222.864179 -88.851474) (xy 222.800169 -88.906939)
			(xy 222.731177 -88.956068) (xy 222.657827 -88.998417) (xy 222.580784 -89.033601) (xy 222.500745 -89.061303)
			(xy 222.418436 -89.081271) (xy 222.334601 -89.093324) (xy 222.25 -89.097355) (xy 222.165399 -89.093324)
			(xy 222.081564 -89.081271) (xy 221.999255 -89.061303) (xy 221.919216 -89.033601) (xy 221.842173 -88.998417)
			(xy 221.768823 -88.956068) (xy 221.699831 -88.906939) (xy 221.635821 -88.851474) (xy 221.577373 -88.790176)
			(xy 221.525017 -88.7236) (xy 221.479227 -88.652348) (xy 221.440416 -88.577067) (xy 221.408937 -88.498437)
			(xy 221.385076 -88.41717) (xy 221.369047 -88.334004) (xy 221.360996 -88.24969) (xy 205.504631 -88.24969)
			(xy 205.461367 -88.25767) (xy 205.380535 -88.26506) (xy 205.33995 -88.265508) (xy 205.298071 -88.264935)
			(xy 205.214685 -88.257057) (xy 205.132409 -88.241375) (xy 205.051971 -88.218029) (xy 204.974085 -88.187225)
			(xy 204.899438 -88.149235) (xy 204.828693 -88.104397) (xy 204.762477 -88.053107) (xy 204.701375 -87.995819)
			(xy 204.645929 -87.933042) (xy 204.596629 -87.86533) (xy 204.553913 -87.793284) (xy 204.518159 -87.717542)
			(xy 204.489683 -87.638774) (xy 204.468737 -87.557678) (xy 204.455508 -87.474972) (xy 204.450111 -87.391389)
			(xy 200.327768 -87.391389) (xy 200.327768 -89.54898) (xy 209.168097 -89.54898) (xy 209.170731 -89.46517)
			(xy 209.18124 -89.381981) (xy 209.199532 -89.30015) (xy 209.225443 -89.220403) (xy 209.258744 -89.143449)
			(xy 209.29914 -89.06997) (xy 209.346271 -89.000618) (xy 209.399719 -88.93601) (xy 209.45901 -88.876719)
			(xy 209.523618 -88.823271) (xy 209.59297 -88.77614) (xy 209.666449 -88.735744) (xy 209.743403 -88.702443)
			(xy 209.82315 -88.676532) (xy 209.904981 -88.65824) (xy 209.98817 -88.647731) (xy 210.07198 -88.645097)
			(xy 210.155665 -88.650362) (xy 210.238483 -88.663479) (xy 210.3197 -88.684332) (xy 210.398593 -88.712736)
			(xy 210.474463 -88.748438) (xy 210.546637 -88.791121) (xy 210.614474 -88.840407) (xy 210.677371 -88.895859)
			(xy 210.734771 -88.956983) (xy 210.786163 -89.023238) (xy 210.831093 -89.094036) (xy 210.86916 -89.168747)
			(xy 210.900028 -89.246709) (xy 210.923421 -89.327231) (xy 210.939133 -89.409596) (xy 210.947024 -89.493075)
			(xy 210.947508 -89.535) (xy 210.94698 -89.578826) (xy 210.938354 -89.666053) (xy 210.921176 -89.752005)
			(xy 210.9089 -89.79408) (xy 210.906311 -89.804059) (xy 210.908514 -89.824541) (xy 210.918567 -89.842523)
			(xy 210.926426 -89.849198) (xy 210.949078 -89.867349) (xy 210.989077 -89.909414) (xy 211.022242 -89.957052)
			(xy 211.047808 -90.009165) (xy 211.065184 -90.06455) (xy 211.073969 -90.121927) (xy 211.074508 -90.15095)
			(xy 211.073998 -90.178202) (xy 211.066248 -90.232151) (xy 211.050898 -90.284448) (xy 211.028262 -90.334028)
			(xy 211.010155 -90.362208) (xy 211.355936 -90.362208) (xy 211.355936 -90.277512) (xy 211.363987 -90.193198)
			(xy 211.380016 -90.110032) (xy 211.403877 -90.028765) (xy 211.435356 -89.950135) (xy 211.474167 -89.874854)
			(xy 211.519957 -89.803602) (xy 211.572313 -89.737026) (xy 211.630761 -89.675728) (xy 211.694771 -89.620263)
			(xy 211.763763 -89.571134) (xy 211.837113 -89.528785) (xy 211.914156 -89.493601) (xy 211.994195 -89.465899)
			(xy 212.076504 -89.445931) (xy 212.160339 -89.433878) (xy 212.24494 -89.429848) (xy 212.329541 -89.433878)
			(xy 212.413376 -89.445931) (xy 212.495685 -89.465899) (xy 212.575724 -89.493601) (xy 212.652767 -89.528785)
			(xy 212.726117 -89.571134) (xy 212.795109 -89.620263) (xy 212.859119 -89.675728) (xy 212.917567 -89.737026)
			(xy 212.969923 -89.803602) (xy 213.015713 -89.874854) (xy 213.054524 -89.950135) (xy 213.086003 -90.028765)
			(xy 213.090833 -90.045216) (xy 213.447118 -90.045216) (xy 213.447118 -89.96052) (xy 213.455169 -89.876206)
			(xy 213.471198 -89.79304) (xy 213.495059 -89.711773) (xy 213.526538 -89.633143) (xy 213.565349 -89.557862)
			(xy 213.611139 -89.48661) (xy 213.663495 -89.420034) (xy 213.721943 -89.358736) (xy 213.785953 -89.303271)
			(xy 213.854945 -89.254142) (xy 213.928295 -89.211793) (xy 214.005338 -89.176609) (xy 214.085377 -89.148907)
			(xy 214.167686 -89.128939) (xy 214.251521 -89.116886) (xy 214.336122 -89.112856) (xy 214.420723 -89.116886)
			(xy 214.504558 -89.128939) (xy 214.586867 -89.148907) (xy 214.666906 -89.176609) (xy 214.743949 -89.211793)
			(xy 214.817299 -89.254142) (xy 214.886291 -89.303271) (xy 214.950301 -89.358736) (xy 215.008749 -89.420034)
			(xy 215.061105 -89.48661) (xy 215.0933 -89.536708) (xy 227.980998 -89.536708) (xy 227.980998 -89.452012)
			(xy 227.989049 -89.367698) (xy 228.005078 -89.284532) (xy 228.028939 -89.203265) (xy 228.060418 -89.124635)
			(xy 228.099229 -89.049354) (xy 228.145019 -88.978102) (xy 228.197375 -88.911526) (xy 228.255823 -88.850228)
			(xy 228.319833 -88.794763) (xy 228.388825 -88.745634) (xy 228.462175 -88.703285) (xy 228.539218 -88.668101)
			(xy 228.619257 -88.640399) (xy 228.701566 -88.620431) (xy 228.785401 -88.608378) (xy 228.870002 -88.604348)
			(xy 228.954603 -88.608378) (xy 229.038438 -88.620431) (xy 229.120747 -88.640399) (xy 229.200786 -88.668101)
			(xy 229.277829 -88.703285) (xy 229.351179 -88.745634) (xy 229.420171 -88.794763) (xy 229.484181 -88.850228)
			(xy 229.542629 -88.911526) (xy 229.594985 -88.978102) (xy 229.640775 -89.049354) (xy 229.679586 -89.124635)
			(xy 229.711065 -89.203265) (xy 229.734926 -89.284532) (xy 229.750955 -89.367698) (xy 229.759006 -89.452012)
			(xy 229.75951 -89.49436) (xy 229.759006 -89.536708) (xy 229.750955 -89.621022) (xy 229.734926 -89.704188)
			(xy 229.711065 -89.785455) (xy 229.679586 -89.864085) (xy 229.640775 -89.939366) (xy 229.594985 -90.010618)
			(xy 229.542629 -90.077194) (xy 229.484181 -90.138492) (xy 229.420171 -90.193957) (xy 229.394344 -90.212348)
			(xy 231.841036 -90.212348) (xy 231.841036 -90.127652) (xy 231.849087 -90.043338) (xy 231.865116 -89.960172)
			(xy 231.888977 -89.878905) (xy 231.920456 -89.800275) (xy 231.959267 -89.724994) (xy 232.005057 -89.653742)
			(xy 232.057413 -89.587166) (xy 232.115861 -89.525868) (xy 232.179871 -89.470403) (xy 232.248863 -89.421274)
			(xy 232.322213 -89.378925) (xy 232.399256 -89.343741) (xy 232.479295 -89.316039) (xy 232.561604 -89.296071)
			(xy 232.645439 -89.284018) (xy 232.73004 -89.279988) (xy 232.814641 -89.284018) (xy 232.898476 -89.296071)
			(xy 232.980785 -89.316039) (xy 233.060824 -89.343741) (xy 233.137867 -89.378925) (xy 233.211217 -89.421274)
			(xy 233.280209 -89.470403) (xy 233.344219 -89.525868) (xy 233.402667 -89.587166) (xy 233.455023 -89.653742)
			(xy 233.500813 -89.724994) (xy 233.537311 -89.795788) (xy 236.14278 -89.795788) (xy 236.14278 -89.711092)
			(xy 236.150831 -89.626778) (xy 236.16686 -89.543612) (xy 236.190721 -89.462345) (xy 236.2222 -89.383715)
			(xy 236.261011 -89.308434) (xy 236.306801 -89.237182) (xy 236.359157 -89.170606) (xy 236.417605 -89.109308)
			(xy 236.481615 -89.053843) (xy 236.550607 -89.004714) (xy 236.623957 -88.962365) (xy 236.701 -88.927181)
			(xy 236.781039 -88.899479) (xy 236.863348 -88.879511) (xy 236.947183 -88.867458) (xy 237.031784 -88.863428)
			(xy 237.116385 -88.867458) (xy 237.20022 -88.879511) (xy 237.282529 -88.899479) (xy 237.362568 -88.927181)
			(xy 237.439611 -88.962365) (xy 237.512961 -89.004714) (xy 237.581953 -89.053843) (xy 237.645963 -89.109308)
			(xy 237.704411 -89.170606) (xy 237.756767 -89.237182) (xy 237.802557 -89.308434) (xy 237.841368 -89.383715)
			(xy 237.872847 -89.462345) (xy 237.896708 -89.543612) (xy 237.912737 -89.626778) (xy 237.920788 -89.711092)
			(xy 237.921292 -89.75344) (xy 237.920788 -89.795788) (xy 237.912737 -89.880102) (xy 237.896708 -89.963268)
			(xy 237.872847 -90.044535) (xy 237.841368 -90.123165) (xy 237.802557 -90.198446) (xy 237.756767 -90.269698)
			(xy 237.704411 -90.336274) (xy 237.645963 -90.397572) (xy 237.581953 -90.453037) (xy 237.512961 -90.502166)
			(xy 237.439611 -90.544515) (xy 237.362568 -90.579699) (xy 237.282529 -90.607401) (xy 237.20022 -90.627369)
			(xy 237.116385 -90.639422) (xy 237.031784 -90.643453) (xy 236.947183 -90.639422) (xy 236.863348 -90.627369)
			(xy 236.781039 -90.607401) (xy 236.701 -90.579699) (xy 236.623957 -90.544515) (xy 236.550607 -90.502166)
			(xy 236.481615 -90.453037) (xy 236.417605 -90.397572) (xy 236.359157 -90.336274) (xy 236.306801 -90.269698)
			(xy 236.261011 -90.198446) (xy 236.2222 -90.123165) (xy 236.190721 -90.044535) (xy 236.16686 -89.963268)
			(xy 236.150831 -89.880102) (xy 236.14278 -89.795788) (xy 233.537311 -89.795788) (xy 233.539624 -89.800275)
			(xy 233.571103 -89.878905) (xy 233.594964 -89.960172) (xy 233.610993 -90.043338) (xy 233.619044 -90.127652)
			(xy 233.619548 -90.17) (xy 233.619044 -90.212348) (xy 233.610993 -90.296662) (xy 233.594964 -90.379828)
			(xy 233.571103 -90.461095) (xy 233.539624 -90.539725) (xy 233.500813 -90.615006) (xy 233.455023 -90.686258)
			(xy 233.402667 -90.752834) (xy 233.344219 -90.814132) (xy 233.280209 -90.869597) (xy 233.211217 -90.918726)
			(xy 233.137867 -90.961075) (xy 233.060824 -90.996259) (xy 232.980785 -91.023961) (xy 232.898476 -91.043929)
			(xy 232.814641 -91.055982) (xy 232.73004 -91.060013) (xy 232.645439 -91.055982) (xy 232.561604 -91.043929)
			(xy 232.479295 -91.023961) (xy 232.399256 -90.996259) (xy 232.322213 -90.961075) (xy 232.248863 -90.918726)
			(xy 232.179871 -90.869597) (xy 232.115861 -90.814132) (xy 232.057413 -90.752834) (xy 232.005057 -90.686258)
			(xy 231.959267 -90.615006) (xy 231.920456 -90.539725) (xy 231.888977 -90.461095) (xy 231.865116 -90.379828)
			(xy 231.849087 -90.296662) (xy 231.841036 -90.212348) (xy 229.394344 -90.212348) (xy 229.351179 -90.243086)
			(xy 229.277829 -90.285435) (xy 229.200786 -90.320619) (xy 229.120747 -90.348321) (xy 229.038438 -90.368289)
			(xy 228.954603 -90.380342) (xy 228.870002 -90.384373) (xy 228.785401 -90.380342) (xy 228.701566 -90.368289)
			(xy 228.619257 -90.348321) (xy 228.539218 -90.320619) (xy 228.462175 -90.285435) (xy 228.388825 -90.243086)
			(xy 228.319833 -90.193957) (xy 228.255823 -90.138492) (xy 228.197375 -90.077194) (xy 228.145019 -90.010618)
			(xy 228.099229 -89.939366) (xy 228.060418 -89.864085) (xy 228.028939 -89.785455) (xy 228.005078 -89.704188)
			(xy 227.989049 -89.621022) (xy 227.980998 -89.536708) (xy 215.0933 -89.536708) (xy 215.106895 -89.557862)
			(xy 215.145706 -89.633143) (xy 215.177185 -89.711773) (xy 215.201046 -89.79304) (xy 215.217075 -89.876206)
			(xy 215.225126 -89.96052) (xy 215.22563 -90.002868) (xy 215.225126 -90.045216) (xy 215.217075 -90.12953)
			(xy 215.201046 -90.212696) (xy 215.177185 -90.293963) (xy 215.145706 -90.372593) (xy 215.106895 -90.447874)
			(xy 215.061105 -90.519126) (xy 215.008749 -90.585702) (xy 214.950301 -90.647) (xy 214.886291 -90.702465)
			(xy 214.817299 -90.751594) (xy 214.743949 -90.793943) (xy 214.666906 -90.829127) (xy 214.586867 -90.856829)
			(xy 214.504558 -90.876797) (xy 214.420723 -90.88885) (xy 214.336122 -90.892881) (xy 214.251521 -90.88885)
			(xy 214.167686 -90.876797) (xy 214.085377 -90.856829) (xy 214.005338 -90.829127) (xy 213.928295 -90.793943)
			(xy 213.854945 -90.751594) (xy 213.785953 -90.702465) (xy 213.721943 -90.647) (xy 213.663495 -90.585702)
			(xy 213.611139 -90.519126) (xy 213.565349 -90.447874) (xy 213.526538 -90.372593) (xy 213.495059 -90.293963)
			(xy 213.471198 -90.212696) (xy 213.455169 -90.12953) (xy 213.447118 -90.045216) (xy 213.090833 -90.045216)
			(xy 213.109864 -90.110032) (xy 213.125893 -90.193198) (xy 213.133944 -90.277512) (xy 213.134448 -90.31986)
			(xy 213.133944 -90.362208) (xy 213.125893 -90.446522) (xy 213.109864 -90.529688) (xy 213.086003 -90.610955)
			(xy 213.054524 -90.689585) (xy 213.015713 -90.764866) (xy 212.969923 -90.836118) (xy 212.917567 -90.902694)
			(xy 212.859119 -90.963992) (xy 212.795109 -91.019457) (xy 212.726117 -91.068586) (xy 212.652767 -91.110935)
			(xy 212.575724 -91.146119) (xy 212.495685 -91.173821) (xy 212.413376 -91.193789) (xy 212.329541 -91.205842)
			(xy 212.24494 -91.209873) (xy 212.160339 -91.205842) (xy 212.076504 -91.193789) (xy 211.994195 -91.173821)
			(xy 211.914156 -91.146119) (xy 211.837113 -91.110935) (xy 211.763763 -91.068586) (xy 211.694771 -91.019457)
			(xy 211.630761 -90.963992) (xy 211.572313 -90.902694) (xy 211.519957 -90.836118) (xy 211.474167 -90.764866)
			(xy 211.435356 -90.689585) (xy 211.403877 -90.610955) (xy 211.380016 -90.529688) (xy 211.363987 -90.446522)
			(xy 211.355936 -90.362208) (xy 211.010155 -90.362208) (xy 210.998799 -90.379881) (xy 210.96311 -90.421074)
			(xy 210.921921 -90.456769) (xy 210.876072 -90.486238) (xy 210.826495 -90.508881) (xy 210.7742 -90.524237)
			(xy 210.720252 -90.531995) (xy 210.693 -90.532458) (xy 210.664938 -90.53201) (xy 210.609417 -90.523804)
			(xy 210.555696 -90.507554) (xy 210.504935 -90.48361) (xy 210.458229 -90.45249) (xy 210.416585 -90.414864)
			(xy 210.39836 -90.39352) (xy 210.39144 -90.385952) (xy 210.373263 -90.376511) (xy 210.352841 -90.37494)
			(xy 210.342988 -90.377772) (xy 210.297052 -90.39263) (xy 210.202767 -90.413424) (xy 210.106783 -90.423878)
			(xy 210.058508 -90.424508) (xy 210.058 -90.424508) (xy 210.016075 -90.424024) (xy 209.932596 -90.416133)
			(xy 209.850231 -90.400421) (xy 209.769709 -90.377028) (xy 209.691747 -90.34616) (xy 209.617036 -90.308093)
			(xy 209.546238 -90.263163) (xy 209.479983 -90.211771) (xy 209.418859 -90.154371) (xy 209.363407 -90.091474)
			(xy 209.314121 -90.023637) (xy 209.271438 -89.951463) (xy 209.235736 -89.875593) (xy 209.207332 -89.7967)
			(xy 209.186479 -89.715483) (xy 209.173362 -89.632665) (xy 209.168097 -89.54898) (xy 200.327768 -89.54898)
			(xy 200.327768 -90.271092) (xy 200.328241 -90.281325) (xy 200.336232 -90.300168) (xy 200.35092 -90.314422)
			(xy 200.36028 -90.31859) (xy 200.448926 -90.352626) (xy 200.458708 -90.355829) (xy 200.479258 -90.355024)
			(xy 200.497867 -90.346272) (xy 200.50506 -90.33891) (xy 200.533131 -90.30825) (xy 200.594096 -90.25173)
			(xy 200.660068 -90.201145) (xy 200.730473 -90.156937) (xy 200.804696 -90.119492) (xy 200.882089 -90.089135)
			(xy 200.961977 -90.066133) (xy 201.043662 -90.050686) (xy 201.126433 -90.042929) (xy 201.168 -90.042492)
			(xy 201.209102 -90.042967) (xy 201.290957 -90.050552) (xy 201.371762 -90.065657) (xy 201.450829 -90.088153)
			(xy 201.527483 -90.117849) (xy 201.60107 -90.154491) (xy 201.670962 -90.197766) (xy 201.736563 -90.247306)
			(xy 201.797313 -90.302687) (xy 201.852694 -90.363437) (xy 201.902234 -90.429038) (xy 201.945509 -90.49893)
			(xy 201.982151 -90.572517) (xy 202.011847 -90.649171) (xy 202.034343 -90.728238) (xy 202.049448 -90.809043)
			(xy 202.057033 -90.890898) (xy 202.057508 -90.932) (xy 202.056898 -90.97899) (xy 202.046987 -91.072446)
			(xy 202.027276 -91.164336) (xy 201.997985 -91.253635) (xy 201.979276 -91.296744) (xy 201.973942 -91.308428)
			(xy 201.975974 -91.334336) (xy 202.029314 -91.416886) (xy 202.034176 -91.423819) (xy 202.047512 -91.434236)
			(xy 202.063523 -91.439716) (xy 202.071986 -91.44)
		)
		(stroke
			(width 0)
			(type solid)
		)
		(fill yes)
		(layer "In2.Cu")
		(net "P3V3_AUX")
	)
	(gr_poly
		(pts
			(xy 222.089472 -145.000726) (xy 222.099523 -145.000222) (xy 222.118086 -144.992502) (xy 222.12554 -144.98574)
			(xy 222.743014 -144.368266) (xy 222.749865 -144.36087) (xy 222.7576 -144.342271) (xy 222.758 -144.332198)
			(xy 222.758 -144.028668) (xy 222.757625 -144.019195) (xy 222.750759 -144.001538) (xy 222.737942 -143.987586)
			(xy 222.720929 -143.979251) (xy 222.711518 -143.978122) (xy 222.646862 -143.972174) (xy 222.51839 -143.953282)
			(xy 222.391334 -143.926472) (xy 222.266181 -143.891849) (xy 222.143412 -143.849543) (xy 222.023497 -143.799719)
			(xy 221.906897 -143.742566) (xy 221.794058 -143.678305) (xy 221.685415 -143.607181) (xy 221.581383 -143.529468)
			(xy 221.482361 -143.445463) (xy 221.38873 -143.35549) (xy 221.300849 -143.259892) (xy 221.219054 -143.159038)
			(xy 221.14366 -143.053313) (xy 221.074956 -142.943123) (xy 221.013205 -142.828891) (xy 220.958645 -142.711056)
			(xy 220.911484 -142.590069) (xy 220.871903 -142.466394) (xy 220.840055 -142.340506) (xy 220.816062 -142.212889)
			(xy 220.800015 -142.08403) (xy 220.791976 -141.954425) (xy 220.791976 -141.824571) (xy 220.800015 -141.694967)
			(xy 220.816062 -141.566108) (xy 220.840056 -141.43849) (xy 220.871904 -141.312603) (xy 220.911485 -141.188928)
			(xy 220.958646 -141.067941) (xy 221.013207 -140.950106) (xy 221.074958 -140.835874) (xy 221.143662 -140.725685)
			(xy 221.219056 -140.61996) (xy 221.300851 -140.519105) (xy 221.388732 -140.423508) (xy 221.482364 -140.333534)
			(xy 221.581385 -140.24953) (xy 221.685418 -140.171817) (xy 221.794061 -140.100693) (xy 221.9069 -140.036432)
			(xy 222.0235 -139.97928) (xy 222.143415 -139.929455) (xy 222.266184 -139.88715) (xy 222.391337 -139.852527)
			(xy 222.518393 -139.825718) (xy 222.646866 -139.806826) (xy 222.711518 -139.800838) (xy 222.720903 -139.799638)
			(xy 222.737867 -139.791285) (xy 222.750655 -139.777358) (xy 222.757533 -139.759745) (xy 222.758 -139.750292)
			(xy 222.758 -117.714522) (xy 222.75038 -117.695726) (xy 222.743014 -117.688614) (xy 222.228664 -117.174264)
			(xy 222.221552 -117.166898) (xy 222.202756 -117.159278) (xy 193.527426 -117.159278) (xy 193.513456 -117.16131)
			(xy 193.507106 -117.163088) (xy 193.50101 -117.166644) (xy 193.494904 -117.170145) (xy 193.481374 -117.174007)
			(xy 193.47434 -117.174264) (xy 38.092634 -117.174264) (xy 38.082571 -117.174701) (xy 38.06399 -117.182439)
			(xy 38.056566 -117.18925) (xy 37.546788 -117.698774) (xy 37.539944 -117.706172) (xy 37.532222 -117.724772)
			(xy 37.531802 -117.734842) (xy 37.531802 -121.209816) (xy 47.412921 -121.209816) (xy 47.416894 -121.089722)
			(xy 47.428795 -120.970154) (xy 47.448573 -120.851634) (xy 47.47614 -120.734679) (xy 47.511377 -120.619803)
			(xy 47.554129 -120.507506) (xy 47.604209 -120.398281) (xy 47.661398 -120.292604) (xy 47.725447 -120.190938)
			(xy 47.796075 -120.093727) (xy 47.872973 -120.001397) (xy 47.955805 -119.91435) (xy 48.044209 -119.832969)
			(xy 48.137798 -119.757607) (xy 48.236164 -119.688597) (xy 48.338875 -119.626238) (xy 48.445483 -119.570803)
			(xy 48.555522 -119.522536) (xy 48.66851 -119.481646) (xy 48.783953 -119.448314) (xy 48.901347 -119.422684)
			(xy 49.020178 -119.404869) (xy 49.139927 -119.394946) (xy 49.26007 -119.392959) (xy 49.380081 -119.398917)
			(xy 49.499437 -119.412794) (xy 49.617614 -119.434528) (xy 49.734096 -119.464026) (xy 49.848374 -119.501157)
			(xy 49.959949 -119.54576) (xy 50.068331 -119.597639) (xy 50.173048 -119.656568) (xy 50.273641 -119.722289)
			(xy 50.369671 -119.794514) (xy 50.460718 -119.872928) (xy 50.546383 -119.957188) (xy 50.626292 -120.046926)
			(xy 50.700095 -120.141748) (xy 50.76747 -120.241241) (xy 50.828122 -120.34497) (xy 50.881786 -120.45248)
			(xy 50.928228 -120.563301) (xy 50.967243 -120.67695) (xy 50.998663 -120.792929) (xy 51.022348 -120.91073)
			(xy 51.038196 -121.02984) (xy 51.046138 -121.149736) (xy 51.046634 -121.209816) (xy 55.032921 -121.209816)
			(xy 55.036894 -121.089722) (xy 55.048795 -120.970154) (xy 55.068573 -120.851634) (xy 55.09614 -120.734679)
			(xy 55.131377 -120.619803) (xy 55.174129 -120.507506) (xy 55.224209 -120.398281) (xy 55.281398 -120.292604)
			(xy 55.345447 -120.190938) (xy 55.416075 -120.093727) (xy 55.492973 -120.001397) (xy 55.575805 -119.91435)
			(xy 55.664209 -119.832969) (xy 55.757798 -119.757607) (xy 55.856164 -119.688597) (xy 55.958875 -119.626238)
			(xy 56.065483 -119.570803) (xy 56.175522 -119.522536) (xy 56.28851 -119.481646) (xy 56.403953 -119.448314)
			(xy 56.521347 -119.422684) (xy 56.640178 -119.404869) (xy 56.759927 -119.394946) (xy 56.88007 -119.392959)
			(xy 57.000081 -119.398917) (xy 57.119437 -119.412794) (xy 57.237614 -119.434528) (xy 57.354096 -119.464026)
			(xy 57.468374 -119.501157) (xy 57.579949 -119.54576) (xy 57.688331 -119.597639) (xy 57.793048 -119.656568)
			(xy 57.893641 -119.722289) (xy 57.989671 -119.794514) (xy 58.080718 -119.872928) (xy 58.166383 -119.957188)
			(xy 58.246292 -120.046926) (xy 58.320095 -120.141748) (xy 58.38747 -120.241241) (xy 58.448122 -120.34497)
			(xy 58.501786 -120.45248) (xy 58.548228 -120.563301) (xy 58.587243 -120.67695) (xy 58.618663 -120.792929)
			(xy 58.642348 -120.91073) (xy 58.658196 -121.02984) (xy 58.666138 -121.149736) (xy 58.666634 -121.209816)
			(xy 58.66621 -121.261212) (xy 63.161922 -121.261212) (xy 63.161922 -121.15842) (xy 63.169987 -121.055946)
			(xy 63.186067 -120.954421) (xy 63.210063 -120.85447) (xy 63.241828 -120.75671) (xy 63.281164 -120.661743)
			(xy 63.32783 -120.570156) (xy 63.381538 -120.482512) (xy 63.441957 -120.399352) (xy 63.508715 -120.321189)
			(xy 63.581399 -120.248505) (xy 63.659562 -120.181747) (xy 63.742722 -120.121328) (xy 63.830366 -120.06762)
			(xy 63.921953 -120.020954) (xy 64.01692 -119.981618) (xy 64.11468 -119.949853) (xy 64.214631 -119.925857)
			(xy 64.316156 -119.909777) (xy 64.41863 -119.901712) (xy 64.521422 -119.901712) (xy 64.623896 -119.909777)
			(xy 64.725421 -119.925857) (xy 64.825372 -119.949853) (xy 64.923132 -119.981618) (xy 65.018099 -120.020954)
			(xy 65.109686 -120.06762) (xy 65.19733 -120.121328) (xy 65.28049 -120.181747) (xy 65.358653 -120.248505)
			(xy 65.431337 -120.321189) (xy 65.498095 -120.399352) (xy 65.558514 -120.482512) (xy 65.612222 -120.570156)
			(xy 65.658888 -120.661743) (xy 65.698224 -120.75671) (xy 65.729989 -120.85447) (xy 65.753985 -120.954421)
			(xy 65.770065 -121.055946) (xy 65.77813 -121.15842) (xy 65.778634 -121.209816) (xy 87.412841 -121.209816)
			(xy 87.416814 -121.089722) (xy 87.428715 -120.970154) (xy 87.448493 -120.851634) (xy 87.47606 -120.734679)
			(xy 87.511297 -120.619803) (xy 87.554049 -120.507506) (xy 87.604129 -120.398281) (xy 87.661318 -120.292604)
			(xy 87.725367 -120.190938) (xy 87.795995 -120.093727) (xy 87.872893 -120.001397) (xy 87.955725 -119.91435)
			(xy 88.044129 -119.832969) (xy 88.137718 -119.757607) (xy 88.236084 -119.688597) (xy 88.338795 -119.626238)
			(xy 88.445403 -119.570803) (xy 88.555442 -119.522536) (xy 88.66843 -119.481646) (xy 88.783873 -119.448314)
			(xy 88.901267 -119.422684) (xy 89.020098 -119.404869) (xy 89.139847 -119.394946) (xy 89.25999 -119.392959)
			(xy 89.380001 -119.398917) (xy 89.499357 -119.412794) (xy 89.617534 -119.434528) (xy 89.734016 -119.464026)
			(xy 89.848294 -119.501157) (xy 89.959869 -119.54576) (xy 90.068251 -119.597639) (xy 90.172968 -119.656568)
			(xy 90.273561 -119.722289) (xy 90.369591 -119.794514) (xy 90.460638 -119.872928) (xy 90.546303 -119.957188)
			(xy 90.626212 -120.046926) (xy 90.700015 -120.141748) (xy 90.76739 -120.241241) (xy 90.828042 -120.34497)
			(xy 90.881706 -120.45248) (xy 90.928148 -120.563301) (xy 90.967163 -120.67695) (xy 90.998583 -120.792929)
			(xy 91.022268 -120.91073) (xy 91.038116 -121.02984) (xy 91.046058 -121.149736) (xy 91.046554 -121.209816)
			(xy 95.032841 -121.209816) (xy 95.036814 -121.089722) (xy 95.048715 -120.970154) (xy 95.068493 -120.851634)
			(xy 95.09606 -120.734679) (xy 95.131297 -120.619803) (xy 95.174049 -120.507506) (xy 95.224129 -120.398281)
			(xy 95.281318 -120.292604) (xy 95.345367 -120.190938) (xy 95.415995 -120.093727) (xy 95.492893 -120.001397)
			(xy 95.575725 -119.91435) (xy 95.664129 -119.832969) (xy 95.757718 -119.757607) (xy 95.856084 -119.688597)
			(xy 95.958795 -119.626238) (xy 96.065403 -119.570803) (xy 96.175442 -119.522536) (xy 96.28843 -119.481646)
			(xy 96.403873 -119.448314) (xy 96.521267 -119.422684) (xy 96.640098 -119.404869) (xy 96.759847 -119.394946)
			(xy 96.87999 -119.392959) (xy 97.000001 -119.398917) (xy 97.119357 -119.412794) (xy 97.237534 -119.434528)
			(xy 97.354016 -119.464026) (xy 97.468294 -119.501157) (xy 97.579869 -119.54576) (xy 97.688251 -119.597639)
			(xy 97.792968 -119.656568) (xy 97.893561 -119.722289) (xy 97.989591 -119.794514) (xy 98.080638 -119.872928)
			(xy 98.166303 -119.957188) (xy 98.246212 -120.046926) (xy 98.320015 -120.141748) (xy 98.38739 -120.241241)
			(xy 98.448042 -120.34497) (xy 98.501706 -120.45248) (xy 98.548148 -120.563301) (xy 98.587163 -120.67695)
			(xy 98.618583 -120.792929) (xy 98.642268 -120.91073) (xy 98.658116 -121.02984) (xy 98.666058 -121.149736)
			(xy 98.666554 -121.209816) (xy 98.66613 -121.261212) (xy 103.161842 -121.261212) (xy 103.161842 -121.15842)
			(xy 103.169907 -121.055946) (xy 103.185987 -120.954421) (xy 103.209983 -120.85447) (xy 103.241748 -120.75671)
			(xy 103.281084 -120.661743) (xy 103.32775 -120.570156) (xy 103.381458 -120.482512) (xy 103.441877 -120.399352)
			(xy 103.508635 -120.321189) (xy 103.581319 -120.248505) (xy 103.659482 -120.181747) (xy 103.742642 -120.121328)
			(xy 103.830286 -120.06762) (xy 103.921873 -120.020954) (xy 104.01684 -119.981618) (xy 104.1146 -119.949853)
			(xy 104.214551 -119.925857) (xy 104.316076 -119.909777) (xy 104.41855 -119.901712) (xy 104.521342 -119.901712)
			(xy 104.623816 -119.909777) (xy 104.725341 -119.925857) (xy 104.825292 -119.949853) (xy 104.923052 -119.981618)
			(xy 105.018019 -120.020954) (xy 105.109606 -120.06762) (xy 105.19725 -120.121328) (xy 105.28041 -120.181747)
			(xy 105.358573 -120.248505) (xy 105.431257 -120.321189) (xy 105.498015 -120.399352) (xy 105.558434 -120.482512)
			(xy 105.612142 -120.570156) (xy 105.658808 -120.661743) (xy 105.698144 -120.75671) (xy 105.729909 -120.85447)
			(xy 105.753905 -120.954421) (xy 105.769985 -121.055946) (xy 105.77805 -121.15842) (xy 105.778554 -121.209816)
			(xy 127.413015 -121.209816) (xy 127.416988 -121.089722) (xy 127.428889 -120.970154) (xy 127.448667 -120.851634)
			(xy 127.476234 -120.734679) (xy 127.511471 -120.619803) (xy 127.554223 -120.507506) (xy 127.604303 -120.398281)
			(xy 127.661492 -120.292604) (xy 127.725541 -120.190938) (xy 127.796169 -120.093727) (xy 127.873067 -120.001397)
			(xy 127.955899 -119.91435) (xy 128.044303 -119.832969) (xy 128.137892 -119.757607) (xy 128.236258 -119.688597)
			(xy 128.338969 -119.626238) (xy 128.445577 -119.570803) (xy 128.555616 -119.522536) (xy 128.668604 -119.481646)
			(xy 128.784047 -119.448314) (xy 128.901441 -119.422684) (xy 129.020272 -119.404869) (xy 129.140021 -119.394946)
			(xy 129.260164 -119.392959) (xy 129.380175 -119.398917) (xy 129.499531 -119.412794) (xy 129.617708 -119.434528)
			(xy 129.73419 -119.464026) (xy 129.848468 -119.501157) (xy 129.960043 -119.54576) (xy 130.068425 -119.597639)
			(xy 130.173142 -119.656568) (xy 130.273735 -119.722289) (xy 130.369765 -119.794514) (xy 130.460812 -119.872928)
			(xy 130.546477 -119.957188) (xy 130.626386 -120.046926) (xy 130.700189 -120.141748) (xy 130.767564 -120.241241)
			(xy 130.828216 -120.34497) (xy 130.88188 -120.45248) (xy 130.928322 -120.563301) (xy 130.967337 -120.67695)
			(xy 130.998757 -120.792929) (xy 131.022442 -120.91073) (xy 131.03829 -121.02984) (xy 131.046232 -121.149736)
			(xy 131.046728 -121.209816) (xy 135.033015 -121.209816) (xy 135.036988 -121.089722) (xy 135.048889 -120.970154)
			(xy 135.068667 -120.851634) (xy 135.096234 -120.734679) (xy 135.131471 -120.619803) (xy 135.174223 -120.507506)
			(xy 135.224303 -120.398281) (xy 135.281492 -120.292604) (xy 135.345541 -120.190938) (xy 135.416169 -120.093727)
			(xy 135.493067 -120.001397) (xy 135.575899 -119.91435) (xy 135.664303 -119.832969) (xy 135.757892 -119.757607)
			(xy 135.856258 -119.688597) (xy 135.958969 -119.626238) (xy 136.065577 -119.570803) (xy 136.175616 -119.522536)
			(xy 136.288604 -119.481646) (xy 136.404047 -119.448314) (xy 136.521441 -119.422684) (xy 136.640272 -119.404869)
			(xy 136.760021 -119.394946) (xy 136.880164 -119.392959) (xy 137.000175 -119.398917) (xy 137.119531 -119.412794)
			(xy 137.237708 -119.434528) (xy 137.35419 -119.464026) (xy 137.468468 -119.501157) (xy 137.580043 -119.54576)
			(xy 137.688425 -119.597639) (xy 137.793142 -119.656568) (xy 137.893735 -119.722289) (xy 137.989765 -119.794514)
			(xy 138.080812 -119.872928) (xy 138.166477 -119.957188) (xy 138.246386 -120.046926) (xy 138.320189 -120.141748)
			(xy 138.387564 -120.241241) (xy 138.448216 -120.34497) (xy 138.50188 -120.45248) (xy 138.548322 -120.563301)
			(xy 138.587337 -120.67695) (xy 138.618757 -120.792929) (xy 138.642442 -120.91073) (xy 138.65829 -121.02984)
			(xy 138.666232 -121.149736) (xy 138.666728 -121.209816) (xy 138.666304 -121.261212) (xy 143.162016 -121.261212)
			(xy 143.162016 -121.15842) (xy 143.170081 -121.055946) (xy 143.186161 -120.954421) (xy 143.210157 -120.85447)
			(xy 143.241922 -120.75671) (xy 143.281258 -120.661743) (xy 143.327924 -120.570156) (xy 143.381632 -120.482512)
			(xy 143.442051 -120.399352) (xy 143.508809 -120.321189) (xy 143.581493 -120.248505) (xy 143.659656 -120.181747)
			(xy 143.742816 -120.121328) (xy 143.83046 -120.06762) (xy 143.922047 -120.020954) (xy 144.017014 -119.981618)
			(xy 144.114774 -119.949853) (xy 144.214725 -119.925857) (xy 144.31625 -119.909777) (xy 144.418724 -119.901712)
			(xy 144.521516 -119.901712) (xy 144.62399 -119.909777) (xy 144.725515 -119.925857) (xy 144.825466 -119.949853)
			(xy 144.923226 -119.981618) (xy 145.018193 -120.020954) (xy 145.10978 -120.06762) (xy 145.197424 -120.121328)
			(xy 145.280584 -120.181747) (xy 145.358747 -120.248505) (xy 145.431431 -120.321189) (xy 145.498189 -120.399352)
			(xy 145.558608 -120.482512) (xy 145.612316 -120.570156) (xy 145.658982 -120.661743) (xy 145.698318 -120.75671)
			(xy 145.730083 -120.85447) (xy 145.754079 -120.954421) (xy 145.770159 -121.055946) (xy 145.778224 -121.15842)
			(xy 145.778728 -121.209816) (xy 167.413189 -121.209816) (xy 167.417162 -121.089722) (xy 167.429063 -120.970154)
			(xy 167.448841 -120.851634) (xy 167.476408 -120.734679) (xy 167.511645 -120.619803) (xy 167.554397 -120.507506)
			(xy 167.604477 -120.398281) (xy 167.661666 -120.292604) (xy 167.725715 -120.190938) (xy 167.796343 -120.093727)
			(xy 167.873241 -120.001397) (xy 167.956073 -119.91435) (xy 168.044477 -119.832969) (xy 168.138066 -119.757607)
			(xy 168.236432 -119.688597) (xy 168.339143 -119.626238) (xy 168.445751 -119.570803) (xy 168.55579 -119.522536)
			(xy 168.668778 -119.481646) (xy 168.784221 -119.448314) (xy 168.901615 -119.422684) (xy 169.020446 -119.404869)
			(xy 169.140195 -119.394946) (xy 169.260338 -119.392959) (xy 169.380349 -119.398917) (xy 169.499705 -119.412794)
			(xy 169.617882 -119.434528) (xy 169.734364 -119.464026) (xy 169.848642 -119.501157) (xy 169.960217 -119.54576)
			(xy 170.068599 -119.597639) (xy 170.173316 -119.656568) (xy 170.273909 -119.722289) (xy 170.369939 -119.794514)
			(xy 170.460986 -119.872928) (xy 170.546651 -119.957188) (xy 170.62656 -120.046926) (xy 170.700363 -120.141748)
			(xy 170.767738 -120.241241) (xy 170.82839 -120.34497) (xy 170.882054 -120.45248) (xy 170.928496 -120.563301)
			(xy 170.967511 -120.67695) (xy 170.998931 -120.792929) (xy 171.022616 -120.91073) (xy 171.038464 -121.02984)
			(xy 171.046406 -121.149736) (xy 171.046902 -121.209816) (xy 175.033189 -121.209816) (xy 175.037162 -121.089722)
			(xy 175.049063 -120.970154) (xy 175.068841 -120.851634) (xy 175.096408 -120.734679) (xy 175.131645 -120.619803)
			(xy 175.174397 -120.507506) (xy 175.224477 -120.398281) (xy 175.281666 -120.292604) (xy 175.345715 -120.190938)
			(xy 175.416343 -120.093727) (xy 175.493241 -120.001397) (xy 175.576073 -119.91435) (xy 175.664477 -119.832969)
			(xy 175.758066 -119.757607) (xy 175.856432 -119.688597) (xy 175.959143 -119.626238) (xy 176.065751 -119.570803)
			(xy 176.17579 -119.522536) (xy 176.288778 -119.481646) (xy 176.404221 -119.448314) (xy 176.521615 -119.422684)
			(xy 176.640446 -119.404869) (xy 176.760195 -119.394946) (xy 176.880338 -119.392959) (xy 177.000349 -119.398917)
			(xy 177.119705 -119.412794) (xy 177.237882 -119.434528) (xy 177.354364 -119.464026) (xy 177.468642 -119.501157)
			(xy 177.580217 -119.54576) (xy 177.688599 -119.597639) (xy 177.793316 -119.656568) (xy 177.893909 -119.722289)
			(xy 177.989939 -119.794514) (xy 178.080986 -119.872928) (xy 178.166651 -119.957188) (xy 178.24656 -120.046926)
			(xy 178.320363 -120.141748) (xy 178.387738 -120.241241) (xy 178.44839 -120.34497) (xy 178.502054 -120.45248)
			(xy 178.548496 -120.563301) (xy 178.587511 -120.67695) (xy 178.618931 -120.792929) (xy 178.642616 -120.91073)
			(xy 178.658464 -121.02984) (xy 178.666406 -121.149736) (xy 178.666902 -121.209816) (xy 178.666478 -121.261212)
			(xy 183.16219 -121.261212) (xy 183.16219 -121.15842) (xy 183.170255 -121.055946) (xy 183.186335 -120.954421)
			(xy 183.210331 -120.85447) (xy 183.242096 -120.75671) (xy 183.281432 -120.661743) (xy 183.328098 -120.570156)
			(xy 183.381806 -120.482512) (xy 183.442225 -120.399352) (xy 183.508983 -120.321189) (xy 183.581667 -120.248505)
			(xy 183.65983 -120.181747) (xy 183.74299 -120.121328) (xy 183.830634 -120.06762) (xy 183.922221 -120.020954)
			(xy 184.017188 -119.981618) (xy 184.114948 -119.949853) (xy 184.214899 -119.925857) (xy 184.316424 -119.909777)
			(xy 184.418898 -119.901712) (xy 184.52169 -119.901712) (xy 184.624164 -119.909777) (xy 184.725689 -119.925857)
			(xy 184.82564 -119.949853) (xy 184.9234 -119.981618) (xy 185.018367 -120.020954) (xy 185.109954 -120.06762)
			(xy 185.197598 -120.121328) (xy 185.280758 -120.181747) (xy 185.358921 -120.248505) (xy 185.431605 -120.321189)
			(xy 185.498363 -120.399352) (xy 185.558782 -120.482512) (xy 185.61249 -120.570156) (xy 185.659156 -120.661743)
			(xy 185.698492 -120.75671) (xy 185.730257 -120.85447) (xy 185.754253 -120.954421) (xy 185.770333 -121.055946)
			(xy 185.778398 -121.15842) (xy 185.778902 -121.209816) (xy 185.778398 -121.261212) (xy 185.770333 -121.363686)
			(xy 185.754253 -121.465211) (xy 185.730257 -121.565162) (xy 185.698492 -121.662922) (xy 185.659156 -121.757889)
			(xy 185.61249 -121.849476) (xy 185.558782 -121.93712) (xy 185.498363 -122.02028) (xy 185.431605 -122.098443)
			(xy 185.358921 -122.171127) (xy 185.280758 -122.237885) (xy 185.197598 -122.298304) (xy 185.109954 -122.352012)
			(xy 185.018367 -122.398678) (xy 184.9234 -122.438014) (xy 184.82564 -122.469779) (xy 184.725689 -122.493775)
			(xy 184.624164 -122.509855) (xy 184.52169 -122.51792) (xy 184.418898 -122.51792) (xy 184.316424 -122.509855)
			(xy 184.214899 -122.493775) (xy 184.114948 -122.469779) (xy 184.017188 -122.438014) (xy 183.922221 -122.398678)
			(xy 183.830634 -122.352012) (xy 183.74299 -122.298304) (xy 183.65983 -122.237885) (xy 183.581667 -122.171127)
			(xy 183.508983 -122.098443) (xy 183.442225 -122.02028) (xy 183.381806 -121.93712) (xy 183.328098 -121.849476)
			(xy 183.281432 -121.757889) (xy 183.242096 -121.662922) (xy 183.210331 -121.565162) (xy 183.186335 -121.465211)
			(xy 183.170255 -121.363686) (xy 183.16219 -121.261212) (xy 178.666478 -121.261212) (xy 178.666406 -121.269896)
			(xy 178.658464 -121.389792) (xy 178.642616 -121.508902) (xy 178.618931 -121.626703) (xy 178.587511 -121.742682)
			(xy 178.548496 -121.856331) (xy 178.502054 -121.967152) (xy 178.44839 -122.074662) (xy 178.387738 -122.178391)
			(xy 178.320363 -122.277884) (xy 178.24656 -122.372706) (xy 178.166651 -122.462444) (xy 178.080986 -122.546704)
			(xy 177.989939 -122.625118) (xy 177.893909 -122.697343) (xy 177.793316 -122.763064) (xy 177.688599 -122.821993)
			(xy 177.580217 -122.873872) (xy 177.468642 -122.918475) (xy 177.354364 -122.955606) (xy 177.237882 -122.985104)
			(xy 177.119705 -123.006838) (xy 177.000349 -123.020715) (xy 176.880338 -123.026673) (xy 176.760195 -123.024686)
			(xy 176.640446 -123.014763) (xy 176.521615 -122.996948) (xy 176.404221 -122.971318) (xy 176.288778 -122.937986)
			(xy 176.17579 -122.897096) (xy 176.065751 -122.848829) (xy 175.959143 -122.793394) (xy 175.856432 -122.731035)
			(xy 175.758066 -122.662025) (xy 175.664477 -122.586663) (xy 175.576073 -122.505282) (xy 175.493241 -122.418235)
			(xy 175.416343 -122.325905) (xy 175.345715 -122.228694) (xy 175.281666 -122.127028) (xy 175.224477 -122.021351)
			(xy 175.174397 -121.912126) (xy 175.131645 -121.799829) (xy 175.096408 -121.684953) (xy 175.068841 -121.567998)
			(xy 175.049063 -121.449478) (xy 175.037162 -121.32991) (xy 175.033189 -121.209816) (xy 171.046902 -121.209816)
			(xy 171.046406 -121.269896) (xy 171.038464 -121.389792) (xy 171.022616 -121.508902) (xy 170.998931 -121.626703)
			(xy 170.967511 -121.742682) (xy 170.928496 -121.856331) (xy 170.882054 -121.967152) (xy 170.82839 -122.074662)
			(xy 170.767738 -122.178391) (xy 170.700363 -122.277884) (xy 170.62656 -122.372706) (xy 170.546651 -122.462444)
			(xy 170.460986 -122.546704) (xy 170.369939 -122.625118) (xy 170.273909 -122.697343) (xy 170.173316 -122.763064)
			(xy 170.068599 -122.821993) (xy 169.960217 -122.873872) (xy 169.848642 -122.918475) (xy 169.734364 -122.955606)
			(xy 169.617882 -122.985104) (xy 169.499705 -123.006838) (xy 169.380349 -123.020715) (xy 169.260338 -123.026673)
			(xy 169.140195 -123.024686) (xy 169.020446 -123.014763) (xy 168.901615 -122.996948) (xy 168.784221 -122.971318)
			(xy 168.668778 -122.937986) (xy 168.55579 -122.897096) (xy 168.445751 -122.848829) (xy 168.339143 -122.793394)
			(xy 168.236432 -122.731035) (xy 168.138066 -122.662025) (xy 168.044477 -122.586663) (xy 167.956073 -122.505282)
			(xy 167.873241 -122.418235) (xy 167.796343 -122.325905) (xy 167.725715 -122.228694) (xy 167.661666 -122.127028)
			(xy 167.604477 -122.021351) (xy 167.554397 -121.912126) (xy 167.511645 -121.799829) (xy 167.476408 -121.684953)
			(xy 167.448841 -121.567998) (xy 167.429063 -121.449478) (xy 167.417162 -121.32991) (xy 167.413189 -121.209816)
			(xy 145.778728 -121.209816) (xy 145.778224 -121.261212) (xy 145.770159 -121.363686) (xy 145.754079 -121.465211)
			(xy 145.730083 -121.565162) (xy 145.698318 -121.662922) (xy 145.658982 -121.757889) (xy 145.612316 -121.849476)
			(xy 145.558608 -121.93712) (xy 145.498189 -122.02028) (xy 145.431431 -122.098443) (xy 145.358747 -122.171127)
			(xy 145.280584 -122.237885) (xy 145.197424 -122.298304) (xy 145.10978 -122.352012) (xy 145.018193 -122.398678)
			(xy 144.923226 -122.438014) (xy 144.825466 -122.469779) (xy 144.725515 -122.493775) (xy 144.62399 -122.509855)
			(xy 144.521516 -122.51792) (xy 144.418724 -122.51792) (xy 144.31625 -122.509855) (xy 144.214725 -122.493775)
			(xy 144.114774 -122.469779) (xy 144.017014 -122.438014) (xy 143.922047 -122.398678) (xy 143.83046 -122.352012)
			(xy 143.742816 -122.298304) (xy 143.659656 -122.237885) (xy 143.581493 -122.171127) (xy 143.508809 -122.098443)
			(xy 143.442051 -122.02028) (xy 143.381632 -121.93712) (xy 143.327924 -121.849476) (xy 143.281258 -121.757889)
			(xy 143.241922 -121.662922) (xy 143.210157 -121.565162) (xy 143.186161 -121.465211) (xy 143.170081 -121.363686)
			(xy 143.162016 -121.261212) (xy 138.666304 -121.261212) (xy 138.666232 -121.269896) (xy 138.65829 -121.389792)
			(xy 138.642442 -121.508902) (xy 138.618757 -121.626703) (xy 138.587337 -121.742682) (xy 138.548322 -121.856331)
			(xy 138.50188 -121.967152) (xy 138.448216 -122.074662) (xy 138.387564 -122.178391) (xy 138.320189 -122.277884)
			(xy 138.246386 -122.372706) (xy 138.166477 -122.462444) (xy 138.080812 -122.546704) (xy 137.989765 -122.625118)
			(xy 137.893735 -122.697343) (xy 137.793142 -122.763064) (xy 137.688425 -122.821993) (xy 137.580043 -122.873872)
			(xy 137.468468 -122.918475) (xy 137.35419 -122.955606) (xy 137.237708 -122.985104) (xy 137.119531 -123.006838)
			(xy 137.000175 -123.020715) (xy 136.880164 -123.026673) (xy 136.760021 -123.024686) (xy 136.640272 -123.014763)
			(xy 136.521441 -122.996948) (xy 136.404047 -122.971318) (xy 136.288604 -122.937986) (xy 136.175616 -122.897096)
			(xy 136.065577 -122.848829) (xy 135.958969 -122.793394) (xy 135.856258 -122.731035) (xy 135.757892 -122.662025)
			(xy 135.664303 -122.586663) (xy 135.575899 -122.505282) (xy 135.493067 -122.418235) (xy 135.416169 -122.325905)
			(xy 135.345541 -122.228694) (xy 135.281492 -122.127028) (xy 135.224303 -122.021351) (xy 135.174223 -121.912126)
			(xy 135.131471 -121.799829) (xy 135.096234 -121.684953) (xy 135.068667 -121.567998) (xy 135.048889 -121.449478)
			(xy 135.036988 -121.32991) (xy 135.033015 -121.209816) (xy 131.046728 -121.209816) (xy 131.046232 -121.269896)
			(xy 131.03829 -121.389792) (xy 131.022442 -121.508902) (xy 130.998757 -121.626703) (xy 130.967337 -121.742682)
			(xy 130.928322 -121.856331) (xy 130.88188 -121.967152) (xy 130.828216 -122.074662) (xy 130.767564 -122.178391)
			(xy 130.700189 -122.277884) (xy 130.626386 -122.372706) (xy 130.546477 -122.462444) (xy 130.460812 -122.546704)
			(xy 130.369765 -122.625118) (xy 130.273735 -122.697343) (xy 130.173142 -122.763064) (xy 130.068425 -122.821993)
			(xy 129.960043 -122.873872) (xy 129.848468 -122.918475) (xy 129.73419 -122.955606) (xy 129.617708 -122.985104)
			(xy 129.499531 -123.006838) (xy 129.380175 -123.020715) (xy 129.260164 -123.026673) (xy 129.140021 -123.024686)
			(xy 129.020272 -123.014763) (xy 128.901441 -122.996948) (xy 128.784047 -122.971318) (xy 128.668604 -122.937986)
			(xy 128.555616 -122.897096) (xy 128.445577 -122.848829) (xy 128.338969 -122.793394) (xy 128.236258 -122.731035)
			(xy 128.137892 -122.662025) (xy 128.044303 -122.586663) (xy 127.955899 -122.505282) (xy 127.873067 -122.418235)
			(xy 127.796169 -122.325905) (xy 127.725541 -122.228694) (xy 127.661492 -122.127028) (xy 127.604303 -122.021351)
			(xy 127.554223 -121.912126) (xy 127.511471 -121.799829) (xy 127.476234 -121.684953) (xy 127.448667 -121.567998)
			(xy 127.428889 -121.449478) (xy 127.416988 -121.32991) (xy 127.413015 -121.209816) (xy 105.778554 -121.209816)
			(xy 105.77805 -121.261212) (xy 105.769985 -121.363686) (xy 105.753905 -121.465211) (xy 105.729909 -121.565162)
			(xy 105.698144 -121.662922) (xy 105.658808 -121.757889) (xy 105.612142 -121.849476) (xy 105.558434 -121.93712)
			(xy 105.498015 -122.02028) (xy 105.431257 -122.098443) (xy 105.358573 -122.171127) (xy 105.28041 -122.237885)
			(xy 105.19725 -122.298304) (xy 105.109606 -122.352012) (xy 105.018019 -122.398678) (xy 104.923052 -122.438014)
			(xy 104.825292 -122.469779) (xy 104.725341 -122.493775) (xy 104.623816 -122.509855) (xy 104.521342 -122.51792)
			(xy 104.41855 -122.51792) (xy 104.316076 -122.509855) (xy 104.214551 -122.493775) (xy 104.1146 -122.469779)
			(xy 104.01684 -122.438014) (xy 103.921873 -122.398678) (xy 103.830286 -122.352012) (xy 103.742642 -122.298304)
			(xy 103.659482 -122.237885) (xy 103.581319 -122.171127) (xy 103.508635 -122.098443) (xy 103.441877 -122.02028)
			(xy 103.381458 -121.93712) (xy 103.32775 -121.849476) (xy 103.281084 -121.757889) (xy 103.241748 -121.662922)
			(xy 103.209983 -121.565162) (xy 103.185987 -121.465211) (xy 103.169907 -121.363686) (xy 103.161842 -121.261212)
			(xy 98.66613 -121.261212) (xy 98.666058 -121.269896) (xy 98.658116 -121.389792) (xy 98.642268 -121.508902)
			(xy 98.618583 -121.626703) (xy 98.587163 -121.742682) (xy 98.548148 -121.856331) (xy 98.501706 -121.967152)
			(xy 98.448042 -122.074662) (xy 98.38739 -122.178391) (xy 98.320015 -122.277884) (xy 98.246212 -122.372706)
			(xy 98.166303 -122.462444) (xy 98.080638 -122.546704) (xy 97.989591 -122.625118) (xy 97.893561 -122.697343)
			(xy 97.792968 -122.763064) (xy 97.688251 -122.821993) (xy 97.579869 -122.873872) (xy 97.468294 -122.918475)
			(xy 97.354016 -122.955606) (xy 97.237534 -122.985104) (xy 97.119357 -123.006838) (xy 97.000001 -123.020715)
			(xy 96.87999 -123.026673) (xy 96.759847 -123.024686) (xy 96.640098 -123.014763) (xy 96.521267 -122.996948)
			(xy 96.403873 -122.971318) (xy 96.28843 -122.937986) (xy 96.175442 -122.897096) (xy 96.065403 -122.848829)
			(xy 95.958795 -122.793394) (xy 95.856084 -122.731035) (xy 95.757718 -122.662025) (xy 95.664129 -122.586663)
			(xy 95.575725 -122.505282) (xy 95.492893 -122.418235) (xy 95.415995 -122.325905) (xy 95.345367 -122.228694)
			(xy 95.281318 -122.127028) (xy 95.224129 -122.021351) (xy 95.174049 -121.912126) (xy 95.131297 -121.799829)
			(xy 95.09606 -121.684953) (xy 95.068493 -121.567998) (xy 95.048715 -121.449478) (xy 95.036814 -121.32991)
			(xy 95.032841 -121.209816) (xy 91.046554 -121.209816) (xy 91.046058 -121.269896) (xy 91.038116 -121.389792)
			(xy 91.022268 -121.508902) (xy 90.998583 -121.626703) (xy 90.967163 -121.742682) (xy 90.928148 -121.856331)
			(xy 90.881706 -121.967152) (xy 90.828042 -122.074662) (xy 90.76739 -122.178391) (xy 90.700015 -122.277884)
			(xy 90.626212 -122.372706) (xy 90.546303 -122.462444) (xy 90.460638 -122.546704) (xy 90.369591 -122.625118)
			(xy 90.273561 -122.697343) (xy 90.172968 -122.763064) (xy 90.068251 -122.821993) (xy 89.959869 -122.873872)
			(xy 89.848294 -122.918475) (xy 89.734016 -122.955606) (xy 89.617534 -122.985104) (xy 89.499357 -123.006838)
			(xy 89.380001 -123.020715) (xy 89.25999 -123.026673) (xy 89.139847 -123.024686) (xy 89.020098 -123.014763)
			(xy 88.901267 -122.996948) (xy 88.783873 -122.971318) (xy 88.66843 -122.937986) (xy 88.555442 -122.897096)
			(xy 88.445403 -122.848829) (xy 88.338795 -122.793394) (xy 88.236084 -122.731035) (xy 88.137718 -122.662025)
			(xy 88.044129 -122.586663) (xy 87.955725 -122.505282) (xy 87.872893 -122.418235) (xy 87.795995 -122.325905)
			(xy 87.725367 -122.228694) (xy 87.661318 -122.127028) (xy 87.604129 -122.021351) (xy 87.554049 -121.912126)
			(xy 87.511297 -121.799829) (xy 87.47606 -121.684953) (xy 87.448493 -121.567998) (xy 87.428715 -121.449478)
			(xy 87.416814 -121.32991) (xy 87.412841 -121.209816) (xy 65.778634 -121.209816) (xy 65.77813 -121.261212)
			(xy 65.770065 -121.363686) (xy 65.753985 -121.465211) (xy 65.729989 -121.565162) (xy 65.698224 -121.662922)
			(xy 65.658888 -121.757889) (xy 65.612222 -121.849476) (xy 65.558514 -121.93712) (xy 65.498095 -122.02028)
			(xy 65.431337 -122.098443) (xy 65.358653 -122.171127) (xy 65.28049 -122.237885) (xy 65.19733 -122.298304)
			(xy 65.109686 -122.352012) (xy 65.018099 -122.398678) (xy 64.923132 -122.438014) (xy 64.825372 -122.469779)
			(xy 64.725421 -122.493775) (xy 64.623896 -122.509855) (xy 64.521422 -122.51792) (xy 64.41863 -122.51792)
			(xy 64.316156 -122.509855) (xy 64.214631 -122.493775) (xy 64.11468 -122.469779) (xy 64.01692 -122.438014)
			(xy 63.921953 -122.398678) (xy 63.830366 -122.352012) (xy 63.742722 -122.298304) (xy 63.659562 -122.237885)
			(xy 63.581399 -122.171127) (xy 63.508715 -122.098443) (xy 63.441957 -122.02028) (xy 63.381538 -121.93712)
			(xy 63.32783 -121.849476) (xy 63.281164 -121.757889) (xy 63.241828 -121.662922) (xy 63.210063 -121.565162)
			(xy 63.186067 -121.465211) (xy 63.169987 -121.363686) (xy 63.161922 -121.261212) (xy 58.66621 -121.261212)
			(xy 58.666138 -121.269896) (xy 58.658196 -121.389792) (xy 58.642348 -121.508902) (xy 58.618663 -121.626703)
			(xy 58.587243 -121.742682) (xy 58.548228 -121.856331) (xy 58.501786 -121.967152) (xy 58.448122 -122.074662)
			(xy 58.38747 -122.178391) (xy 58.320095 -122.277884) (xy 58.246292 -122.372706) (xy 58.166383 -122.462444)
			(xy 58.080718 -122.546704) (xy 57.989671 -122.625118) (xy 57.893641 -122.697343) (xy 57.793048 -122.763064)
			(xy 57.688331 -122.821993) (xy 57.579949 -122.873872) (xy 57.468374 -122.918475) (xy 57.354096 -122.955606)
			(xy 57.237614 -122.985104) (xy 57.119437 -123.006838) (xy 57.000081 -123.020715) (xy 56.88007 -123.026673)
			(xy 56.759927 -123.024686) (xy 56.640178 -123.014763) (xy 56.521347 -122.996948) (xy 56.403953 -122.971318)
			(xy 56.28851 -122.937986) (xy 56.175522 -122.897096) (xy 56.065483 -122.848829) (xy 55.958875 -122.793394)
			(xy 55.856164 -122.731035) (xy 55.757798 -122.662025) (xy 55.664209 -122.586663) (xy 55.575805 -122.505282)
			(xy 55.492973 -122.418235) (xy 55.416075 -122.325905) (xy 55.345447 -122.228694) (xy 55.281398 -122.127028)
			(xy 55.224209 -122.021351) (xy 55.174129 -121.912126) (xy 55.131377 -121.799829) (xy 55.09614 -121.684953)
			(xy 55.068573 -121.567998) (xy 55.048795 -121.449478) (xy 55.036894 -121.32991) (xy 55.032921 -121.209816)
			(xy 51.046634 -121.209816) (xy 51.046138 -121.269896) (xy 51.038196 -121.389792) (xy 51.022348 -121.508902)
			(xy 50.998663 -121.626703) (xy 50.967243 -121.742682) (xy 50.928228 -121.856331) (xy 50.881786 -121.967152)
			(xy 50.828122 -122.074662) (xy 50.76747 -122.178391) (xy 50.700095 -122.277884) (xy 50.626292 -122.372706)
			(xy 50.546383 -122.462444) (xy 50.460718 -122.546704) (xy 50.369671 -122.625118) (xy 50.273641 -122.697343)
			(xy 50.173048 -122.763064) (xy 50.068331 -122.821993) (xy 49.959949 -122.873872) (xy 49.848374 -122.918475)
			(xy 49.734096 -122.955606) (xy 49.617614 -122.985104) (xy 49.499437 -123.006838) (xy 49.380081 -123.020715)
			(xy 49.26007 -123.026673) (xy 49.139927 -123.024686) (xy 49.020178 -123.014763) (xy 48.901347 -122.996948)
			(xy 48.783953 -122.971318) (xy 48.66851 -122.937986) (xy 48.555522 -122.897096) (xy 48.445483 -122.848829)
			(xy 48.338875 -122.793394) (xy 48.236164 -122.731035) (xy 48.137798 -122.662025) (xy 48.044209 -122.586663)
			(xy 47.955805 -122.505282) (xy 47.872973 -122.418235) (xy 47.796075 -122.325905) (xy 47.725447 -122.228694)
			(xy 47.661398 -122.127028) (xy 47.604209 -122.021351) (xy 47.554129 -121.912126) (xy 47.511377 -121.799829)
			(xy 47.47614 -121.684953) (xy 47.448573 -121.567998) (xy 47.428795 -121.449478) (xy 47.416894 -121.32991)
			(xy 47.412921 -121.209816) (xy 37.531802 -121.209816) (xy 37.531802 -126.492) (xy 44.966872 -126.492)
			(xy 44.970902 -126.407397) (xy 44.982956 -126.32356) (xy 45.002925 -126.241249) (xy 45.030627 -126.161209)
			(xy 45.065812 -126.084164) (xy 45.108162 -126.010813) (xy 45.157292 -125.941819) (xy 45.212758 -125.877808)
			(xy 45.274058 -125.81936) (xy 45.340636 -125.767002) (xy 45.411889 -125.721211) (xy 45.487173 -125.6824)
			(xy 45.565805 -125.650921) (xy 45.647073 -125.627059) (xy 45.730241 -125.61103) (xy 45.814557 -125.60298)
			(xy 45.856906 -125.602492) (xy 45.857414 -125.602492) (xy 45.903746 -125.603096) (xy 45.995904 -125.612768)
			(xy 46.086558 -125.631964) (xy 46.174727 -125.660477) (xy 46.217332 -125.678692) (xy 46.227272 -125.682512)
			(xy 46.24854 -125.682512) (xy 46.25848 -125.678692) (xy 46.301082 -125.660468) (xy 46.38925 -125.631951)
			(xy 46.479906 -125.612759) (xy 46.572066 -125.6031) (xy 46.618398 -125.602492) (xy 46.618906 -125.602492)
			(xy 46.661254 -125.602996) (xy 46.745567 -125.611047) (xy 46.828733 -125.627077) (xy 46.909999 -125.650939)
			(xy 46.988629 -125.682418) (xy 47.06391 -125.721229) (xy 47.135161 -125.767019) (xy 47.201737 -125.819376)
			(xy 47.263034 -125.877823) (xy 47.318499 -125.941833) (xy 47.367627 -126.010825) (xy 47.409975 -126.084174)
			(xy 47.44516 -126.161217) (xy 47.472861 -126.241256) (xy 47.492829 -126.323565) (xy 47.504882 -126.407399)
			(xy 47.508913 -126.492) (xy 57.158872 -126.492) (xy 57.162902 -126.407397) (xy 57.174956 -126.32356)
			(xy 57.194925 -126.241249) (xy 57.222627 -126.161209) (xy 57.257812 -126.084164) (xy 57.300162 -126.010813)
			(xy 57.349292 -125.941819) (xy 57.404758 -125.877808) (xy 57.466058 -125.81936) (xy 57.532636 -125.767002)
			(xy 57.603889 -125.721211) (xy 57.679173 -125.6824) (xy 57.757805 -125.650921) (xy 57.839073 -125.627059)
			(xy 57.922241 -125.61103) (xy 58.006557 -125.60298) (xy 58.048906 -125.602492) (xy 58.049414 -125.602492)
			(xy 58.095746 -125.603096) (xy 58.187904 -125.612768) (xy 58.278558 -125.631964) (xy 58.366727 -125.660477)
			(xy 58.409332 -125.678692) (xy 58.419272 -125.682512) (xy 58.44054 -125.682512) (xy 58.45048 -125.678692)
			(xy 58.493082 -125.660468) (xy 58.58125 -125.631951) (xy 58.671906 -125.612759) (xy 58.764066 -125.6031)
			(xy 58.810398 -125.602492) (xy 58.810906 -125.602492) (xy 58.853254 -125.602996) (xy 58.937567 -125.611047)
			(xy 59.020733 -125.627077) (xy 59.101999 -125.650939) (xy 59.180629 -125.682418) (xy 59.25591 -125.721229)
			(xy 59.327161 -125.767019) (xy 59.393737 -125.819376) (xy 59.455034 -125.877823) (xy 59.510499 -125.941833)
			(xy 59.559627 -126.010825) (xy 59.601975 -126.084174) (xy 59.63716 -126.161217) (xy 59.664861 -126.241256)
			(xy 59.684829 -126.323565) (xy 59.696882 -126.407399) (xy 59.700913 -126.492) (xy 69.350872 -126.492)
			(xy 69.354902 -126.407397) (xy 69.366956 -126.32356) (xy 69.386925 -126.241249) (xy 69.414627 -126.161209)
			(xy 69.449812 -126.084164) (xy 69.492162 -126.010813) (xy 69.541292 -125.941819) (xy 69.596758 -125.877808)
			(xy 69.658058 -125.81936) (xy 69.724636 -125.767002) (xy 69.795889 -125.721211) (xy 69.871173 -125.6824)
			(xy 69.949805 -125.650921) (xy 70.031073 -125.627059) (xy 70.114241 -125.61103) (xy 70.198557 -125.60298)
			(xy 70.240906 -125.602492) (xy 70.241414 -125.602492) (xy 70.287746 -125.603096) (xy 70.379904 -125.612768)
			(xy 70.470558 -125.631964) (xy 70.558727 -125.660477) (xy 70.601332 -125.678692) (xy 70.611272 -125.682512)
			(xy 70.63254 -125.682512) (xy 70.64248 -125.678692) (xy 70.685082 -125.660468) (xy 70.77325 -125.631951)
			(xy 70.863906 -125.612759) (xy 70.956066 -125.6031) (xy 71.002398 -125.602492) (xy 71.002906 -125.602492)
			(xy 71.045254 -125.602996) (xy 71.129567 -125.611047) (xy 71.212733 -125.627077) (xy 71.293999 -125.650939)
			(xy 71.372629 -125.682418) (xy 71.44791 -125.721229) (xy 71.519161 -125.767019) (xy 71.585737 -125.819376)
			(xy 71.647034 -125.877823) (xy 71.702499 -125.941833) (xy 71.751627 -126.010825) (xy 71.793975 -126.084174)
			(xy 71.82916 -126.161217) (xy 71.856861 -126.241256) (xy 71.876829 -126.323565) (xy 71.888882 -126.407399)
			(xy 71.892913 -126.492) (xy 84.966772 -126.492) (xy 84.970802 -126.407396) (xy 84.982857 -126.323558)
			(xy 85.002826 -126.241246) (xy 85.030529 -126.161204) (xy 85.065715 -126.084159) (xy 85.108066 -126.010807)
			(xy 85.157198 -125.941813) (xy 85.212665 -125.877801) (xy 85.273966 -125.819352) (xy 85.340546 -125.766995)
			(xy 85.411801 -125.721204) (xy 85.487086 -125.682394) (xy 85.56572 -125.650916) (xy 85.646989 -125.627055)
			(xy 85.730159 -125.611028) (xy 85.814476 -125.602979) (xy 85.856826 -125.602492) (xy 85.857334 -125.602492)
			(xy 85.903665 -125.603124) (xy 85.995822 -125.612788) (xy 86.086476 -125.631976) (xy 86.174646 -125.66048)
			(xy 86.217252 -125.678692) (xy 86.227192 -125.682512) (xy 86.24846 -125.682512) (xy 86.2584 -125.678692)
			(xy 86.300999 -125.660461) (xy 86.389168 -125.631946) (xy 86.479825 -125.612756) (xy 86.571985 -125.603099)
			(xy 86.618318 -125.602492) (xy 86.618826 -125.602492) (xy 86.661174 -125.602997) (xy 86.745485 -125.61105)
			(xy 86.82865 -125.627081) (xy 86.909914 -125.650944) (xy 86.988542 -125.682424) (xy 87.063821 -125.721235)
			(xy 87.135071 -125.767026) (xy 87.201645 -125.819383) (xy 87.262941 -125.87783) (xy 87.318404 -125.941839)
			(xy 87.367531 -126.010831) (xy 87.409878 -126.08418) (xy 87.445061 -126.161222) (xy 87.472762 -126.241259)
			(xy 87.492729 -126.323567) (xy 87.504783 -126.407401) (xy 87.508813 -126.492) (xy 97.158772 -126.492)
			(xy 97.162802 -126.407396) (xy 97.174857 -126.323558) (xy 97.194826 -126.241246) (xy 97.222529 -126.161204)
			(xy 97.257715 -126.084159) (xy 97.300066 -126.010807) (xy 97.349198 -125.941813) (xy 97.404665 -125.877801)
			(xy 97.465966 -125.819352) (xy 97.532546 -125.766995) (xy 97.603801 -125.721204) (xy 97.679086 -125.682394)
			(xy 97.75772 -125.650916) (xy 97.838989 -125.627055) (xy 97.922159 -125.611028) (xy 98.006476 -125.602979)
			(xy 98.048826 -125.602492) (xy 98.049334 -125.602492) (xy 98.095665 -125.603124) (xy 98.187822 -125.612788)
			(xy 98.278476 -125.631976) (xy 98.366646 -125.66048) (xy 98.409252 -125.678692) (xy 98.419192 -125.682512)
			(xy 98.44046 -125.682512) (xy 98.4504 -125.678692) (xy 98.492999 -125.660461) (xy 98.581168 -125.631946)
			(xy 98.671825 -125.612756) (xy 98.763985 -125.603099) (xy 98.810318 -125.602492) (xy 98.810826 -125.602492)
			(xy 98.853174 -125.602997) (xy 98.937485 -125.61105) (xy 99.02065 -125.627081) (xy 99.101914 -125.650944)
			(xy 99.180542 -125.682424) (xy 99.255821 -125.721235) (xy 99.327071 -125.767026) (xy 99.393645 -125.819383)
			(xy 99.454941 -125.87783) (xy 99.510404 -125.941839) (xy 99.559531 -126.010831) (xy 99.601878 -126.08418)
			(xy 99.637061 -126.161222) (xy 99.664762 -126.241259) (xy 99.684729 -126.323567) (xy 99.696783 -126.407401)
			(xy 99.700813 -126.492) (xy 109.350772 -126.492) (xy 109.354802 -126.407396) (xy 109.366857 -126.323558)
			(xy 109.386826 -126.241246) (xy 109.414529 -126.161204) (xy 109.449715 -126.084159) (xy 109.492066 -126.010807)
			(xy 109.541198 -125.941813) (xy 109.596665 -125.877801) (xy 109.657966 -125.819352) (xy 109.724546 -125.766995)
			(xy 109.795801 -125.721204) (xy 109.871086 -125.682394) (xy 109.94972 -125.650916) (xy 110.030989 -125.627055)
			(xy 110.114159 -125.611028) (xy 110.198476 -125.602979) (xy 110.240826 -125.602492) (xy 110.241334 -125.602492)
			(xy 110.287665 -125.603124) (xy 110.379822 -125.612788) (xy 110.470476 -125.631976) (xy 110.558646 -125.66048)
			(xy 110.601252 -125.678692) (xy 110.611192 -125.682512) (xy 110.63246 -125.682512) (xy 110.6424 -125.678692)
			(xy 110.684999 -125.660461) (xy 110.773168 -125.631946) (xy 110.863825 -125.612756) (xy 110.955985 -125.603099)
			(xy 111.002318 -125.602492) (xy 111.002826 -125.602492) (xy 111.045174 -125.602997) (xy 111.129485 -125.61105)
			(xy 111.21265 -125.627081) (xy 111.293914 -125.650944) (xy 111.372542 -125.682424) (xy 111.447821 -125.721235)
			(xy 111.519071 -125.767026) (xy 111.585645 -125.819383) (xy 111.646941 -125.87783) (xy 111.702404 -125.941839)
			(xy 111.751531 -126.010831) (xy 111.793878 -126.08418) (xy 111.829061 -126.161222) (xy 111.856762 -126.241259)
			(xy 111.876729 -126.323567) (xy 111.888783 -126.407401) (xy 111.892813 -126.492) (xy 124.966988 -126.492)
			(xy 124.971018 -126.407399) (xy 124.983071 -126.323564) (xy 125.003039 -126.241255) (xy 125.030741 -126.161216)
			(xy 125.065925 -126.084173) (xy 125.108274 -126.010823) (xy 125.157403 -125.941831) (xy 125.212868 -125.877821)
			(xy 125.274166 -125.819373) (xy 125.340742 -125.767017) (xy 125.411994 -125.721227) (xy 125.487275 -125.682416)
			(xy 125.565905 -125.650937) (xy 125.647172 -125.627076) (xy 125.730338 -125.611047) (xy 125.814652 -125.602996)
			(xy 125.857 -125.602492) (xy 125.857508 -125.602492) (xy 125.90384 -125.603098) (xy 125.995998 -125.612769)
			(xy 126.086652 -125.631965) (xy 126.174821 -125.660477) (xy 126.217426 -125.678692) (xy 126.227366 -125.682512)
			(xy 126.248634 -125.682512) (xy 126.258574 -125.678692) (xy 126.301177 -125.66047) (xy 126.389344 -125.631952)
			(xy 126.48 -125.61276) (xy 126.57216 -125.6031) (xy 126.618492 -125.602492) (xy 126.619 -125.602492)
			(xy 126.661348 -125.602996) (xy 126.745662 -125.611047) (xy 126.828828 -125.627076) (xy 126.910095 -125.650937)
			(xy 126.988725 -125.682416) (xy 127.064006 -125.721227) (xy 127.135258 -125.767017) (xy 127.201834 -125.819373)
			(xy 127.263132 -125.877821) (xy 127.318597 -125.941831) (xy 127.367726 -126.010823) (xy 127.410075 -126.084173)
			(xy 127.445259 -126.161216) (xy 127.472961 -126.241255) (xy 127.492929 -126.323564) (xy 127.504982 -126.407399)
			(xy 127.509013 -126.492) (xy 137.158988 -126.492) (xy 137.163018 -126.407399) (xy 137.175071 -126.323564)
			(xy 137.195039 -126.241255) (xy 137.222741 -126.161216) (xy 137.257925 -126.084173) (xy 137.300274 -126.010823)
			(xy 137.349403 -125.941831) (xy 137.404868 -125.877821) (xy 137.466166 -125.819373) (xy 137.532742 -125.767017)
			(xy 137.603994 -125.721227) (xy 137.679275 -125.682416) (xy 137.757905 -125.650937) (xy 137.839172 -125.627076)
			(xy 137.922338 -125.611047) (xy 138.006652 -125.602996) (xy 138.049 -125.602492) (xy 138.049508 -125.602492)
			(xy 138.09584 -125.603098) (xy 138.187998 -125.612769) (xy 138.278652 -125.631965) (xy 138.366821 -125.660477)
			(xy 138.409426 -125.678692) (xy 138.419366 -125.682512) (xy 138.440634 -125.682512) (xy 138.450574 -125.678692)
			(xy 138.493177 -125.66047) (xy 138.581344 -125.631952) (xy 138.672 -125.61276) (xy 138.76416 -125.6031)
			(xy 138.810492 -125.602492) (xy 138.811 -125.602492) (xy 138.853348 -125.602996) (xy 138.937662 -125.611047)
			(xy 139.020828 -125.627076) (xy 139.102095 -125.650937) (xy 139.180725 -125.682416) (xy 139.256006 -125.721227)
			(xy 139.327258 -125.767017) (xy 139.393834 -125.819373) (xy 139.455132 -125.877821) (xy 139.510597 -125.941831)
			(xy 139.559726 -126.010823) (xy 139.602075 -126.084173) (xy 139.637259 -126.161216) (xy 139.664961 -126.241255)
			(xy 139.684929 -126.323564) (xy 139.696982 -126.407399) (xy 139.701013 -126.492) (xy 149.350988 -126.492)
			(xy 149.355018 -126.407399) (xy 149.367071 -126.323564) (xy 149.387039 -126.241255) (xy 149.414741 -126.161216)
			(xy 149.449925 -126.084173) (xy 149.492274 -126.010823) (xy 149.541403 -125.941831) (xy 149.596868 -125.877821)
			(xy 149.658166 -125.819373) (xy 149.724742 -125.767017) (xy 149.795994 -125.721227) (xy 149.871275 -125.682416)
			(xy 149.949905 -125.650937) (xy 150.031172 -125.627076) (xy 150.114338 -125.611047) (xy 150.198652 -125.602996)
			(xy 150.241 -125.602492) (xy 150.241508 -125.602492) (xy 150.28784 -125.603098) (xy 150.379998 -125.612769)
			(xy 150.470652 -125.631965) (xy 150.558821 -125.660477) (xy 150.601426 -125.678692) (xy 150.611366 -125.682512)
			(xy 150.632634 -125.682512) (xy 150.642574 -125.678692) (xy 150.685177 -125.66047) (xy 150.773344 -125.631952)
			(xy 150.864 -125.61276) (xy 150.95616 -125.6031) (xy 151.002492 -125.602492) (xy 151.003 -125.602492)
			(xy 151.045348 -125.602996) (xy 151.129662 -125.611047) (xy 151.212828 -125.627076) (xy 151.294095 -125.650937)
			(xy 151.372725 -125.682416) (xy 151.448006 -125.721227) (xy 151.519258 -125.767017) (xy 151.585834 -125.819373)
			(xy 151.647132 -125.877821) (xy 151.702597 -125.941831) (xy 151.751726 -126.010823) (xy 151.794075 -126.084173)
			(xy 151.829259 -126.161216) (xy 151.856961 -126.241255) (xy 151.876929 -126.323564) (xy 151.888982 -126.407399)
			(xy 151.893013 -126.492) (xy 164.967187 -126.492) (xy 164.971217 -126.407401) (xy 164.983271 -126.323567)
			(xy 165.003238 -126.241259) (xy 165.030939 -126.161222) (xy 165.066122 -126.08418) (xy 165.108469 -126.010831)
			(xy 165.157596 -125.941839) (xy 165.213059 -125.87783) (xy 165.274355 -125.819383) (xy 165.340929 -125.767026)
			(xy 165.412179 -125.721235) (xy 165.487458 -125.682424) (xy 165.566086 -125.650944) (xy 165.64735 -125.627081)
			(xy 165.730515 -125.61105) (xy 165.814826 -125.602997) (xy 165.857174 -125.602492) (xy 165.857682 -125.602492)
			(xy 165.904014 -125.603107) (xy 165.996171 -125.612776) (xy 166.086825 -125.631969) (xy 166.174994 -125.660478)
			(xy 166.2176 -125.678692) (xy 166.22754 -125.682512) (xy 166.248808 -125.682512) (xy 166.258748 -125.678692)
			(xy 166.301354 -125.660479) (xy 166.389521 -125.631959) (xy 166.480175 -125.612764) (xy 166.572334 -125.603101)
			(xy 166.618666 -125.602492) (xy 166.619174 -125.602492) (xy 166.661524 -125.602979) (xy 166.745841 -125.611028)
			(xy 166.829011 -125.627055) (xy 166.91028 -125.650916) (xy 166.988914 -125.682394) (xy 167.064199 -125.721204)
			(xy 167.135454 -125.766995) (xy 167.202034 -125.819352) (xy 167.263335 -125.877801) (xy 167.318802 -125.941813)
			(xy 167.367934 -126.010807) (xy 167.410285 -126.084159) (xy 167.445471 -126.161204) (xy 167.473174 -126.241246)
			(xy 167.493143 -126.323558) (xy 167.505198 -126.407396) (xy 167.509228 -126.492) (xy 177.159187 -126.492)
			(xy 177.163217 -126.407401) (xy 177.175271 -126.323567) (xy 177.195238 -126.241259) (xy 177.222939 -126.161222)
			(xy 177.258122 -126.08418) (xy 177.300469 -126.010831) (xy 177.349596 -125.941839) (xy 177.405059 -125.87783)
			(xy 177.466355 -125.819383) (xy 177.532929 -125.767026) (xy 177.604179 -125.721235) (xy 177.679458 -125.682424)
			(xy 177.758086 -125.650944) (xy 177.83935 -125.627081) (xy 177.922515 -125.61105) (xy 178.006826 -125.602997)
			(xy 178.049174 -125.602492) (xy 178.049682 -125.602492) (xy 178.096014 -125.603107) (xy 178.188171 -125.612776)
			(xy 178.278825 -125.631969) (xy 178.366994 -125.660478) (xy 178.4096 -125.678692) (xy 178.41954 -125.682512)
			(xy 178.440808 -125.682512) (xy 178.450748 -125.678692) (xy 178.493354 -125.660479) (xy 178.581521 -125.631959)
			(xy 178.672175 -125.612764) (xy 178.764334 -125.603101) (xy 178.810666 -125.602492) (xy 178.811174 -125.602492)
			(xy 178.853524 -125.602979) (xy 178.937841 -125.611028) (xy 179.021011 -125.627055) (xy 179.10228 -125.650916)
			(xy 179.180914 -125.682394) (xy 179.256199 -125.721204) (xy 179.327454 -125.766995) (xy 179.394034 -125.819352)
			(xy 179.455335 -125.877801) (xy 179.510802 -125.941813) (xy 179.559934 -126.010807) (xy 179.602285 -126.084159)
			(xy 179.637471 -126.161204) (xy 179.665174 -126.241246) (xy 179.685143 -126.323558) (xy 179.697198 -126.407396)
			(xy 179.701228 -126.492) (xy 189.351187 -126.492) (xy 189.355217 -126.407401) (xy 189.367271 -126.323567)
			(xy 189.387238 -126.241259) (xy 189.414939 -126.161222) (xy 189.450122 -126.08418) (xy 189.492469 -126.010831)
			(xy 189.541596 -125.941839) (xy 189.597059 -125.87783) (xy 189.658355 -125.819383) (xy 189.724929 -125.767026)
			(xy 189.796179 -125.721235) (xy 189.871458 -125.682424) (xy 189.950086 -125.650944) (xy 190.03135 -125.627081)
			(xy 190.114515 -125.61105) (xy 190.198826 -125.602997) (xy 190.241174 -125.602492) (xy 190.241682 -125.602492)
			(xy 190.288014 -125.603107) (xy 190.380171 -125.612776) (xy 190.470825 -125.631969) (xy 190.558994 -125.660478)
			(xy 190.6016 -125.678692) (xy 190.61154 -125.682512) (xy 190.632808 -125.682512) (xy 190.642748 -125.678692)
			(xy 190.685354 -125.660479) (xy 190.773521 -125.631959) (xy 190.864175 -125.612764) (xy 190.956334 -125.603101)
			(xy 191.002666 -125.602492) (xy 191.003174 -125.602492) (xy 191.045524 -125.602979) (xy 191.129841 -125.611028)
			(xy 191.213011 -125.627055) (xy 191.29428 -125.650916) (xy 191.372914 -125.682394) (xy 191.448199 -125.721204)
			(xy 191.519454 -125.766995) (xy 191.586034 -125.819352) (xy 191.647335 -125.877801) (xy 191.702802 -125.941813)
			(xy 191.751934 -126.010807) (xy 191.794285 -126.084159) (xy 191.829471 -126.161204) (xy 191.857174 -126.241246)
			(xy 191.877143 -126.323558) (xy 191.889198 -126.407396) (xy 191.893228 -126.492) (xy 191.889198 -126.576604)
			(xy 191.877143 -126.660442) (xy 191.857174 -126.742754) (xy 191.829471 -126.822796) (xy 191.794285 -126.899841)
			(xy 191.751934 -126.973193) (xy 191.702802 -127.042187) (xy 191.647335 -127.106199) (xy 191.586034 -127.164648)
			(xy 191.519454 -127.217005) (xy 191.448199 -127.262796) (xy 191.372914 -127.301606) (xy 191.29428 -127.333084)
			(xy 191.213011 -127.356945) (xy 191.129841 -127.372972) (xy 191.045524 -127.381021) (xy 191.003174 -127.381508)
			(xy 191.002666 -127.381508) (xy 190.956335 -127.380876) (xy 190.864178 -127.371212) (xy 190.773524 -127.352024)
			(xy 190.685354 -127.32352) (xy 190.642748 -127.305308) (xy 190.632808 -127.301488) (xy 190.61154 -127.301488)
			(xy 190.6016 -127.305308) (xy 190.559001 -127.323539) (xy 190.470832 -127.352054) (xy 190.380175 -127.371244)
			(xy 190.288015 -127.380901) (xy 190.241682 -127.381508) (xy 190.241174 -127.381508) (xy 190.198826 -127.381003)
			(xy 190.114515 -127.37295) (xy 190.03135 -127.356919) (xy 189.950086 -127.333056) (xy 189.871458 -127.301576)
			(xy 189.796179 -127.262765) (xy 189.724929 -127.216974) (xy 189.658355 -127.164617) (xy 189.597059 -127.10617)
			(xy 189.541596 -127.042161) (xy 189.492469 -126.973169) (xy 189.450122 -126.89982) (xy 189.414939 -126.822778)
			(xy 189.387238 -126.742741) (xy 189.367271 -126.660433) (xy 189.355217 -126.576599) (xy 189.351187 -126.492)
			(xy 179.701228 -126.492) (xy 179.697198 -126.576604) (xy 179.685143 -126.660442) (xy 179.665174 -126.742754)
			(xy 179.637471 -126.822796) (xy 179.602285 -126.899841) (xy 179.559934 -126.973193) (xy 179.510802 -127.042187)
			(xy 179.455335 -127.106199) (xy 179.394034 -127.164648) (xy 179.327454 -127.217005) (xy 179.256199 -127.262796)
			(xy 179.180914 -127.301606) (xy 179.10228 -127.333084) (xy 179.021011 -127.356945) (xy 178.937841 -127.372972)
			(xy 178.853524 -127.381021) (xy 178.811174 -127.381508) (xy 178.810666 -127.381508) (xy 178.764335 -127.380876)
			(xy 178.672178 -127.371212) (xy 178.581524 -127.352024) (xy 178.493354 -127.32352) (xy 178.450748 -127.305308)
			(xy 178.440808 -127.301488) (xy 178.41954 -127.301488) (xy 178.4096 -127.305308) (xy 178.367001 -127.323539)
			(xy 178.278832 -127.352054) (xy 178.188175 -127.371244) (xy 178.096015 -127.380901) (xy 178.049682 -127.381508)
			(xy 178.049174 -127.381508) (xy 178.006826 -127.381003) (xy 177.922515 -127.37295) (xy 177.83935 -127.356919)
			(xy 177.758086 -127.333056) (xy 177.679458 -127.301576) (xy 177.604179 -127.262765) (xy 177.532929 -127.216974)
			(xy 177.466355 -127.164617) (xy 177.405059 -127.10617) (xy 177.349596 -127.042161) (xy 177.300469 -126.973169)
			(xy 177.258122 -126.89982) (xy 177.222939 -126.822778) (xy 177.195238 -126.742741) (xy 177.175271 -126.660433)
			(xy 177.163217 -126.576599) (xy 177.159187 -126.492) (xy 167.509228 -126.492) (xy 167.505198 -126.576604)
			(xy 167.493143 -126.660442) (xy 167.473174 -126.742754) (xy 167.445471 -126.822796) (xy 167.410285 -126.899841)
			(xy 167.367934 -126.973193) (xy 167.318802 -127.042187) (xy 167.263335 -127.106199) (xy 167.202034 -127.164648)
			(xy 167.135454 -127.217005) (xy 167.064199 -127.262796) (xy 166.988914 -127.301606) (xy 166.91028 -127.333084)
			(xy 166.829011 -127.356945) (xy 166.745841 -127.372972) (xy 166.661524 -127.381021) (xy 166.619174 -127.381508)
			(xy 166.618666 -127.381508) (xy 166.572335 -127.380876) (xy 166.480178 -127.371212) (xy 166.389524 -127.352024)
			(xy 166.301354 -127.32352) (xy 166.258748 -127.305308) (xy 166.248808 -127.301488) (xy 166.22754 -127.301488)
			(xy 166.2176 -127.305308) (xy 166.175001 -127.323539) (xy 166.086832 -127.352054) (xy 165.996175 -127.371244)
			(xy 165.904015 -127.380901) (xy 165.857682 -127.381508) (xy 165.857174 -127.381508) (xy 165.814826 -127.381003)
			(xy 165.730515 -127.37295) (xy 165.64735 -127.356919) (xy 165.566086 -127.333056) (xy 165.487458 -127.301576)
			(xy 165.412179 -127.262765) (xy 165.340929 -127.216974) (xy 165.274355 -127.164617) (xy 165.213059 -127.10617)
			(xy 165.157596 -127.042161) (xy 165.108469 -126.973169) (xy 165.066122 -126.89982) (xy 165.030939 -126.822778)
			(xy 165.003238 -126.742741) (xy 164.983271 -126.660433) (xy 164.971217 -126.576599) (xy 164.967187 -126.492)
			(xy 151.893013 -126.492) (xy 151.888982 -126.576601) (xy 151.876929 -126.660436) (xy 151.856961 -126.742745)
			(xy 151.829259 -126.822784) (xy 151.794075 -126.899827) (xy 151.751726 -126.973177) (xy 151.702597 -127.042169)
			(xy 151.647132 -127.106179) (xy 151.585834 -127.164627) (xy 151.519258 -127.216983) (xy 151.448006 -127.262773)
			(xy 151.372725 -127.301584) (xy 151.294095 -127.333063) (xy 151.212828 -127.356924) (xy 151.129662 -127.372953)
			(xy 151.045348 -127.381004) (xy 151.003 -127.381508) (xy 151.002492 -127.381508) (xy 150.95616 -127.380902)
			(xy 150.864002 -127.371231) (xy 150.773348 -127.352035) (xy 150.685179 -127.323523) (xy 150.642574 -127.305308)
			(xy 150.632634 -127.301488) (xy 150.611366 -127.301488) (xy 150.601426 -127.305308) (xy 150.558823 -127.32353)
			(xy 150.470656 -127.352048) (xy 150.38 -127.37124) (xy 150.28784 -127.3809) (xy 150.241508 -127.381508)
			(xy 150.241 -127.381508) (xy 150.198652 -127.381004) (xy 150.114338 -127.372953) (xy 150.031172 -127.356924)
			(xy 149.949905 -127.333063) (xy 149.871275 -127.301584) (xy 149.795994 -127.262773) (xy 149.724742 -127.216983)
			(xy 149.658166 -127.164627) (xy 149.596868 -127.106179) (xy 149.541403 -127.042169) (xy 149.492274 -126.973177)
			(xy 149.449925 -126.899827) (xy 149.414741 -126.822784) (xy 149.387039 -126.742745) (xy 149.367071 -126.660436)
			(xy 149.355018 -126.576601) (xy 149.350988 -126.492) (xy 139.701013 -126.492) (xy 139.696982 -126.576601)
			(xy 139.684929 -126.660436) (xy 139.664961 -126.742745) (xy 139.637259 -126.822784) (xy 139.602075 -126.899827)
			(xy 139.559726 -126.973177) (xy 139.510597 -127.042169) (xy 139.455132 -127.106179) (xy 139.393834 -127.164627)
			(xy 139.327258 -127.216983) (xy 139.256006 -127.262773) (xy 139.180725 -127.301584) (xy 139.102095 -127.333063)
			(xy 139.020828 -127.356924) (xy 138.937662 -127.372953) (xy 138.853348 -127.381004) (xy 138.811 -127.381508)
			(xy 138.810492 -127.381508) (xy 138.76416 -127.380902) (xy 138.672002 -127.371231) (xy 138.581348 -127.352035)
			(xy 138.493179 -127.323523) (xy 138.450574 -127.305308) (xy 138.440634 -127.301488) (xy 138.419366 -127.301488)
			(xy 138.409426 -127.305308) (xy 138.366823 -127.32353) (xy 138.278656 -127.352048) (xy 138.188 -127.37124)
			(xy 138.09584 -127.3809) (xy 138.049508 -127.381508) (xy 138.049 -127.381508) (xy 138.006652 -127.381004)
			(xy 137.922338 -127.372953) (xy 137.839172 -127.356924) (xy 137.757905 -127.333063) (xy 137.679275 -127.301584)
			(xy 137.603994 -127.262773) (xy 137.532742 -127.216983) (xy 137.466166 -127.164627) (xy 137.404868 -127.106179)
			(xy 137.349403 -127.042169) (xy 137.300274 -126.973177) (xy 137.257925 -126.899827) (xy 137.222741 -126.822784)
			(xy 137.195039 -126.742745) (xy 137.175071 -126.660436) (xy 137.163018 -126.576601) (xy 137.158988 -126.492)
			(xy 127.509013 -126.492) (xy 127.504982 -126.576601) (xy 127.492929 -126.660436) (xy 127.472961 -126.742745)
			(xy 127.445259 -126.822784) (xy 127.410075 -126.899827) (xy 127.367726 -126.973177) (xy 127.318597 -127.042169)
			(xy 127.263132 -127.106179) (xy 127.201834 -127.164627) (xy 127.135258 -127.216983) (xy 127.064006 -127.262773)
			(xy 126.988725 -127.301584) (xy 126.910095 -127.333063) (xy 126.828828 -127.356924) (xy 126.745662 -127.372953)
			(xy 126.661348 -127.381004) (xy 126.619 -127.381508) (xy 126.618492 -127.381508) (xy 126.57216 -127.380902)
			(xy 126.480002 -127.371231) (xy 126.389348 -127.352035) (xy 126.301179 -127.323523) (xy 126.258574 -127.305308)
			(xy 126.248634 -127.301488) (xy 126.227366 -127.301488) (xy 126.217426 -127.305308) (xy 126.174823 -127.32353)
			(xy 126.086656 -127.352048) (xy 125.996 -127.37124) (xy 125.90384 -127.3809) (xy 125.857508 -127.381508)
			(xy 125.857 -127.381508) (xy 125.814652 -127.381004) (xy 125.730338 -127.372953) (xy 125.647172 -127.356924)
			(xy 125.565905 -127.333063) (xy 125.487275 -127.301584) (xy 125.411994 -127.262773) (xy 125.340742 -127.216983)
			(xy 125.274166 -127.164627) (xy 125.212868 -127.106179) (xy 125.157403 -127.042169) (xy 125.108274 -126.973177)
			(xy 125.065925 -126.899827) (xy 125.030741 -126.822784) (xy 125.003039 -126.742745) (xy 124.983071 -126.660436)
			(xy 124.971018 -126.576601) (xy 124.966988 -126.492) (xy 111.892813 -126.492) (xy 111.888783 -126.576599)
			(xy 111.876729 -126.660433) (xy 111.856762 -126.742741) (xy 111.829061 -126.822778) (xy 111.793878 -126.89982)
			(xy 111.751531 -126.973169) (xy 111.702404 -127.042161) (xy 111.646941 -127.10617) (xy 111.585645 -127.164617)
			(xy 111.519071 -127.216974) (xy 111.447821 -127.262765) (xy 111.372542 -127.301576) (xy 111.293914 -127.333056)
			(xy 111.21265 -127.356919) (xy 111.129485 -127.37295) (xy 111.045174 -127.381003) (xy 111.002826 -127.381508)
			(xy 111.002318 -127.381508) (xy 110.955986 -127.380893) (xy 110.863829 -127.371224) (xy 110.773175 -127.352031)
			(xy 110.685006 -127.323522) (xy 110.6424 -127.305308) (xy 110.63246 -127.301488) (xy 110.611192 -127.301488)
			(xy 110.601252 -127.305308) (xy 110.558646 -127.323521) (xy 110.470479 -127.352041) (xy 110.379825 -127.371236)
			(xy 110.287666 -127.380899) (xy 110.241334 -127.381508) (xy 110.240826 -127.381508) (xy 110.198476 -127.381021)
			(xy 110.114159 -127.372972) (xy 110.030989 -127.356945) (xy 109.94972 -127.333084) (xy 109.871086 -127.301606)
			(xy 109.795801 -127.262796) (xy 109.724546 -127.217005) (xy 109.657966 -127.164648) (xy 109.596665 -127.106199)
			(xy 109.541198 -127.042187) (xy 109.492066 -126.973193) (xy 109.449715 -126.899841) (xy 109.414529 -126.822796)
			(xy 109.386826 -126.742754) (xy 109.366857 -126.660442) (xy 109.354802 -126.576604) (xy 109.350772 -126.492)
			(xy 99.700813 -126.492) (xy 99.696783 -126.576599) (xy 99.684729 -126.660433) (xy 99.664762 -126.742741)
			(xy 99.637061 -126.822778) (xy 99.601878 -126.89982) (xy 99.559531 -126.973169) (xy 99.510404 -127.042161)
			(xy 99.454941 -127.10617) (xy 99.393645 -127.164617) (xy 99.327071 -127.216974) (xy 99.255821 -127.262765)
			(xy 99.180542 -127.301576) (xy 99.101914 -127.333056) (xy 99.02065 -127.356919) (xy 98.937485 -127.37295)
			(xy 98.853174 -127.381003) (xy 98.810826 -127.381508) (xy 98.810318 -127.381508) (xy 98.763986 -127.380893)
			(xy 98.671829 -127.371224) (xy 98.581175 -127.352031) (xy 98.493006 -127.323522) (xy 98.4504 -127.305308)
			(xy 98.44046 -127.301488) (xy 98.419192 -127.301488) (xy 98.409252 -127.305308) (xy 98.366646 -127.323521)
			(xy 98.278479 -127.352041) (xy 98.187825 -127.371236) (xy 98.095666 -127.380899) (xy 98.049334 -127.381508)
			(xy 98.048826 -127.381508) (xy 98.006476 -127.381021) (xy 97.922159 -127.372972) (xy 97.838989 -127.356945)
			(xy 97.75772 -127.333084) (xy 97.679086 -127.301606) (xy 97.603801 -127.262796) (xy 97.532546 -127.217005)
			(xy 97.465966 -127.164648) (xy 97.404665 -127.106199) (xy 97.349198 -127.042187) (xy 97.300066 -126.973193)
			(xy 97.257715 -126.899841) (xy 97.222529 -126.822796) (xy 97.194826 -126.742754) (xy 97.174857 -126.660442)
			(xy 97.162802 -126.576604) (xy 97.158772 -126.492) (xy 87.508813 -126.492) (xy 87.504783 -126.576599)
			(xy 87.492729 -126.660433) (xy 87.472762 -126.742741) (xy 87.445061 -126.822778) (xy 87.409878 -126.89982)
			(xy 87.367531 -126.973169) (xy 87.318404 -127.042161) (xy 87.262941 -127.10617) (xy 87.201645 -127.164617)
			(xy 87.135071 -127.216974) (xy 87.063821 -127.262765) (xy 86.988542 -127.301576) (xy 86.909914 -127.333056)
			(xy 86.82865 -127.356919) (xy 86.745485 -127.37295) (xy 86.661174 -127.381003) (xy 86.618826 -127.381508)
			(xy 86.618318 -127.381508) (xy 86.571986 -127.380893) (xy 86.479829 -127.371224) (xy 86.389175 -127.352031)
			(xy 86.301006 -127.323522) (xy 86.2584 -127.305308) (xy 86.24846 -127.301488) (xy 86.227192 -127.301488)
			(xy 86.217252 -127.305308) (xy 86.174646 -127.323521) (xy 86.086479 -127.352041) (xy 85.995825 -127.371236)
			(xy 85.903666 -127.380899) (xy 85.857334 -127.381508) (xy 85.856826 -127.381508) (xy 85.814476 -127.381021)
			(xy 85.730159 -127.372972) (xy 85.646989 -127.356945) (xy 85.56572 -127.333084) (xy 85.487086 -127.301606)
			(xy 85.411801 -127.262796) (xy 85.340546 -127.217005) (xy 85.273966 -127.164648) (xy 85.212665 -127.106199)
			(xy 85.157198 -127.042187) (xy 85.108066 -126.973193) (xy 85.065715 -126.899841) (xy 85.030529 -126.822796)
			(xy 85.002826 -126.742754) (xy 84.982857 -126.660442) (xy 84.970802 -126.576604) (xy 84.966772 -126.492)
			(xy 71.892913 -126.492) (xy 71.888882 -126.576601) (xy 71.876829 -126.660435) (xy 71.856861 -126.742744)
			(xy 71.82916 -126.822783) (xy 71.793975 -126.899826) (xy 71.751627 -126.973175) (xy 71.702499 -127.042167)
			(xy 71.647034 -127.106177) (xy 71.585737 -127.164624) (xy 71.519161 -127.216981) (xy 71.44791 -127.262771)
			(xy 71.372629 -127.301582) (xy 71.293999 -127.333061) (xy 71.212733 -127.356923) (xy 71.129567 -127.372953)
			(xy 71.045254 -127.381004) (xy 71.002906 -127.381508) (xy 71.002398 -127.381508) (xy 70.956066 -127.3809)
			(xy 70.863908 -127.371229) (xy 70.773254 -127.352034) (xy 70.685085 -127.323523) (xy 70.64248 -127.305308)
			(xy 70.63254 -127.301488) (xy 70.611272 -127.301488) (xy 70.601332 -127.305308) (xy 70.558728 -127.323528)
			(xy 70.470561 -127.352046) (xy 70.379906 -127.371239) (xy 70.287746 -127.3809) (xy 70.241414 -127.381508)
			(xy 70.240906 -127.381508) (xy 70.198557 -127.38102) (xy 70.114241 -127.37297) (xy 70.031073 -127.356941)
			(xy 69.949805 -127.333079) (xy 69.871173 -127.3016) (xy 69.795889 -127.262789) (xy 69.724636 -127.216998)
			(xy 69.658058 -127.16464) (xy 69.596758 -127.106192) (xy 69.541292 -127.042181) (xy 69.492162 -126.973187)
			(xy 69.449812 -126.899836) (xy 69.414627 -126.822791) (xy 69.386925 -126.742751) (xy 69.366956 -126.66044)
			(xy 69.354902 -126.576603) (xy 69.350872 -126.492) (xy 59.700913 -126.492) (xy 59.696882 -126.576601)
			(xy 59.684829 -126.660435) (xy 59.664861 -126.742744) (xy 59.63716 -126.822783) (xy 59.601975 -126.899826)
			(xy 59.559627 -126.973175) (xy 59.510499 -127.042167) (xy 59.455034 -127.106177) (xy 59.393737 -127.164624)
			(xy 59.327161 -127.216981) (xy 59.25591 -127.262771) (xy 59.180629 -127.301582) (xy 59.101999 -127.333061)
			(xy 59.020733 -127.356923) (xy 58.937567 -127.372953) (xy 58.853254 -127.381004) (xy 58.810906 -127.381508)
			(xy 58.810398 -127.381508) (xy 58.764066 -127.3809) (xy 58.671908 -127.371229) (xy 58.581254 -127.352034)
			(xy 58.493085 -127.323523) (xy 58.45048 -127.305308) (xy 58.44054 -127.301488) (xy 58.419272 -127.301488)
			(xy 58.409332 -127.305308) (xy 58.366728 -127.323528) (xy 58.278561 -127.352046) (xy 58.187906 -127.371239)
			(xy 58.095746 -127.3809) (xy 58.049414 -127.381508) (xy 58.048906 -127.381508) (xy 58.006557 -127.38102)
			(xy 57.922241 -127.37297) (xy 57.839073 -127.356941) (xy 57.757805 -127.333079) (xy 57.679173 -127.3016)
			(xy 57.603889 -127.262789) (xy 57.532636 -127.216998) (xy 57.466058 -127.16464) (xy 57.404758 -127.106192)
			(xy 57.349292 -127.042181) (xy 57.300162 -126.973187) (xy 57.257812 -126.899836) (xy 57.222627 -126.822791)
			(xy 57.194925 -126.742751) (xy 57.174956 -126.66044) (xy 57.162902 -126.576603) (xy 57.158872 -126.492)
			(xy 47.508913 -126.492) (xy 47.504882 -126.576601) (xy 47.492829 -126.660435) (xy 47.472861 -126.742744)
			(xy 47.44516 -126.822783) (xy 47.409975 -126.899826) (xy 47.367627 -126.973175) (xy 47.318499 -127.042167)
			(xy 47.263034 -127.106177) (xy 47.201737 -127.164624) (xy 47.135161 -127.216981) (xy 47.06391 -127.262771)
			(xy 46.988629 -127.301582) (xy 46.909999 -127.333061) (xy 46.828733 -127.356923) (xy 46.745567 -127.372953)
			(xy 46.661254 -127.381004) (xy 46.618906 -127.381508) (xy 46.618398 -127.381508) (xy 46.572066 -127.3809)
			(xy 46.479908 -127.371229) (xy 46.389254 -127.352034) (xy 46.301085 -127.323523) (xy 46.25848 -127.305308)
			(xy 46.24854 -127.301488) (xy 46.227272 -127.301488) (xy 46.217332 -127.305308) (xy 46.174728 -127.323528)
			(xy 46.086561 -127.352046) (xy 45.995906 -127.371239) (xy 45.903746 -127.3809) (xy 45.857414 -127.381508)
			(xy 45.856906 -127.381508) (xy 45.814557 -127.38102) (xy 45.730241 -127.37297) (xy 45.647073 -127.356941)
			(xy 45.565805 -127.333079) (xy 45.487173 -127.3016) (xy 45.411889 -127.262789) (xy 45.340636 -127.216998)
			(xy 45.274058 -127.16464) (xy 45.212758 -127.106192) (xy 45.157292 -127.042181) (xy 45.108162 -126.973187)
			(xy 45.065812 -126.899836) (xy 45.030627 -126.822791) (xy 45.002925 -126.742751) (xy 44.982956 -126.66044)
			(xy 44.970902 -126.576603) (xy 44.966872 -126.492) (xy 37.531802 -126.492) (xy 37.531802 -131.572)
			(xy 44.966872 -131.572) (xy 44.970902 -131.487397) (xy 44.982956 -131.40356) (xy 45.002925 -131.321249)
			(xy 45.030627 -131.241209) (xy 45.065812 -131.164164) (xy 45.108162 -131.090813) (xy 45.157292 -131.021819)
			(xy 45.212758 -130.957808) (xy 45.274058 -130.89936) (xy 45.340636 -130.847002) (xy 45.411889 -130.801211)
			(xy 45.487173 -130.7624) (xy 45.565805 -130.730921) (xy 45.647073 -130.707059) (xy 45.730241 -130.69103)
			(xy 45.814557 -130.68298) (xy 45.856906 -130.682492) (xy 45.857414 -130.682492) (xy 45.903746 -130.683096)
			(xy 45.995904 -130.692768) (xy 46.086558 -130.711964) (xy 46.174727 -130.740477) (xy 46.217332 -130.758692)
			(xy 46.227272 -130.762512) (xy 46.24854 -130.762512) (xy 46.25848 -130.758692) (xy 46.301082 -130.740468)
			(xy 46.38925 -130.711951) (xy 46.479906 -130.692759) (xy 46.572066 -130.6831) (xy 46.618398 -130.682492)
			(xy 46.618906 -130.682492) (xy 46.661254 -130.682996) (xy 46.745567 -130.691047) (xy 46.828733 -130.707077)
			(xy 46.909999 -130.730939) (xy 46.988629 -130.762418) (xy 47.06391 -130.801229) (xy 47.135161 -130.847019)
			(xy 47.201737 -130.899376) (xy 47.263034 -130.957823) (xy 47.318499 -131.021833) (xy 47.367627 -131.090825)
			(xy 47.409975 -131.164174) (xy 47.44516 -131.241217) (xy 47.472861 -131.321256) (xy 47.492829 -131.403565)
			(xy 47.504882 -131.487399) (xy 47.508913 -131.572) (xy 57.158872 -131.572) (xy 57.162902 -131.487397)
			(xy 57.174956 -131.40356) (xy 57.194925 -131.321249) (xy 57.222627 -131.241209) (xy 57.257812 -131.164164)
			(xy 57.300162 -131.090813) (xy 57.349292 -131.021819) (xy 57.404758 -130.957808) (xy 57.466058 -130.89936)
			(xy 57.532636 -130.847002) (xy 57.603889 -130.801211) (xy 57.679173 -130.7624) (xy 57.757805 -130.730921)
			(xy 57.839073 -130.707059) (xy 57.922241 -130.69103) (xy 58.006557 -130.68298) (xy 58.048906 -130.682492)
			(xy 58.049414 -130.682492) (xy 58.095746 -130.683096) (xy 58.187904 -130.692768) (xy 58.278558 -130.711964)
			(xy 58.366727 -130.740477) (xy 58.409332 -130.758692) (xy 58.419272 -130.762512) (xy 58.44054 -130.762512)
			(xy 58.45048 -130.758692) (xy 58.493082 -130.740468) (xy 58.58125 -130.711951) (xy 58.671906 -130.692759)
			(xy 58.764066 -130.6831) (xy 58.810398 -130.682492) (xy 58.810906 -130.682492) (xy 58.853254 -130.682996)
			(xy 58.937567 -130.691047) (xy 59.020733 -130.707077) (xy 59.101999 -130.730939) (xy 59.180629 -130.762418)
			(xy 59.25591 -130.801229) (xy 59.327161 -130.847019) (xy 59.393737 -130.899376) (xy 59.455034 -130.957823)
			(xy 59.510499 -131.021833) (xy 59.559627 -131.090825) (xy 59.601975 -131.164174) (xy 59.63716 -131.241217)
			(xy 59.664861 -131.321256) (xy 59.684829 -131.403565) (xy 59.696882 -131.487399) (xy 59.700913 -131.572)
			(xy 69.350872 -131.572) (xy 69.354902 -131.487397) (xy 69.366956 -131.40356) (xy 69.386925 -131.321249)
			(xy 69.414627 -131.241209) (xy 69.449812 -131.164164) (xy 69.492162 -131.090813) (xy 69.541292 -131.021819)
			(xy 69.596758 -130.957808) (xy 69.658058 -130.89936) (xy 69.724636 -130.847002) (xy 69.795889 -130.801211)
			(xy 69.871173 -130.7624) (xy 69.949805 -130.730921) (xy 70.031073 -130.707059) (xy 70.114241 -130.69103)
			(xy 70.198557 -130.68298) (xy 70.240906 -130.682492) (xy 70.241414 -130.682492) (xy 70.287746 -130.683096)
			(xy 70.379904 -130.692768) (xy 70.470558 -130.711964) (xy 70.558727 -130.740477) (xy 70.601332 -130.758692)
			(xy 70.611272 -130.762512) (xy 70.63254 -130.762512) (xy 70.64248 -130.758692) (xy 70.685082 -130.740468)
			(xy 70.77325 -130.711951) (xy 70.863906 -130.692759) (xy 70.956066 -130.6831) (xy 71.002398 -130.682492)
			(xy 71.002906 -130.682492) (xy 71.045254 -130.682996) (xy 71.129567 -130.691047) (xy 71.212733 -130.707077)
			(xy 71.293999 -130.730939) (xy 71.372629 -130.762418) (xy 71.44791 -130.801229) (xy 71.519161 -130.847019)
			(xy 71.585737 -130.899376) (xy 71.647034 -130.957823) (xy 71.702499 -131.021833) (xy 71.751627 -131.090825)
			(xy 71.793975 -131.164174) (xy 71.82916 -131.241217) (xy 71.856861 -131.321256) (xy 71.876829 -131.403565)
			(xy 71.888882 -131.487399) (xy 71.892913 -131.572) (xy 84.966772 -131.572) (xy 84.970802 -131.487396)
			(xy 84.982857 -131.403558) (xy 85.002826 -131.321246) (xy 85.030529 -131.241204) (xy 85.065715 -131.164159)
			(xy 85.108066 -131.090807) (xy 85.157198 -131.021813) (xy 85.212665 -130.957801) (xy 85.273966 -130.899352)
			(xy 85.340546 -130.846995) (xy 85.411801 -130.801204) (xy 85.487086 -130.762394) (xy 85.56572 -130.730916)
			(xy 85.646989 -130.707055) (xy 85.730159 -130.691028) (xy 85.814476 -130.682979) (xy 85.856826 -130.682492)
			(xy 85.857334 -130.682492) (xy 85.903665 -130.683124) (xy 85.995822 -130.692788) (xy 86.086476 -130.711976)
			(xy 86.174646 -130.74048) (xy 86.217252 -130.758692) (xy 86.227192 -130.762512) (xy 86.24846 -130.762512)
			(xy 86.2584 -130.758692) (xy 86.300999 -130.740461) (xy 86.389168 -130.711946) (xy 86.479825 -130.692756)
			(xy 86.571985 -130.683099) (xy 86.618318 -130.682492) (xy 86.618826 -130.682492) (xy 86.661174 -130.682997)
			(xy 86.745485 -130.69105) (xy 86.82865 -130.707081) (xy 86.909914 -130.730944) (xy 86.988542 -130.762424)
			(xy 87.063821 -130.801235) (xy 87.135071 -130.847026) (xy 87.201645 -130.899383) (xy 87.262941 -130.95783)
			(xy 87.318404 -131.021839) (xy 87.367531 -131.090831) (xy 87.409878 -131.16418) (xy 87.445061 -131.241222)
			(xy 87.472762 -131.321259) (xy 87.492729 -131.403567) (xy 87.504783 -131.487401) (xy 87.508813 -131.572)
			(xy 97.158772 -131.572) (xy 97.162802 -131.487396) (xy 97.174857 -131.403558) (xy 97.194826 -131.321246)
			(xy 97.222529 -131.241204) (xy 97.257715 -131.164159) (xy 97.300066 -131.090807) (xy 97.349198 -131.021813)
			(xy 97.404665 -130.957801) (xy 97.465966 -130.899352) (xy 97.532546 -130.846995) (xy 97.603801 -130.801204)
			(xy 97.679086 -130.762394) (xy 97.75772 -130.730916) (xy 97.838989 -130.707055) (xy 97.922159 -130.691028)
			(xy 98.006476 -130.682979) (xy 98.048826 -130.682492) (xy 98.049334 -130.682492) (xy 98.095665 -130.683124)
			(xy 98.187822 -130.692788) (xy 98.278476 -130.711976) (xy 98.366646 -130.74048) (xy 98.409252 -130.758692)
			(xy 98.419192 -130.762512) (xy 98.44046 -130.762512) (xy 98.4504 -130.758692) (xy 98.492999 -130.740461)
			(xy 98.581168 -130.711946) (xy 98.671825 -130.692756) (xy 98.763985 -130.683099) (xy 98.810318 -130.682492)
			(xy 98.810826 -130.682492) (xy 98.853174 -130.682997) (xy 98.937485 -130.69105) (xy 99.02065 -130.707081)
			(xy 99.101914 -130.730944) (xy 99.180542 -130.762424) (xy 99.255821 -130.801235) (xy 99.327071 -130.847026)
			(xy 99.393645 -130.899383) (xy 99.454941 -130.95783) (xy 99.510404 -131.021839) (xy 99.559531 -131.090831)
			(xy 99.601878 -131.16418) (xy 99.637061 -131.241222) (xy 99.664762 -131.321259) (xy 99.684729 -131.403567)
			(xy 99.696783 -131.487401) (xy 99.700813 -131.572) (xy 109.350772 -131.572) (xy 109.354802 -131.487396)
			(xy 109.366857 -131.403558) (xy 109.386826 -131.321246) (xy 109.414529 -131.241204) (xy 109.449715 -131.164159)
			(xy 109.492066 -131.090807) (xy 109.541198 -131.021813) (xy 109.596665 -130.957801) (xy 109.657966 -130.899352)
			(xy 109.724546 -130.846995) (xy 109.795801 -130.801204) (xy 109.871086 -130.762394) (xy 109.94972 -130.730916)
			(xy 110.030989 -130.707055) (xy 110.114159 -130.691028) (xy 110.198476 -130.682979) (xy 110.240826 -130.682492)
			(xy 110.241334 -130.682492) (xy 110.287665 -130.683124) (xy 110.379822 -130.692788) (xy 110.470476 -130.711976)
			(xy 110.558646 -130.74048) (xy 110.601252 -130.758692) (xy 110.611192 -130.762512) (xy 110.63246 -130.762512)
			(xy 110.6424 -130.758692) (xy 110.684999 -130.740461) (xy 110.773168 -130.711946) (xy 110.863825 -130.692756)
			(xy 110.955985 -130.683099) (xy 111.002318 -130.682492) (xy 111.002826 -130.682492) (xy 111.045174 -130.682997)
			(xy 111.129485 -130.69105) (xy 111.21265 -130.707081) (xy 111.293914 -130.730944) (xy 111.372542 -130.762424)
			(xy 111.447821 -130.801235) (xy 111.519071 -130.847026) (xy 111.585645 -130.899383) (xy 111.646941 -130.95783)
			(xy 111.702404 -131.021839) (xy 111.751531 -131.090831) (xy 111.793878 -131.16418) (xy 111.829061 -131.241222)
			(xy 111.856762 -131.321259) (xy 111.876729 -131.403567) (xy 111.888783 -131.487401) (xy 111.892813 -131.572)
			(xy 124.966988 -131.572) (xy 124.971018 -131.487399) (xy 124.983071 -131.403564) (xy 125.003039 -131.321255)
			(xy 125.030741 -131.241216) (xy 125.065925 -131.164173) (xy 125.108274 -131.090823) (xy 125.157403 -131.021831)
			(xy 125.212868 -130.957821) (xy 125.274166 -130.899373) (xy 125.340742 -130.847017) (xy 125.411994 -130.801227)
			(xy 125.487275 -130.762416) (xy 125.565905 -130.730937) (xy 125.647172 -130.707076) (xy 125.730338 -130.691047)
			(xy 125.814652 -130.682996) (xy 125.857 -130.682492) (xy 125.857508 -130.682492) (xy 125.90384 -130.683098)
			(xy 125.995998 -130.692769) (xy 126.086652 -130.711965) (xy 126.174821 -130.740477) (xy 126.217426 -130.758692)
			(xy 126.227366 -130.762512) (xy 126.248634 -130.762512) (xy 126.258574 -130.758692) (xy 126.301177 -130.74047)
			(xy 126.389344 -130.711952) (xy 126.48 -130.69276) (xy 126.57216 -130.6831) (xy 126.618492 -130.682492)
			(xy 126.619 -130.682492) (xy 126.661348 -130.682996) (xy 126.745662 -130.691047) (xy 126.828828 -130.707076)
			(xy 126.910095 -130.730937) (xy 126.988725 -130.762416) (xy 127.064006 -130.801227) (xy 127.135258 -130.847017)
			(xy 127.201834 -130.899373) (xy 127.263132 -130.957821) (xy 127.318597 -131.021831) (xy 127.367726 -131.090823)
			(xy 127.410075 -131.164173) (xy 127.445259 -131.241216) (xy 127.472961 -131.321255) (xy 127.492929 -131.403564)
			(xy 127.504982 -131.487399) (xy 127.509013 -131.572) (xy 137.158988 -131.572) (xy 137.163018 -131.487399)
			(xy 137.175071 -131.403564) (xy 137.195039 -131.321255) (xy 137.222741 -131.241216) (xy 137.257925 -131.164173)
			(xy 137.300274 -131.090823) (xy 137.349403 -131.021831) (xy 137.404868 -130.957821) (xy 137.466166 -130.899373)
			(xy 137.532742 -130.847017) (xy 137.603994 -130.801227) (xy 137.679275 -130.762416) (xy 137.757905 -130.730937)
			(xy 137.839172 -130.707076) (xy 137.922338 -130.691047) (xy 138.006652 -130.682996) (xy 138.049 -130.682492)
			(xy 138.049508 -130.682492) (xy 138.09584 -130.683098) (xy 138.187998 -130.692769) (xy 138.278652 -130.711965)
			(xy 138.366821 -130.740477) (xy 138.409426 -130.758692) (xy 138.419366 -130.762512) (xy 138.440634 -130.762512)
			(xy 138.450574 -130.758692) (xy 138.493177 -130.74047) (xy 138.581344 -130.711952) (xy 138.672 -130.69276)
			(xy 138.76416 -130.6831) (xy 138.810492 -130.682492) (xy 138.811 -130.682492) (xy 138.853348 -130.682996)
			(xy 138.937662 -130.691047) (xy 139.020828 -130.707076) (xy 139.102095 -130.730937) (xy 139.180725 -130.762416)
			(xy 139.256006 -130.801227) (xy 139.327258 -130.847017) (xy 139.393834 -130.899373) (xy 139.455132 -130.957821)
			(xy 139.510597 -131.021831) (xy 139.559726 -131.090823) (xy 139.602075 -131.164173) (xy 139.637259 -131.241216)
			(xy 139.664961 -131.321255) (xy 139.684929 -131.403564) (xy 139.696982 -131.487399) (xy 139.701013 -131.572)
			(xy 149.350988 -131.572) (xy 149.355018 -131.487399) (xy 149.367071 -131.403564) (xy 149.387039 -131.321255)
			(xy 149.414741 -131.241216) (xy 149.449925 -131.164173) (xy 149.492274 -131.090823) (xy 149.541403 -131.021831)
			(xy 149.596868 -130.957821) (xy 149.658166 -130.899373) (xy 149.724742 -130.847017) (xy 149.795994 -130.801227)
			(xy 149.871275 -130.762416) (xy 149.949905 -130.730937) (xy 150.031172 -130.707076) (xy 150.114338 -130.691047)
			(xy 150.198652 -130.682996) (xy 150.241 -130.682492) (xy 150.241508 -130.682492) (xy 150.28784 -130.683098)
			(xy 150.379998 -130.692769) (xy 150.470652 -130.711965) (xy 150.558821 -130.740477) (xy 150.601426 -130.758692)
			(xy 150.611366 -130.762512) (xy 150.632634 -130.762512) (xy 150.642574 -130.758692) (xy 150.685177 -130.74047)
			(xy 150.773344 -130.711952) (xy 150.864 -130.69276) (xy 150.95616 -130.6831) (xy 151.002492 -130.682492)
			(xy 151.003 -130.682492) (xy 151.045348 -130.682996) (xy 151.129662 -130.691047) (xy 151.212828 -130.707076)
			(xy 151.294095 -130.730937) (xy 151.372725 -130.762416) (xy 151.448006 -130.801227) (xy 151.519258 -130.847017)
			(xy 151.585834 -130.899373) (xy 151.647132 -130.957821) (xy 151.702597 -131.021831) (xy 151.751726 -131.090823)
			(xy 151.794075 -131.164173) (xy 151.829259 -131.241216) (xy 151.856961 -131.321255) (xy 151.876929 -131.403564)
			(xy 151.888982 -131.487399) (xy 151.893013 -131.572) (xy 164.967187 -131.572) (xy 164.971217 -131.487401)
			(xy 164.983271 -131.403567) (xy 165.003238 -131.321259) (xy 165.030939 -131.241222) (xy 165.066122 -131.16418)
			(xy 165.108469 -131.090831) (xy 165.157596 -131.021839) (xy 165.213059 -130.95783) (xy 165.274355 -130.899383)
			(xy 165.340929 -130.847026) (xy 165.412179 -130.801235) (xy 165.487458 -130.762424) (xy 165.566086 -130.730944)
			(xy 165.64735 -130.707081) (xy 165.730515 -130.69105) (xy 165.814826 -130.682997) (xy 165.857174 -130.682492)
			(xy 165.857682 -130.682492) (xy 165.904014 -130.683107) (xy 165.996171 -130.692776) (xy 166.086825 -130.711969)
			(xy 166.174994 -130.740478) (xy 166.2176 -130.758692) (xy 166.22754 -130.762512) (xy 166.248808 -130.762512)
			(xy 166.258748 -130.758692) (xy 166.301354 -130.740479) (xy 166.389521 -130.711959) (xy 166.480175 -130.692764)
			(xy 166.572334 -130.683101) (xy 166.618666 -130.682492) (xy 166.619174 -130.682492) (xy 166.661524 -130.682979)
			(xy 166.745841 -130.691028) (xy 166.829011 -130.707055) (xy 166.91028 -130.730916) (xy 166.988914 -130.762394)
			(xy 167.064199 -130.801204) (xy 167.135454 -130.846995) (xy 167.202034 -130.899352) (xy 167.263335 -130.957801)
			(xy 167.318802 -131.021813) (xy 167.367934 -131.090807) (xy 167.410285 -131.164159) (xy 167.445471 -131.241204)
			(xy 167.473174 -131.321246) (xy 167.493143 -131.403558) (xy 167.505198 -131.487396) (xy 167.509228 -131.572)
			(xy 177.159187 -131.572) (xy 177.163217 -131.487401) (xy 177.175271 -131.403567) (xy 177.195238 -131.321259)
			(xy 177.222939 -131.241222) (xy 177.258122 -131.16418) (xy 177.300469 -131.090831) (xy 177.349596 -131.021839)
			(xy 177.405059 -130.95783) (xy 177.466355 -130.899383) (xy 177.532929 -130.847026) (xy 177.604179 -130.801235)
			(xy 177.679458 -130.762424) (xy 177.758086 -130.730944) (xy 177.83935 -130.707081) (xy 177.922515 -130.69105)
			(xy 178.006826 -130.682997) (xy 178.049174 -130.682492) (xy 178.049682 -130.682492) (xy 178.096014 -130.683107)
			(xy 178.188171 -130.692776) (xy 178.278825 -130.711969) (xy 178.366994 -130.740478) (xy 178.4096 -130.758692)
			(xy 178.41954 -130.762512) (xy 178.440808 -130.762512) (xy 178.450748 -130.758692) (xy 178.493354 -130.740479)
			(xy 178.581521 -130.711959) (xy 178.672175 -130.692764) (xy 178.764334 -130.683101) (xy 178.810666 -130.682492)
			(xy 178.811174 -130.682492) (xy 178.853524 -130.682979) (xy 178.937841 -130.691028) (xy 179.021011 -130.707055)
			(xy 179.10228 -130.730916) (xy 179.180914 -130.762394) (xy 179.256199 -130.801204) (xy 179.327454 -130.846995)
			(xy 179.394034 -130.899352) (xy 179.455335 -130.957801) (xy 179.510802 -131.021813) (xy 179.559934 -131.090807)
			(xy 179.602285 -131.164159) (xy 179.637471 -131.241204) (xy 179.665174 -131.321246) (xy 179.685143 -131.403558)
			(xy 179.697198 -131.487396) (xy 179.701228 -131.572) (xy 189.351187 -131.572) (xy 189.355217 -131.487401)
			(xy 189.367271 -131.403567) (xy 189.387238 -131.321259) (xy 189.414939 -131.241222) (xy 189.450122 -131.16418)
			(xy 189.492469 -131.090831) (xy 189.541596 -131.021839) (xy 189.597059 -130.95783) (xy 189.658355 -130.899383)
			(xy 189.724929 -130.847026) (xy 189.796179 -130.801235) (xy 189.871458 -130.762424) (xy 189.950086 -130.730944)
			(xy 190.03135 -130.707081) (xy 190.114515 -130.69105) (xy 190.198826 -130.682997) (xy 190.241174 -130.682492)
			(xy 190.241682 -130.682492) (xy 190.288014 -130.683107) (xy 190.380171 -130.692776) (xy 190.470825 -130.711969)
			(xy 190.558994 -130.740478) (xy 190.6016 -130.758692) (xy 190.61154 -130.762512) (xy 190.632808 -130.762512)
			(xy 190.642748 -130.758692) (xy 190.685354 -130.740479) (xy 190.773521 -130.711959) (xy 190.864175 -130.692764)
			(xy 190.956334 -130.683101) (xy 191.002666 -130.682492) (xy 191.003174 -130.682492) (xy 191.045524 -130.682979)
			(xy 191.129841 -130.691028) (xy 191.213011 -130.707055) (xy 191.29428 -130.730916) (xy 191.372914 -130.762394)
			(xy 191.448199 -130.801204) (xy 191.519454 -130.846995) (xy 191.586034 -130.899352) (xy 191.647335 -130.957801)
			(xy 191.702802 -131.021813) (xy 191.751934 -131.090807) (xy 191.794285 -131.164159) (xy 191.829471 -131.241204)
			(xy 191.857174 -131.321246) (xy 191.877143 -131.403558) (xy 191.889198 -131.487396) (xy 191.893228 -131.572)
			(xy 191.889198 -131.656604) (xy 191.877143 -131.740442) (xy 191.857174 -131.822754) (xy 191.829471 -131.902796)
			(xy 191.794285 -131.979841) (xy 191.751934 -132.053193) (xy 191.702802 -132.122187) (xy 191.647335 -132.186199)
			(xy 191.586034 -132.244648) (xy 191.519454 -132.297005) (xy 191.448199 -132.342796) (xy 191.372914 -132.381606)
			(xy 191.29428 -132.413084) (xy 191.213011 -132.436945) (xy 191.129841 -132.452972) (xy 191.045524 -132.461021)
			(xy 191.003174 -132.461508) (xy 191.002666 -132.461508) (xy 190.956335 -132.460876) (xy 190.864178 -132.451212)
			(xy 190.773524 -132.432024) (xy 190.685354 -132.40352) (xy 190.642748 -132.385308) (xy 190.632808 -132.381488)
			(xy 190.61154 -132.381488) (xy 190.6016 -132.385308) (xy 190.559001 -132.403539) (xy 190.470832 -132.432054)
			(xy 190.380175 -132.451244) (xy 190.288015 -132.460901) (xy 190.241682 -132.461508) (xy 190.241174 -132.461508)
			(xy 190.198826 -132.461003) (xy 190.114515 -132.45295) (xy 190.03135 -132.436919) (xy 189.950086 -132.413056)
			(xy 189.871458 -132.381576) (xy 189.796179 -132.342765) (xy 189.724929 -132.296974) (xy 189.658355 -132.244617)
			(xy 189.597059 -132.18617) (xy 189.541596 -132.122161) (xy 189.492469 -132.053169) (xy 189.450122 -131.97982)
			(xy 189.414939 -131.902778) (xy 189.387238 -131.822741) (xy 189.367271 -131.740433) (xy 189.355217 -131.656599)
			(xy 189.351187 -131.572) (xy 179.701228 -131.572) (xy 179.697198 -131.656604) (xy 179.685143 -131.740442)
			(xy 179.665174 -131.822754) (xy 179.637471 -131.902796) (xy 179.602285 -131.979841) (xy 179.559934 -132.053193)
			(xy 179.510802 -132.122187) (xy 179.455335 -132.186199) (xy 179.394034 -132.244648) (xy 179.327454 -132.297005)
			(xy 179.256199 -132.342796) (xy 179.180914 -132.381606) (xy 179.10228 -132.413084) (xy 179.021011 -132.436945)
			(xy 178.937841 -132.452972) (xy 178.853524 -132.461021) (xy 178.811174 -132.461508) (xy 178.810666 -132.461508)
			(xy 178.764335 -132.460876) (xy 178.672178 -132.451212) (xy 178.581524 -132.432024) (xy 178.493354 -132.40352)
			(xy 178.450748 -132.385308) (xy 178.440808 -132.381488) (xy 178.41954 -132.381488) (xy 178.4096 -132.385308)
			(xy 178.367001 -132.403539) (xy 178.278832 -132.432054) (xy 178.188175 -132.451244) (xy 178.096015 -132.460901)
			(xy 178.049682 -132.461508) (xy 178.049174 -132.461508) (xy 178.006826 -132.461003) (xy 177.922515 -132.45295)
			(xy 177.83935 -132.436919) (xy 177.758086 -132.413056) (xy 177.679458 -132.381576) (xy 177.604179 -132.342765)
			(xy 177.532929 -132.296974) (xy 177.466355 -132.244617) (xy 177.405059 -132.18617) (xy 177.349596 -132.122161)
			(xy 177.300469 -132.053169) (xy 177.258122 -131.97982) (xy 177.222939 -131.902778) (xy 177.195238 -131.822741)
			(xy 177.175271 -131.740433) (xy 177.163217 -131.656599) (xy 177.159187 -131.572) (xy 167.509228 -131.572)
			(xy 167.505198 -131.656604) (xy 167.493143 -131.740442) (xy 167.473174 -131.822754) (xy 167.445471 -131.902796)
			(xy 167.410285 -131.979841) (xy 167.367934 -132.053193) (xy 167.318802 -132.122187) (xy 167.263335 -132.186199)
			(xy 167.202034 -132.244648) (xy 167.135454 -132.297005) (xy 167.064199 -132.342796) (xy 166.988914 -132.381606)
			(xy 166.91028 -132.413084) (xy 166.829011 -132.436945) (xy 166.745841 -132.452972) (xy 166.661524 -132.461021)
			(xy 166.619174 -132.461508) (xy 166.618666 -132.461508) (xy 166.572335 -132.460876) (xy 166.480178 -132.451212)
			(xy 166.389524 -132.432024) (xy 166.301354 -132.40352) (xy 166.258748 -132.385308) (xy 166.248808 -132.381488)
			(xy 166.22754 -132.381488) (xy 166.2176 -132.385308) (xy 166.175001 -132.403539) (xy 166.086832 -132.432054)
			(xy 165.996175 -132.451244) (xy 165.904015 -132.460901) (xy 165.857682 -132.461508) (xy 165.857174 -132.461508)
			(xy 165.814826 -132.461003) (xy 165.730515 -132.45295) (xy 165.64735 -132.436919) (xy 165.566086 -132.413056)
			(xy 165.487458 -132.381576) (xy 165.412179 -132.342765) (xy 165.340929 -132.296974) (xy 165.274355 -132.244617)
			(xy 165.213059 -132.18617) (xy 165.157596 -132.122161) (xy 165.108469 -132.053169) (xy 165.066122 -131.97982)
			(xy 165.030939 -131.902778) (xy 165.003238 -131.822741) (xy 164.983271 -131.740433) (xy 164.971217 -131.656599)
			(xy 164.967187 -131.572) (xy 151.893013 -131.572) (xy 151.888982 -131.656601) (xy 151.876929 -131.740436)
			(xy 151.856961 -131.822745) (xy 151.829259 -131.902784) (xy 151.794075 -131.979827) (xy 151.751726 -132.053177)
			(xy 151.702597 -132.122169) (xy 151.647132 -132.186179) (xy 151.585834 -132.244627) (xy 151.519258 -132.296983)
			(xy 151.448006 -132.342773) (xy 151.372725 -132.381584) (xy 151.294095 -132.413063) (xy 151.212828 -132.436924)
			(xy 151.129662 -132.452953) (xy 151.045348 -132.461004) (xy 151.003 -132.461508) (xy 151.002492 -132.461508)
			(xy 150.95616 -132.460902) (xy 150.864002 -132.451231) (xy 150.773348 -132.432035) (xy 150.685179 -132.403523)
			(xy 150.642574 -132.385308) (xy 150.632634 -132.381488) (xy 150.611366 -132.381488) (xy 150.601426 -132.385308)
			(xy 150.558823 -132.40353) (xy 150.470656 -132.432048) (xy 150.38 -132.45124) (xy 150.28784 -132.4609)
			(xy 150.241508 -132.461508) (xy 150.241 -132.461508) (xy 150.198652 -132.461004) (xy 150.114338 -132.452953)
			(xy 150.031172 -132.436924) (xy 149.949905 -132.413063) (xy 149.871275 -132.381584) (xy 149.795994 -132.342773)
			(xy 149.724742 -132.296983) (xy 149.658166 -132.244627) (xy 149.596868 -132.186179) (xy 149.541403 -132.122169)
			(xy 149.492274 -132.053177) (xy 149.449925 -131.979827) (xy 149.414741 -131.902784) (xy 149.387039 -131.822745)
			(xy 149.367071 -131.740436) (xy 149.355018 -131.656601) (xy 149.350988 -131.572) (xy 139.701013 -131.572)
			(xy 139.696982 -131.656601) (xy 139.684929 -131.740436) (xy 139.664961 -131.822745) (xy 139.637259 -131.902784)
			(xy 139.602075 -131.979827) (xy 139.559726 -132.053177) (xy 139.510597 -132.122169) (xy 139.455132 -132.186179)
			(xy 139.393834 -132.244627) (xy 139.327258 -132.296983) (xy 139.256006 -132.342773) (xy 139.180725 -132.381584)
			(xy 139.102095 -132.413063) (xy 139.020828 -132.436924) (xy 138.937662 -132.452953) (xy 138.853348 -132.461004)
			(xy 138.811 -132.461508) (xy 138.810492 -132.461508) (xy 138.76416 -132.460902) (xy 138.672002 -132.451231)
			(xy 138.581348 -132.432035) (xy 138.493179 -132.403523) (xy 138.450574 -132.385308) (xy 138.440634 -132.381488)
			(xy 138.419366 -132.381488) (xy 138.409426 -132.385308) (xy 138.366823 -132.40353) (xy 138.278656 -132.432048)
			(xy 138.188 -132.45124) (xy 138.09584 -132.4609) (xy 138.049508 -132.461508) (xy 138.049 -132.461508)
			(xy 138.006652 -132.461004) (xy 137.922338 -132.452953) (xy 137.839172 -132.436924) (xy 137.757905 -132.413063)
			(xy 137.679275 -132.381584) (xy 137.603994 -132.342773) (xy 137.532742 -132.296983) (xy 137.466166 -132.244627)
			(xy 137.404868 -132.186179) (xy 137.349403 -132.122169) (xy 137.300274 -132.053177) (xy 137.257925 -131.979827)
			(xy 137.222741 -131.902784) (xy 137.195039 -131.822745) (xy 137.175071 -131.740436) (xy 137.163018 -131.656601)
			(xy 137.158988 -131.572) (xy 127.509013 -131.572) (xy 127.504982 -131.656601) (xy 127.492929 -131.740436)
			(xy 127.472961 -131.822745) (xy 127.445259 -131.902784) (xy 127.410075 -131.979827) (xy 127.367726 -132.053177)
			(xy 127.318597 -132.122169) (xy 127.263132 -132.186179) (xy 127.201834 -132.244627) (xy 127.135258 -132.296983)
			(xy 127.064006 -132.342773) (xy 126.988725 -132.381584) (xy 126.910095 -132.413063) (xy 126.828828 -132.436924)
			(xy 126.745662 -132.452953) (xy 126.661348 -132.461004) (xy 126.619 -132.461508) (xy 126.618492 -132.461508)
			(xy 126.57216 -132.460902) (xy 126.480002 -132.451231) (xy 126.389348 -132.432035) (xy 126.301179 -132.403523)
			(xy 126.258574 -132.385308) (xy 126.248634 -132.381488) (xy 126.227366 -132.381488) (xy 126.217426 -132.385308)
			(xy 126.174823 -132.40353) (xy 126.086656 -132.432048) (xy 125.996 -132.45124) (xy 125.90384 -132.4609)
			(xy 125.857508 -132.461508) (xy 125.857 -132.461508) (xy 125.814652 -132.461004) (xy 125.730338 -132.452953)
			(xy 125.647172 -132.436924) (xy 125.565905 -132.413063) (xy 125.487275 -132.381584) (xy 125.411994 -132.342773)
			(xy 125.340742 -132.296983) (xy 125.274166 -132.244627) (xy 125.212868 -132.186179) (xy 125.157403 -132.122169)
			(xy 125.108274 -132.053177) (xy 125.065925 -131.979827) (xy 125.030741 -131.902784) (xy 125.003039 -131.822745)
			(xy 124.983071 -131.740436) (xy 124.971018 -131.656601) (xy 124.966988 -131.572) (xy 111.892813 -131.572)
			(xy 111.888783 -131.656599) (xy 111.876729 -131.740433) (xy 111.856762 -131.822741) (xy 111.829061 -131.902778)
			(xy 111.793878 -131.97982) (xy 111.751531 -132.053169) (xy 111.702404 -132.122161) (xy 111.646941 -132.18617)
			(xy 111.585645 -132.244617) (xy 111.519071 -132.296974) (xy 111.447821 -132.342765) (xy 111.372542 -132.381576)
			(xy 111.293914 -132.413056) (xy 111.21265 -132.436919) (xy 111.129485 -132.45295) (xy 111.045174 -132.461003)
			(xy 111.002826 -132.461508) (xy 111.002318 -132.461508) (xy 110.955986 -132.460893) (xy 110.863829 -132.451224)
			(xy 110.773175 -132.432031) (xy 110.685006 -132.403522) (xy 110.6424 -132.385308) (xy 110.63246 -132.381488)
			(xy 110.611192 -132.381488) (xy 110.601252 -132.385308) (xy 110.558646 -132.403521) (xy 110.470479 -132.432041)
			(xy 110.379825 -132.451236) (xy 110.287666 -132.460899) (xy 110.241334 -132.461508) (xy 110.240826 -132.461508)
			(xy 110.198476 -132.461021) (xy 110.114159 -132.452972) (xy 110.030989 -132.436945) (xy 109.94972 -132.413084)
			(xy 109.871086 -132.381606) (xy 109.795801 -132.342796) (xy 109.724546 -132.297005) (xy 109.657966 -132.244648)
			(xy 109.596665 -132.186199) (xy 109.541198 -132.122187) (xy 109.492066 -132.053193) (xy 109.449715 -131.979841)
			(xy 109.414529 -131.902796) (xy 109.386826 -131.822754) (xy 109.366857 -131.740442) (xy 109.354802 -131.656604)
			(xy 109.350772 -131.572) (xy 99.700813 -131.572) (xy 99.696783 -131.656599) (xy 99.684729 -131.740433)
			(xy 99.664762 -131.822741) (xy 99.637061 -131.902778) (xy 99.601878 -131.97982) (xy 99.559531 -132.053169)
			(xy 99.510404 -132.122161) (xy 99.454941 -132.18617) (xy 99.393645 -132.244617) (xy 99.327071 -132.296974)
			(xy 99.255821 -132.342765) (xy 99.180542 -132.381576) (xy 99.101914 -132.413056) (xy 99.02065 -132.436919)
			(xy 98.937485 -132.45295) (xy 98.853174 -132.461003) (xy 98.810826 -132.461508) (xy 98.810318 -132.461508)
			(xy 98.763986 -132.460893) (xy 98.671829 -132.451224) (xy 98.581175 -132.432031) (xy 98.493006 -132.403522)
			(xy 98.4504 -132.385308) (xy 98.44046 -132.381488) (xy 98.419192 -132.381488) (xy 98.409252 -132.385308)
			(xy 98.366646 -132.403521) (xy 98.278479 -132.432041) (xy 98.187825 -132.451236) (xy 98.095666 -132.460899)
			(xy 98.049334 -132.461508) (xy 98.048826 -132.461508) (xy 98.006476 -132.461021) (xy 97.922159 -132.452972)
			(xy 97.838989 -132.436945) (xy 97.75772 -132.413084) (xy 97.679086 -132.381606) (xy 97.603801 -132.342796)
			(xy 97.532546 -132.297005) (xy 97.465966 -132.244648) (xy 97.404665 -132.186199) (xy 97.349198 -132.122187)
			(xy 97.300066 -132.053193) (xy 97.257715 -131.979841) (xy 97.222529 -131.902796) (xy 97.194826 -131.822754)
			(xy 97.174857 -131.740442) (xy 97.162802 -131.656604) (xy 97.158772 -131.572) (xy 87.508813 -131.572)
			(xy 87.504783 -131.656599) (xy 87.492729 -131.740433) (xy 87.472762 -131.822741) (xy 87.445061 -131.902778)
			(xy 87.409878 -131.97982) (xy 87.367531 -132.053169) (xy 87.318404 -132.122161) (xy 87.262941 -132.18617)
			(xy 87.201645 -132.244617) (xy 87.135071 -132.296974) (xy 87.063821 -132.342765) (xy 86.988542 -132.381576)
			(xy 86.909914 -132.413056) (xy 86.82865 -132.436919) (xy 86.745485 -132.45295) (xy 86.661174 -132.461003)
			(xy 86.618826 -132.461508) (xy 86.618318 -132.461508) (xy 86.571986 -132.460893) (xy 86.479829 -132.451224)
			(xy 86.389175 -132.432031) (xy 86.301006 -132.403522) (xy 86.2584 -132.385308) (xy 86.24846 -132.381488)
			(xy 86.227192 -132.381488) (xy 86.217252 -132.385308) (xy 86.174646 -132.403521) (xy 86.086479 -132.432041)
			(xy 85.995825 -132.451236) (xy 85.903666 -132.460899) (xy 85.857334 -132.461508) (xy 85.856826 -132.461508)
			(xy 85.814476 -132.461021) (xy 85.730159 -132.452972) (xy 85.646989 -132.436945) (xy 85.56572 -132.413084)
			(xy 85.487086 -132.381606) (xy 85.411801 -132.342796) (xy 85.340546 -132.297005) (xy 85.273966 -132.244648)
			(xy 85.212665 -132.186199) (xy 85.157198 -132.122187) (xy 85.108066 -132.053193) (xy 85.065715 -131.979841)
			(xy 85.030529 -131.902796) (xy 85.002826 -131.822754) (xy 84.982857 -131.740442) (xy 84.970802 -131.656604)
			(xy 84.966772 -131.572) (xy 71.892913 -131.572) (xy 71.888882 -131.656601) (xy 71.876829 -131.740435)
			(xy 71.856861 -131.822744) (xy 71.82916 -131.902783) (xy 71.793975 -131.979826) (xy 71.751627 -132.053175)
			(xy 71.702499 -132.122167) (xy 71.647034 -132.186177) (xy 71.585737 -132.244624) (xy 71.519161 -132.296981)
			(xy 71.44791 -132.342771) (xy 71.372629 -132.381582) (xy 71.293999 -132.413061) (xy 71.212733 -132.436923)
			(xy 71.129567 -132.452953) (xy 71.045254 -132.461004) (xy 71.002906 -132.461508) (xy 71.002398 -132.461508)
			(xy 70.956066 -132.4609) (xy 70.863908 -132.451229) (xy 70.773254 -132.432034) (xy 70.685085 -132.403523)
			(xy 70.64248 -132.385308) (xy 70.63254 -132.381488) (xy 70.611272 -132.381488) (xy 70.601332 -132.385308)
			(xy 70.558728 -132.403528) (xy 70.470561 -132.432046) (xy 70.379906 -132.451239) (xy 70.287746 -132.4609)
			(xy 70.241414 -132.461508) (xy 70.240906 -132.461508) (xy 70.198557 -132.46102) (xy 70.114241 -132.45297)
			(xy 70.031073 -132.436941) (xy 69.949805 -132.413079) (xy 69.871173 -132.3816) (xy 69.795889 -132.342789)
			(xy 69.724636 -132.296998) (xy 69.658058 -132.24464) (xy 69.596758 -132.186192) (xy 69.541292 -132.122181)
			(xy 69.492162 -132.053187) (xy 69.449812 -131.979836) (xy 69.414627 -131.902791) (xy 69.386925 -131.822751)
			(xy 69.366956 -131.74044) (xy 69.354902 -131.656603) (xy 69.350872 -131.572) (xy 59.700913 -131.572)
			(xy 59.696882 -131.656601) (xy 59.684829 -131.740435) (xy 59.664861 -131.822744) (xy 59.63716 -131.902783)
			(xy 59.601975 -131.979826) (xy 59.559627 -132.053175) (xy 59.510499 -132.122167) (xy 59.455034 -132.186177)
			(xy 59.393737 -132.244624) (xy 59.327161 -132.296981) (xy 59.25591 -132.342771) (xy 59.180629 -132.381582)
			(xy 59.101999 -132.413061) (xy 59.020733 -132.436923) (xy 58.937567 -132.452953) (xy 58.853254 -132.461004)
			(xy 58.810906 -132.461508) (xy 58.810398 -132.461508) (xy 58.764066 -132.4609) (xy 58.671908 -132.451229)
			(xy 58.581254 -132.432034) (xy 58.493085 -132.403523) (xy 58.45048 -132.385308) (xy 58.44054 -132.381488)
			(xy 58.419272 -132.381488) (xy 58.409332 -132.385308) (xy 58.366728 -132.403528) (xy 58.278561 -132.432046)
			(xy 58.187906 -132.451239) (xy 58.095746 -132.4609) (xy 58.049414 -132.461508) (xy 58.048906 -132.461508)
			(xy 58.006557 -132.46102) (xy 57.922241 -132.45297) (xy 57.839073 -132.436941) (xy 57.757805 -132.413079)
			(xy 57.679173 -132.3816) (xy 57.603889 -132.342789) (xy 57.532636 -132.296998) (xy 57.466058 -132.24464)
			(xy 57.404758 -132.186192) (xy 57.349292 -132.122181) (xy 57.300162 -132.053187) (xy 57.257812 -131.979836)
			(xy 57.222627 -131.902791) (xy 57.194925 -131.822751) (xy 57.174956 -131.74044) (xy 57.162902 -131.656603)
			(xy 57.158872 -131.572) (xy 47.508913 -131.572) (xy 47.504882 -131.656601) (xy 47.492829 -131.740435)
			(xy 47.472861 -131.822744) (xy 47.44516 -131.902783) (xy 47.409975 -131.979826) (xy 47.367627 -132.053175)
			(xy 47.318499 -132.122167) (xy 47.263034 -132.186177) (xy 47.201737 -132.244624) (xy 47.135161 -132.296981)
			(xy 47.06391 -132.342771) (xy 46.988629 -132.381582) (xy 46.909999 -132.413061) (xy 46.828733 -132.436923)
			(xy 46.745567 -132.452953) (xy 46.661254 -132.461004) (xy 46.618906 -132.461508) (xy 46.618398 -132.461508)
			(xy 46.572066 -132.4609) (xy 46.479908 -132.451229) (xy 46.389254 -132.432034) (xy 46.301085 -132.403523)
			(xy 46.25848 -132.385308) (xy 46.24854 -132.381488) (xy 46.227272 -132.381488) (xy 46.217332 -132.385308)
			(xy 46.174728 -132.403528) (xy 46.086561 -132.432046) (xy 45.995906 -132.451239) (xy 45.903746 -132.4609)
			(xy 45.857414 -132.461508) (xy 45.856906 -132.461508) (xy 45.814557 -132.46102) (xy 45.730241 -132.45297)
			(xy 45.647073 -132.436941) (xy 45.565805 -132.413079) (xy 45.487173 -132.3816) (xy 45.411889 -132.342789)
			(xy 45.340636 -132.296998) (xy 45.274058 -132.24464) (xy 45.212758 -132.186192) (xy 45.157292 -132.122181)
			(xy 45.108162 -132.053187) (xy 45.065812 -131.979836) (xy 45.030627 -131.902791) (xy 45.002925 -131.822751)
			(xy 44.982956 -131.74044) (xy 44.970902 -131.656603) (xy 44.966872 -131.572) (xy 37.531802 -131.572)
			(xy 37.531802 -136.906) (xy 41.131495 -136.906) (xy 41.135517 -136.82028) (xy 41.147548 -136.735312)
			(xy 41.167484 -136.651845) (xy 41.195147 -136.570611) (xy 41.230296 -136.492325) (xy 41.272622 -136.417674)
			(xy 41.321751 -136.347315) (xy 41.377254 -136.281865) (xy 41.438641 -136.221901) (xy 41.505374 -136.167948)
			(xy 41.576866 -136.120481) (xy 41.652488 -136.079917) (xy 41.731577 -136.046613) (xy 41.813437 -136.020861)
			(xy 41.897348 -136.002888) (xy 41.982574 -135.992852) (xy 42.068366 -135.99084) (xy 42.153968 -135.996871)
			(xy 42.23863 -136.010891) (xy 42.321607 -136.032777) (xy 42.40217 -136.062338) (xy 42.47961 -136.099312)
			(xy 42.553249 -136.143376) (xy 42.622437 -136.194142) (xy 42.686568 -136.251163) (xy 42.745077 -136.313939)
			(xy 42.79745 -136.381919) (xy 42.843228 -136.454504) (xy 42.882008 -136.531056) (xy 42.913449 -136.610904)
			(xy 42.937275 -136.693345) (xy 42.953276 -136.777655) (xy 42.961311 -136.863093) (xy 42.961814 -136.906)
			(xy 42.961311 -136.948907) (xy 42.960341 -136.959223) (xy 45.624485 -136.959223) (xy 45.624485 -136.852777)
			(xy 45.63244 -136.746629) (xy 45.648305 -136.641372) (xy 45.671991 -136.537595) (xy 45.703367 -136.435879)
			(xy 45.742256 -136.336791) (xy 45.788441 -136.240887) (xy 45.841664 -136.148702) (xy 45.901627 -136.060753)
			(xy 45.967995 -135.97753) (xy 46.040396 -135.8995) (xy 46.118426 -135.827099) (xy 46.201649 -135.760731)
			(xy 46.289598 -135.700768) (xy 46.381783 -135.647545) (xy 46.477687 -135.60136) (xy 46.576775 -135.562471)
			(xy 46.678491 -135.531095) (xy 46.782268 -135.507409) (xy 46.887525 -135.491544) (xy 46.993673 -135.483589)
			(xy 47.100119 -135.483589) (xy 47.206267 -135.491544) (xy 47.311524 -135.507409) (xy 47.415301 -135.531095)
			(xy 47.517017 -135.562471) (xy 47.616105 -135.60136) (xy 47.712009 -135.647545) (xy 47.804194 -135.700768)
			(xy 47.892143 -135.760731) (xy 47.975366 -135.827099) (xy 48.053396 -135.8995) (xy 48.125797 -135.97753)
			(xy 48.192165 -136.060753) (xy 48.252128 -136.148702) (xy 48.305351 -136.240887) (xy 48.351536 -136.336791)
			(xy 48.390425 -136.435879) (xy 48.421801 -136.537595) (xy 48.445487 -136.641372) (xy 48.461352 -136.746629)
			(xy 48.469307 -136.852777) (xy 48.469804 -136.906) (xy 53.323495 -136.906) (xy 53.327517 -136.82028)
			(xy 53.339548 -136.735312) (xy 53.359484 -136.651845) (xy 53.387147 -136.570611) (xy 53.422296 -136.492325)
			(xy 53.464622 -136.417674) (xy 53.513751 -136.347315) (xy 53.569254 -136.281865) (xy 53.630641 -136.221901)
			(xy 53.697374 -136.167948) (xy 53.768866 -136.120481) (xy 53.844488 -136.079917) (xy 53.923577 -136.046613)
			(xy 54.005437 -136.020861) (xy 54.089348 -136.002888) (xy 54.174574 -135.992852) (xy 54.260366 -135.99084)
			(xy 54.345968 -135.996871) (xy 54.43063 -136.010891) (xy 54.513607 -136.032777) (xy 54.59417 -136.062338)
			(xy 54.67161 -136.099312) (xy 54.745249 -136.143376) (xy 54.814437 -136.194142) (xy 54.878568 -136.251163)
			(xy 54.937077 -136.313939) (xy 54.98945 -136.381919) (xy 55.035228 -136.454504) (xy 55.074008 -136.531056)
			(xy 55.105449 -136.610904) (xy 55.129275 -136.693345) (xy 55.145276 -136.777655) (xy 55.153311 -136.863093)
			(xy 55.153814 -136.906) (xy 55.153311 -136.948907) (xy 55.152341 -136.959223) (xy 57.816485 -136.959223)
			(xy 57.816485 -136.852777) (xy 57.82444 -136.746629) (xy 57.840305 -136.641372) (xy 57.863991 -136.537595)
			(xy 57.895367 -136.435879) (xy 57.934256 -136.336791) (xy 57.980441 -136.240887) (xy 58.033664 -136.148702)
			(xy 58.093627 -136.060753) (xy 58.159995 -135.97753) (xy 58.232396 -135.8995) (xy 58.310426 -135.827099)
			(xy 58.393649 -135.760731) (xy 58.481598 -135.700768) (xy 58.573783 -135.647545) (xy 58.669687 -135.60136)
			(xy 58.768775 -135.562471) (xy 58.870491 -135.531095) (xy 58.974268 -135.507409) (xy 59.079525 -135.491544)
			(xy 59.185673 -135.483589) (xy 59.292119 -135.483589) (xy 59.398267 -135.491544) (xy 59.503524 -135.507409)
			(xy 59.607301 -135.531095) (xy 59.709017 -135.562471) (xy 59.808105 -135.60136) (xy 59.904009 -135.647545)
			(xy 59.996194 -135.700768) (xy 60.084143 -135.760731) (xy 60.167366 -135.827099) (xy 60.245396 -135.8995)
			(xy 60.317797 -135.97753) (xy 60.384165 -136.060753) (xy 60.444128 -136.148702) (xy 60.497351 -136.240887)
			(xy 60.543536 -136.336791) (xy 60.582425 -136.435879) (xy 60.613801 -136.537595) (xy 60.637487 -136.641372)
			(xy 60.653352 -136.746629) (xy 60.661307 -136.852777) (xy 60.661804 -136.906) (xy 65.515495 -136.906)
			(xy 65.519517 -136.82028) (xy 65.531548 -136.735312) (xy 65.551484 -136.651845) (xy 65.579147 -136.570611)
			(xy 65.614296 -136.492325) (xy 65.656622 -136.417674) (xy 65.705751 -136.347315) (xy 65.761254 -136.281865)
			(xy 65.822641 -136.221901) (xy 65.889374 -136.167948) (xy 65.960866 -136.120481) (xy 66.036488 -136.079917)
			(xy 66.115577 -136.046613) (xy 66.197437 -136.020861) (xy 66.281348 -136.002888) (xy 66.366574 -135.992852)
			(xy 66.452366 -135.99084) (xy 66.537968 -135.996871) (xy 66.62263 -136.010891) (xy 66.705607 -136.032777)
			(xy 66.78617 -136.062338) (xy 66.86361 -136.099312) (xy 66.937249 -136.143376) (xy 67.006437 -136.194142)
			(xy 67.070568 -136.251163) (xy 67.129077 -136.313939) (xy 67.18145 -136.381919) (xy 67.227228 -136.454504)
			(xy 67.266008 -136.531056) (xy 67.297449 -136.610904) (xy 67.321275 -136.693345) (xy 67.337276 -136.777655)
			(xy 67.345311 -136.863093) (xy 67.345814 -136.906) (xy 67.345311 -136.948907) (xy 67.344341 -136.959223)
			(xy 70.008485 -136.959223) (xy 70.008485 -136.852777) (xy 70.01644 -136.746629) (xy 70.032305 -136.641372)
			(xy 70.055991 -136.537595) (xy 70.087367 -136.435879) (xy 70.126256 -136.336791) (xy 70.172441 -136.240887)
			(xy 70.225664 -136.148702) (xy 70.285627 -136.060753) (xy 70.351995 -135.97753) (xy 70.424396 -135.8995)
			(xy 70.502426 -135.827099) (xy 70.585649 -135.760731) (xy 70.673598 -135.700768) (xy 70.765783 -135.647545)
			(xy 70.861687 -135.60136) (xy 70.960775 -135.562471) (xy 71.062491 -135.531095) (xy 71.166268 -135.507409)
			(xy 71.271525 -135.491544) (xy 71.377673 -135.483589) (xy 71.484119 -135.483589) (xy 71.590267 -135.491544)
			(xy 71.695524 -135.507409) (xy 71.799301 -135.531095) (xy 71.901017 -135.562471) (xy 72.000105 -135.60136)
			(xy 72.096009 -135.647545) (xy 72.188194 -135.700768) (xy 72.276143 -135.760731) (xy 72.359366 -135.827099)
			(xy 72.437396 -135.8995) (xy 72.509797 -135.97753) (xy 72.576165 -136.060753) (xy 72.636128 -136.148702)
			(xy 72.689351 -136.240887) (xy 72.735536 -136.336791) (xy 72.774425 -136.435879) (xy 72.805801 -136.537595)
			(xy 72.829487 -136.641372) (xy 72.845352 -136.746629) (xy 72.853307 -136.852777) (xy 72.853804 -136.906)
			(xy 81.131415 -136.906) (xy 81.135437 -136.82028) (xy 81.147468 -136.735312) (xy 81.167404 -136.651845)
			(xy 81.195067 -136.570611) (xy 81.230216 -136.492325) (xy 81.272542 -136.417674) (xy 81.321671 -136.347315)
			(xy 81.377174 -136.281865) (xy 81.438561 -136.221901) (xy 81.505294 -136.167948) (xy 81.576786 -136.120481)
			(xy 81.652408 -136.079917) (xy 81.731497 -136.046613) (xy 81.813357 -136.020861) (xy 81.897268 -136.002888)
			(xy 81.982494 -135.992852) (xy 82.068286 -135.99084) (xy 82.153888 -135.996871) (xy 82.23855 -136.010891)
			(xy 82.321527 -136.032777) (xy 82.40209 -136.062338) (xy 82.47953 -136.099312) (xy 82.553169 -136.143376)
			(xy 82.622357 -136.194142) (xy 82.686488 -136.251163) (xy 82.744997 -136.313939) (xy 82.79737 -136.381919)
			(xy 82.843148 -136.454504) (xy 82.881928 -136.531056) (xy 82.913369 -136.610904) (xy 82.937195 -136.693345)
			(xy 82.953196 -136.777655) (xy 82.961231 -136.863093) (xy 82.961734 -136.906) (xy 82.961231 -136.948907)
			(xy 82.960261 -136.959223) (xy 85.624405 -136.959223) (xy 85.624405 -136.852777) (xy 85.63236 -136.746629)
			(xy 85.648225 -136.641372) (xy 85.671911 -136.537595) (xy 85.703287 -136.435879) (xy 85.742176 -136.336791)
			(xy 85.788361 -136.240887) (xy 85.841584 -136.148702) (xy 85.901547 -136.060753) (xy 85.967915 -135.97753)
			(xy 86.040316 -135.8995) (xy 86.118346 -135.827099) (xy 86.201569 -135.760731) (xy 86.289518 -135.700768)
			(xy 86.381703 -135.647545) (xy 86.477607 -135.60136) (xy 86.576695 -135.562471) (xy 86.678411 -135.531095)
			(xy 86.782188 -135.507409) (xy 86.887445 -135.491544) (xy 86.993593 -135.483589) (xy 87.100039 -135.483589)
			(xy 87.206187 -135.491544) (xy 87.311444 -135.507409) (xy 87.415221 -135.531095) (xy 87.516937 -135.562471)
			(xy 87.616025 -135.60136) (xy 87.711929 -135.647545) (xy 87.804114 -135.700768) (xy 87.892063 -135.760731)
			(xy 87.975286 -135.827099) (xy 88.053316 -135.8995) (xy 88.125717 -135.97753) (xy 88.192085 -136.060753)
			(xy 88.252048 -136.148702) (xy 88.305271 -136.240887) (xy 88.351456 -136.336791) (xy 88.390345 -136.435879)
			(xy 88.421721 -136.537595) (xy 88.445407 -136.641372) (xy 88.461272 -136.746629) (xy 88.469227 -136.852777)
			(xy 88.469724 -136.906) (xy 93.323415 -136.906) (xy 93.327437 -136.82028) (xy 93.339468 -136.735312)
			(xy 93.359404 -136.651845) (xy 93.387067 -136.570611) (xy 93.422216 -136.492325) (xy 93.464542 -136.417674)
			(xy 93.513671 -136.347315) (xy 93.569174 -136.281865) (xy 93.630561 -136.221901) (xy 93.697294 -136.167948)
			(xy 93.768786 -136.120481) (xy 93.844408 -136.079917) (xy 93.923497 -136.046613) (xy 94.005357 -136.020861)
			(xy 94.089268 -136.002888) (xy 94.174494 -135.992852) (xy 94.260286 -135.99084) (xy 94.345888 -135.996871)
			(xy 94.43055 -136.010891) (xy 94.513527 -136.032777) (xy 94.59409 -136.062338) (xy 94.67153 -136.099312)
			(xy 94.745169 -136.143376) (xy 94.814357 -136.194142) (xy 94.878488 -136.251163) (xy 94.936997 -136.313939)
			(xy 94.98937 -136.381919) (xy 95.035148 -136.454504) (xy 95.073928 -136.531056) (xy 95.105369 -136.610904)
			(xy 95.129195 -136.693345) (xy 95.145196 -136.777655) (xy 95.153231 -136.863093) (xy 95.153734 -136.906)
			(xy 95.153231 -136.948907) (xy 95.152261 -136.959223) (xy 97.816405 -136.959223) (xy 97.816405 -136.852777)
			(xy 97.82436 -136.746629) (xy 97.840225 -136.641372) (xy 97.863911 -136.537595) (xy 97.895287 -136.435879)
			(xy 97.934176 -136.336791) (xy 97.980361 -136.240887) (xy 98.033584 -136.148702) (xy 98.093547 -136.060753)
			(xy 98.159915 -135.97753) (xy 98.232316 -135.8995) (xy 98.310346 -135.827099) (xy 98.393569 -135.760731)
			(xy 98.481518 -135.700768) (xy 98.573703 -135.647545) (xy 98.669607 -135.60136) (xy 98.768695 -135.562471)
			(xy 98.870411 -135.531095) (xy 98.974188 -135.507409) (xy 99.079445 -135.491544) (xy 99.185593 -135.483589)
			(xy 99.292039 -135.483589) (xy 99.398187 -135.491544) (xy 99.503444 -135.507409) (xy 99.607221 -135.531095)
			(xy 99.708937 -135.562471) (xy 99.808025 -135.60136) (xy 99.903929 -135.647545) (xy 99.996114 -135.700768)
			(xy 100.084063 -135.760731) (xy 100.167286 -135.827099) (xy 100.245316 -135.8995) (xy 100.317717 -135.97753)
			(xy 100.384085 -136.060753) (xy 100.444048 -136.148702) (xy 100.497271 -136.240887) (xy 100.543456 -136.336791)
			(xy 100.582345 -136.435879) (xy 100.613721 -136.537595) (xy 100.637407 -136.641372) (xy 100.653272 -136.746629)
			(xy 100.661227 -136.852777) (xy 100.661724 -136.906) (xy 105.515415 -136.906) (xy 105.519437 -136.82028)
			(xy 105.531468 -136.735312) (xy 105.551404 -136.651845) (xy 105.579067 -136.570611) (xy 105.614216 -136.492325)
			(xy 105.656542 -136.417674) (xy 105.705671 -136.347315) (xy 105.761174 -136.281865) (xy 105.822561 -136.221901)
			(xy 105.889294 -136.167948) (xy 105.960786 -136.120481) (xy 106.036408 -136.079917) (xy 106.115497 -136.046613)
			(xy 106.197357 -136.020861) (xy 106.281268 -136.002888) (xy 106.366494 -135.992852) (xy 106.452286 -135.99084)
			(xy 106.537888 -135.996871) (xy 106.62255 -136.010891) (xy 106.705527 -136.032777) (xy 106.78609 -136.062338)
			(xy 106.86353 -136.099312) (xy 106.937169 -136.143376) (xy 107.006357 -136.194142) (xy 107.070488 -136.251163)
			(xy 107.128997 -136.313939) (xy 107.18137 -136.381919) (xy 107.227148 -136.454504) (xy 107.265928 -136.531056)
			(xy 107.297369 -136.610904) (xy 107.321195 -136.693345) (xy 107.337196 -136.777655) (xy 107.345231 -136.863093)
			(xy 107.345734 -136.906) (xy 107.345231 -136.948907) (xy 107.344261 -136.959223) (xy 110.008405 -136.959223)
			(xy 110.008405 -136.852777) (xy 110.01636 -136.746629) (xy 110.032225 -136.641372) (xy 110.055911 -136.537595)
			(xy 110.087287 -136.435879) (xy 110.126176 -136.336791) (xy 110.172361 -136.240887) (xy 110.225584 -136.148702)
			(xy 110.285547 -136.060753) (xy 110.351915 -135.97753) (xy 110.424316 -135.8995) (xy 110.502346 -135.827099)
			(xy 110.585569 -135.760731) (xy 110.673518 -135.700768) (xy 110.765703 -135.647545) (xy 110.861607 -135.60136)
			(xy 110.960695 -135.562471) (xy 111.062411 -135.531095) (xy 111.166188 -135.507409) (xy 111.271445 -135.491544)
			(xy 111.377593 -135.483589) (xy 111.484039 -135.483589) (xy 111.590187 -135.491544) (xy 111.695444 -135.507409)
			(xy 111.799221 -135.531095) (xy 111.900937 -135.562471) (xy 112.000025 -135.60136) (xy 112.095929 -135.647545)
			(xy 112.188114 -135.700768) (xy 112.276063 -135.760731) (xy 112.359286 -135.827099) (xy 112.437316 -135.8995)
			(xy 112.509717 -135.97753) (xy 112.576085 -136.060753) (xy 112.636048 -136.148702) (xy 112.689271 -136.240887)
			(xy 112.735456 -136.336791) (xy 112.774345 -136.435879) (xy 112.805721 -136.537595) (xy 112.829407 -136.641372)
			(xy 112.845272 -136.746629) (xy 112.853227 -136.852777) (xy 112.853724 -136.906) (xy 121.131589 -136.906)
			(xy 121.135611 -136.82028) (xy 121.147642 -136.735312) (xy 121.167578 -136.651845) (xy 121.195241 -136.570611)
			(xy 121.23039 -136.492325) (xy 121.272716 -136.417674) (xy 121.321845 -136.347315) (xy 121.377348 -136.281865)
			(xy 121.438735 -136.221901) (xy 121.505468 -136.167948) (xy 121.57696 -136.120481) (xy 121.652582 -136.079917)
			(xy 121.731671 -136.046613) (xy 121.813531 -136.020861) (xy 121.897442 -136.002888) (xy 121.982668 -135.992852)
			(xy 122.06846 -135.99084) (xy 122.154062 -135.996871) (xy 122.238724 -136.010891) (xy 122.321701 -136.032777)
			(xy 122.402264 -136.062338) (xy 122.479704 -136.099312) (xy 122.553343 -136.143376) (xy 122.622531 -136.194142)
			(xy 122.686662 -136.251163) (xy 122.745171 -136.313939) (xy 122.797544 -136.381919) (xy 122.843322 -136.454504)
			(xy 122.882102 -136.531056) (xy 122.913543 -136.610904) (xy 122.937369 -136.693345) (xy 122.95337 -136.777655)
			(xy 122.961405 -136.863093) (xy 122.961908 -136.906) (xy 122.961405 -136.948907) (xy 122.960435 -136.959223)
			(xy 125.624579 -136.959223) (xy 125.624579 -136.852777) (xy 125.632534 -136.746629) (xy 125.648399 -136.641372)
			(xy 125.672085 -136.537595) (xy 125.703461 -136.435879) (xy 125.74235 -136.336791) (xy 125.788535 -136.240887)
			(xy 125.841758 -136.148702) (xy 125.901721 -136.060753) (xy 125.968089 -135.97753) (xy 126.04049 -135.8995)
			(xy 126.11852 -135.827099) (xy 126.201743 -135.760731) (xy 126.289692 -135.700768) (xy 126.381877 -135.647545)
			(xy 126.477781 -135.60136) (xy 126.576869 -135.562471) (xy 126.678585 -135.531095) (xy 126.782362 -135.507409)
			(xy 126.887619 -135.491544) (xy 126.993767 -135.483589) (xy 127.100213 -135.483589) (xy 127.206361 -135.491544)
			(xy 127.311618 -135.507409) (xy 127.415395 -135.531095) (xy 127.517111 -135.562471) (xy 127.616199 -135.60136)
			(xy 127.712103 -135.647545) (xy 127.804288 -135.700768) (xy 127.892237 -135.760731) (xy 127.97546 -135.827099)
			(xy 128.05349 -135.8995) (xy 128.125891 -135.97753) (xy 128.192259 -136.060753) (xy 128.252222 -136.148702)
			(xy 128.305445 -136.240887) (xy 128.35163 -136.336791) (xy 128.390519 -136.435879) (xy 128.421895 -136.537595)
			(xy 128.445581 -136.641372) (xy 128.461446 -136.746629) (xy 128.469401 -136.852777) (xy 128.469898 -136.906)
			(xy 133.323589 -136.906) (xy 133.327611 -136.82028) (xy 133.339642 -136.735312) (xy 133.359578 -136.651845)
			(xy 133.387241 -136.570611) (xy 133.42239 -136.492325) (xy 133.464716 -136.417674) (xy 133.513845 -136.347315)
			(xy 133.569348 -136.281865) (xy 133.630735 -136.221901) (xy 133.697468 -136.167948) (xy 133.76896 -136.120481)
			(xy 133.844582 -136.079917) (xy 133.923671 -136.046613) (xy 134.005531 -136.020861) (xy 134.089442 -136.002888)
			(xy 134.174668 -135.992852) (xy 134.26046 -135.99084) (xy 134.346062 -135.996871) (xy 134.430724 -136.010891)
			(xy 134.513701 -136.032777) (xy 134.594264 -136.062338) (xy 134.671704 -136.099312) (xy 134.745343 -136.143376)
			(xy 134.814531 -136.194142) (xy 134.878662 -136.251163) (xy 134.937171 -136.313939) (xy 134.989544 -136.381919)
			(xy 135.035322 -136.454504) (xy 135.074102 -136.531056) (xy 135.105543 -136.610904) (xy 135.129369 -136.693345)
			(xy 135.14537 -136.777655) (xy 135.153405 -136.863093) (xy 135.153908 -136.906) (xy 135.153405 -136.948907)
			(xy 135.152435 -136.959223) (xy 137.816579 -136.959223) (xy 137.816579 -136.852777) (xy 137.824534 -136.746629)
			(xy 137.840399 -136.641372) (xy 137.864085 -136.537595) (xy 137.895461 -136.435879) (xy 137.93435 -136.336791)
			(xy 137.980535 -136.240887) (xy 138.033758 -136.148702) (xy 138.093721 -136.060753) (xy 138.160089 -135.97753)
			(xy 138.23249 -135.8995) (xy 138.31052 -135.827099) (xy 138.393743 -135.760731) (xy 138.481692 -135.700768)
			(xy 138.573877 -135.647545) (xy 138.669781 -135.60136) (xy 138.768869 -135.562471) (xy 138.870585 -135.531095)
			(xy 138.974362 -135.507409) (xy 139.079619 -135.491544) (xy 139.185767 -135.483589) (xy 139.292213 -135.483589)
			(xy 139.398361 -135.491544) (xy 139.503618 -135.507409) (xy 139.607395 -135.531095) (xy 139.709111 -135.562471)
			(xy 139.808199 -135.60136) (xy 139.904103 -135.647545) (xy 139.996288 -135.700768) (xy 140.084237 -135.760731)
			(xy 140.16746 -135.827099) (xy 140.24549 -135.8995) (xy 140.317891 -135.97753) (xy 140.384259 -136.060753)
			(xy 140.444222 -136.148702) (xy 140.497445 -136.240887) (xy 140.54363 -136.336791) (xy 140.582519 -136.435879)
			(xy 140.613895 -136.537595) (xy 140.637581 -136.641372) (xy 140.653446 -136.746629) (xy 140.661401 -136.852777)
			(xy 140.661898 -136.906) (xy 145.515589 -136.906) (xy 145.519611 -136.82028) (xy 145.531642 -136.735312)
			(xy 145.551578 -136.651845) (xy 145.579241 -136.570611) (xy 145.61439 -136.492325) (xy 145.656716 -136.417674)
			(xy 145.705845 -136.347315) (xy 145.761348 -136.281865) (xy 145.822735 -136.221901) (xy 145.889468 -136.167948)
			(xy 145.96096 -136.120481) (xy 146.036582 -136.079917) (xy 146.115671 -136.046613) (xy 146.197531 -136.020861)
			(xy 146.281442 -136.002888) (xy 146.366668 -135.992852) (xy 146.45246 -135.99084) (xy 146.538062 -135.996871)
			(xy 146.622724 -136.010891) (xy 146.705701 -136.032777) (xy 146.786264 -136.062338) (xy 146.863704 -136.099312)
			(xy 146.937343 -136.143376) (xy 147.006531 -136.194142) (xy 147.070662 -136.251163) (xy 147.129171 -136.313939)
			(xy 147.181544 -136.381919) (xy 147.227322 -136.454504) (xy 147.266102 -136.531056) (xy 147.297543 -136.610904)
			(xy 147.321369 -136.693345) (xy 147.33737 -136.777655) (xy 147.345405 -136.863093) (xy 147.345908 -136.906)
			(xy 147.345405 -136.948907) (xy 147.344435 -136.959223) (xy 150.008579 -136.959223) (xy 150.008579 -136.852777)
			(xy 150.016534 -136.746629) (xy 150.032399 -136.641372) (xy 150.056085 -136.537595) (xy 150.087461 -136.435879)
			(xy 150.12635 -136.336791) (xy 150.172535 -136.240887) (xy 150.225758 -136.148702) (xy 150.285721 -136.060753)
			(xy 150.352089 -135.97753) (xy 150.42449 -135.8995) (xy 150.50252 -135.827099) (xy 150.585743 -135.760731)
			(xy 150.673692 -135.700768) (xy 150.765877 -135.647545) (xy 150.861781 -135.60136) (xy 150.960869 -135.562471)
			(xy 151.062585 -135.531095) (xy 151.166362 -135.507409) (xy 151.271619 -135.491544) (xy 151.377767 -135.483589)
			(xy 151.484213 -135.483589) (xy 151.590361 -135.491544) (xy 151.695618 -135.507409) (xy 151.799395 -135.531095)
			(xy 151.901111 -135.562471) (xy 152.000199 -135.60136) (xy 152.096103 -135.647545) (xy 152.188288 -135.700768)
			(xy 152.276237 -135.760731) (xy 152.35946 -135.827099) (xy 152.43749 -135.8995) (xy 152.509891 -135.97753)
			(xy 152.576259 -136.060753) (xy 152.636222 -136.148702) (xy 152.689445 -136.240887) (xy 152.73563 -136.336791)
			(xy 152.774519 -136.435879) (xy 152.805895 -136.537595) (xy 152.829581 -136.641372) (xy 152.845446 -136.746629)
			(xy 152.853401 -136.852777) (xy 152.853898 -136.906) (xy 161.131763 -136.906) (xy 161.135785 -136.82028)
			(xy 161.147816 -136.735312) (xy 161.167752 -136.651845) (xy 161.195415 -136.570611) (xy 161.230564 -136.492325)
			(xy 161.27289 -136.417674) (xy 161.322019 -136.347315) (xy 161.377522 -136.281865) (xy 161.438909 -136.221901)
			(xy 161.505642 -136.167948) (xy 161.577134 -136.120481) (xy 161.652756 -136.079917) (xy 161.731845 -136.046613)
			(xy 161.813705 -136.020861) (xy 161.897616 -136.002888) (xy 161.982842 -135.992852) (xy 162.068634 -135.99084)
			(xy 162.154236 -135.996871) (xy 162.238898 -136.010891) (xy 162.321875 -136.032777) (xy 162.402438 -136.062338)
			(xy 162.479878 -136.099312) (xy 162.553517 -136.143376) (xy 162.622705 -136.194142) (xy 162.686836 -136.251163)
			(xy 162.745345 -136.313939) (xy 162.797718 -136.381919) (xy 162.843496 -136.454504) (xy 162.882276 -136.531056)
			(xy 162.913717 -136.610904) (xy 162.937543 -136.693345) (xy 162.953544 -136.777655) (xy 162.961579 -136.863093)
			(xy 162.962082 -136.906) (xy 162.961579 -136.948907) (xy 162.960609 -136.959223) (xy 165.624753 -136.959223)
			(xy 165.624753 -136.852777) (xy 165.632708 -136.746629) (xy 165.648573 -136.641372) (xy 165.672259 -136.537595)
			(xy 165.703635 -136.435879) (xy 165.742524 -136.336791) (xy 165.788709 -136.240887) (xy 165.841932 -136.148702)
			(xy 165.901895 -136.060753) (xy 165.968263 -135.97753) (xy 166.040664 -135.8995) (xy 166.118694 -135.827099)
			(xy 166.201917 -135.760731) (xy 166.289866 -135.700768) (xy 166.382051 -135.647545) (xy 166.477955 -135.60136)
			(xy 166.577043 -135.562471) (xy 166.678759 -135.531095) (xy 166.782536 -135.507409) (xy 166.887793 -135.491544)
			(xy 166.993941 -135.483589) (xy 167.100387 -135.483589) (xy 167.206535 -135.491544) (xy 167.311792 -135.507409)
			(xy 167.415569 -135.531095) (xy 167.517285 -135.562471) (xy 167.616373 -135.60136) (xy 167.712277 -135.647545)
			(xy 167.804462 -135.700768) (xy 167.892411 -135.760731) (xy 167.975634 -135.827099) (xy 168.053664 -135.8995)
			(xy 168.126065 -135.97753) (xy 168.192433 -136.060753) (xy 168.252396 -136.148702) (xy 168.305619 -136.240887)
			(xy 168.351804 -136.336791) (xy 168.390693 -136.435879) (xy 168.422069 -136.537595) (xy 168.445755 -136.641372)
			(xy 168.46162 -136.746629) (xy 168.469575 -136.852777) (xy 168.470072 -136.906) (xy 173.323763 -136.906)
			(xy 173.327785 -136.82028) (xy 173.339816 -136.735312) (xy 173.359752 -136.651845) (xy 173.387415 -136.570611)
			(xy 173.422564 -136.492325) (xy 173.46489 -136.417674) (xy 173.514019 -136.347315) (xy 173.569522 -136.281865)
			(xy 173.630909 -136.221901) (xy 173.697642 -136.167948) (xy 173.769134 -136.120481) (xy 173.844756 -136.079917)
			(xy 173.923845 -136.046613) (xy 174.005705 -136.020861) (xy 174.089616 -136.002888) (xy 174.174842 -135.992852)
			(xy 174.260634 -135.99084) (xy 174.346236 -135.996871) (xy 174.430898 -136.010891) (xy 174.513875 -136.032777)
			(xy 174.594438 -136.062338) (xy 174.671878 -136.099312) (xy 174.745517 -136.143376) (xy 174.814705 -136.194142)
			(xy 174.878836 -136.251163) (xy 174.937345 -136.313939) (xy 174.989718 -136.381919) (xy 175.035496 -136.454504)
			(xy 175.074276 -136.531056) (xy 175.105717 -136.610904) (xy 175.129543 -136.693345) (xy 175.145544 -136.777655)
			(xy 175.153579 -136.863093) (xy 175.154082 -136.906) (xy 175.153579 -136.948907) (xy 175.152609 -136.959223)
			(xy 177.816753 -136.959223) (xy 177.816753 -136.852777) (xy 177.824708 -136.746629) (xy 177.840573 -136.641372)
			(xy 177.864259 -136.537595) (xy 177.895635 -136.435879) (xy 177.934524 -136.336791) (xy 177.980709 -136.240887)
			(xy 178.033932 -136.148702) (xy 178.093895 -136.060753) (xy 178.160263 -135.97753) (xy 178.232664 -135.8995)
			(xy 178.310694 -135.827099) (xy 178.393917 -135.760731) (xy 178.481866 -135.700768) (xy 178.574051 -135.647545)
			(xy 178.669955 -135.60136) (xy 178.769043 -135.562471) (xy 178.870759 -135.531095) (xy 178.974536 -135.507409)
			(xy 179.079793 -135.491544) (xy 179.185941 -135.483589) (xy 179.292387 -135.483589) (xy 179.398535 -135.491544)
			(xy 179.503792 -135.507409) (xy 179.607569 -135.531095) (xy 179.709285 -135.562471) (xy 179.808373 -135.60136)
			(xy 179.904277 -135.647545) (xy 179.996462 -135.700768) (xy 180.084411 -135.760731) (xy 180.167634 -135.827099)
			(xy 180.245664 -135.8995) (xy 180.318065 -135.97753) (xy 180.384433 -136.060753) (xy 180.444396 -136.148702)
			(xy 180.497619 -136.240887) (xy 180.543804 -136.336791) (xy 180.582693 -136.435879) (xy 180.614069 -136.537595)
			(xy 180.637755 -136.641372) (xy 180.65362 -136.746629) (xy 180.661575 -136.852777) (xy 180.662072 -136.906)
			(xy 185.515763 -136.906) (xy 185.519785 -136.82028) (xy 185.531816 -136.735312) (xy 185.551752 -136.651845)
			(xy 185.579415 -136.570611) (xy 185.614564 -136.492325) (xy 185.65689 -136.417674) (xy 185.706019 -136.347315)
			(xy 185.761522 -136.281865) (xy 185.822909 -136.221901) (xy 185.889642 -136.167948) (xy 185.961134 -136.120481)
			(xy 186.036756 -136.079917) (xy 186.115845 -136.046613) (xy 186.197705 -136.020861) (xy 186.281616 -136.002888)
			(xy 186.366842 -135.992852) (xy 186.452634 -135.99084) (xy 186.538236 -135.996871) (xy 186.622898 -136.010891)
			(xy 186.705875 -136.032777) (xy 186.786438 -136.062338) (xy 186.863878 -136.099312) (xy 186.937517 -136.143376)
			(xy 187.006705 -136.194142) (xy 187.070836 -136.251163) (xy 187.129345 -136.313939) (xy 187.181718 -136.381919)
			(xy 187.227496 -136.454504) (xy 187.266276 -136.531056) (xy 187.297717 -136.610904) (xy 187.321543 -136.693345)
			(xy 187.337544 -136.777655) (xy 187.345579 -136.863093) (xy 187.346082 -136.906) (xy 187.345579 -136.948907)
			(xy 187.344609 -136.959223) (xy 190.008753 -136.959223) (xy 190.008753 -136.852777) (xy 190.016708 -136.746629)
			(xy 190.032573 -136.641372) (xy 190.056259 -136.537595) (xy 190.087635 -136.435879) (xy 190.126524 -136.336791)
			(xy 190.172709 -136.240887) (xy 190.225932 -136.148702) (xy 190.285895 -136.060753) (xy 190.352263 -135.97753)
			(xy 190.424664 -135.8995) (xy 190.502694 -135.827099) (xy 190.585917 -135.760731) (xy 190.673866 -135.700768)
			(xy 190.766051 -135.647545) (xy 190.861955 -135.60136) (xy 190.961043 -135.562471) (xy 191.062759 -135.531095)
			(xy 191.166536 -135.507409) (xy 191.271793 -135.491544) (xy 191.377941 -135.483589) (xy 191.484387 -135.483589)
			(xy 191.590535 -135.491544) (xy 191.695792 -135.507409) (xy 191.799569 -135.531095) (xy 191.901285 -135.562471)
			(xy 192.000373 -135.60136) (xy 192.096277 -135.647545) (xy 192.188462 -135.700768) (xy 192.276411 -135.760731)
			(xy 192.359634 -135.827099) (xy 192.437664 -135.8995) (xy 192.510065 -135.97753) (xy 192.576433 -136.060753)
			(xy 192.636396 -136.148702) (xy 192.689619 -136.240887) (xy 192.735804 -136.336791) (xy 192.774693 -136.435879)
			(xy 192.806069 -136.537595) (xy 192.829755 -136.641372) (xy 192.84562 -136.746629) (xy 192.853575 -136.852777)
			(xy 192.854072 -136.906) (xy 192.853575 -136.959223) (xy 192.84562 -137.065371) (xy 192.829755 -137.170628)
			(xy 192.806069 -137.274405) (xy 192.774693 -137.376121) (xy 192.735804 -137.475209) (xy 192.689619 -137.571113)
			(xy 192.636396 -137.663298) (xy 192.576433 -137.751247) (xy 192.510065 -137.83447) (xy 192.437664 -137.9125)
			(xy 192.359634 -137.984901) (xy 192.276411 -138.051269) (xy 192.188462 -138.111232) (xy 192.096277 -138.164455)
			(xy 192.000373 -138.21064) (xy 191.901285 -138.249529) (xy 191.799569 -138.280905) (xy 191.695792 -138.304591)
			(xy 191.590535 -138.320456) (xy 191.484387 -138.328411) (xy 191.377941 -138.328411) (xy 191.271793 -138.320456)
			(xy 191.166536 -138.304591) (xy 191.062759 -138.280905) (xy 190.961043 -138.249529) (xy 190.861955 -138.21064)
			(xy 190.766051 -138.164455) (xy 190.673866 -138.111232) (xy 190.585917 -138.051269) (xy 190.502694 -137.984901)
			(xy 190.424664 -137.9125) (xy 190.352263 -137.83447) (xy 190.285895 -137.751247) (xy 190.225932 -137.663298)
			(xy 190.172709 -137.571113) (xy 190.126524 -137.475209) (xy 190.087635 -137.376121) (xy 190.056259 -137.274405)
			(xy 190.032573 -137.170628) (xy 190.016708 -137.065371) (xy 190.008753 -136.959223) (xy 187.344609 -136.959223)
			(xy 187.337544 -137.034345) (xy 187.321543 -137.118655) (xy 187.297717 -137.201096) (xy 187.266276 -137.280944)
			(xy 187.227496 -137.357496) (xy 187.181718 -137.430081) (xy 187.129345 -137.498061) (xy 187.070836 -137.560837)
			(xy 187.006705 -137.617858) (xy 186.937517 -137.668624) (xy 186.863878 -137.712688) (xy 186.786438 -137.749662)
			(xy 186.705875 -137.779223) (xy 186.622898 -137.801109) (xy 186.538236 -137.815129) (xy 186.452634 -137.82116)
			(xy 186.366842 -137.819148) (xy 186.281616 -137.809112) (xy 186.197705 -137.791139) (xy 186.115845 -137.765387)
			(xy 186.036756 -137.732083) (xy 185.961134 -137.691519) (xy 185.889642 -137.644052) (xy 185.822909 -137.590099)
			(xy 185.761522 -137.530135) (xy 185.706019 -137.464685) (xy 185.65689 -137.394326) (xy 185.614564 -137.319675)
			(xy 185.579415 -137.241389) (xy 185.551752 -137.160155) (xy 185.531816 -137.076688) (xy 185.519785 -136.99172)
			(xy 185.515763 -136.906) (xy 180.662072 -136.906) (xy 180.661575 -136.959223) (xy 180.65362 -137.065371)
			(xy 180.637755 -137.170628) (xy 180.614069 -137.274405) (xy 180.582693 -137.376121) (xy 180.543804 -137.475209)
			(xy 180.497619 -137.571113) (xy 180.444396 -137.663298) (xy 180.384433 -137.751247) (xy 180.318065 -137.83447)
			(xy 180.245664 -137.9125) (xy 180.167634 -137.984901) (xy 180.084411 -138.051269) (xy 179.996462 -138.111232)
			(xy 179.904277 -138.164455) (xy 179.808373 -138.21064) (xy 179.709285 -138.249529) (xy 179.607569 -138.280905)
			(xy 179.503792 -138.304591) (xy 179.398535 -138.320456) (xy 179.292387 -138.328411) (xy 179.185941 -138.328411)
			(xy 179.079793 -138.320456) (xy 178.974536 -138.304591) (xy 178.870759 -138.280905) (xy 178.769043 -138.249529)
			(xy 178.669955 -138.21064) (xy 178.574051 -138.164455) (xy 178.481866 -138.111232) (xy 178.393917 -138.051269)
			(xy 178.310694 -137.984901) (xy 178.232664 -137.9125) (xy 178.160263 -137.83447) (xy 178.093895 -137.751247)
			(xy 178.033932 -137.663298) (xy 177.980709 -137.571113) (xy 177.934524 -137.475209) (xy 177.895635 -137.376121)
			(xy 177.864259 -137.274405) (xy 177.840573 -137.170628) (xy 177.824708 -137.065371) (xy 177.816753 -136.959223)
			(xy 175.152609 -136.959223) (xy 175.145544 -137.034345) (xy 175.129543 -137.118655) (xy 175.105717 -137.201096)
			(xy 175.074276 -137.280944) (xy 175.035496 -137.357496) (xy 174.989718 -137.430081) (xy 174.937345 -137.498061)
			(xy 174.878836 -137.560837) (xy 174.814705 -137.617858) (xy 174.745517 -137.668624) (xy 174.671878 -137.712688)
			(xy 174.594438 -137.749662) (xy 174.513875 -137.779223) (xy 174.430898 -137.801109) (xy 174.346236 -137.815129)
			(xy 174.260634 -137.82116) (xy 174.174842 -137.819148) (xy 174.089616 -137.809112) (xy 174.005705 -137.791139)
			(xy 173.923845 -137.765387) (xy 173.844756 -137.732083) (xy 173.769134 -137.691519) (xy 173.697642 -137.644052)
			(xy 173.630909 -137.590099) (xy 173.569522 -137.530135) (xy 173.514019 -137.464685) (xy 173.46489 -137.394326)
			(xy 173.422564 -137.319675) (xy 173.387415 -137.241389) (xy 173.359752 -137.160155) (xy 173.339816 -137.076688)
			(xy 173.327785 -136.99172) (xy 173.323763 -136.906) (xy 168.470072 -136.906) (xy 168.469575 -136.959223)
			(xy 168.46162 -137.065371) (xy 168.445755 -137.170628) (xy 168.422069 -137.274405) (xy 168.390693 -137.376121)
			(xy 168.351804 -137.475209) (xy 168.305619 -137.571113) (xy 168.252396 -137.663298) (xy 168.192433 -137.751247)
			(xy 168.126065 -137.83447) (xy 168.053664 -137.9125) (xy 167.975634 -137.984901) (xy 167.892411 -138.051269)
			(xy 167.804462 -138.111232) (xy 167.712277 -138.164455) (xy 167.616373 -138.21064) (xy 167.517285 -138.249529)
			(xy 167.415569 -138.280905) (xy 167.311792 -138.304591) (xy 167.206535 -138.320456) (xy 167.100387 -138.328411)
			(xy 166.993941 -138.328411) (xy 166.887793 -138.320456) (xy 166.782536 -138.304591) (xy 166.678759 -138.280905)
			(xy 166.577043 -138.249529) (xy 166.477955 -138.21064) (xy 166.382051 -138.164455) (xy 166.289866 -138.111232)
			(xy 166.201917 -138.051269) (xy 166.118694 -137.984901) (xy 166.040664 -137.9125) (xy 165.968263 -137.83447)
			(xy 165.901895 -137.751247) (xy 165.841932 -137.663298) (xy 165.788709 -137.571113) (xy 165.742524 -137.475209)
			(xy 165.703635 -137.376121) (xy 165.672259 -137.274405) (xy 165.648573 -137.170628) (xy 165.632708 -137.065371)
			(xy 165.624753 -136.959223) (xy 162.960609 -136.959223) (xy 162.953544 -137.034345) (xy 162.937543 -137.118655)
			(xy 162.913717 -137.201096) (xy 162.882276 -137.280944) (xy 162.843496 -137.357496) (xy 162.797718 -137.430081)
			(xy 162.745345 -137.498061) (xy 162.686836 -137.560837) (xy 162.622705 -137.617858) (xy 162.553517 -137.668624)
			(xy 162.479878 -137.712688) (xy 162.402438 -137.749662) (xy 162.321875 -137.779223) (xy 162.238898 -137.801109)
			(xy 162.154236 -137.815129) (xy 162.068634 -137.82116) (xy 161.982842 -137.819148) (xy 161.897616 -137.809112)
			(xy 161.813705 -137.791139) (xy 161.731845 -137.765387) (xy 161.652756 -137.732083) (xy 161.577134 -137.691519)
			(xy 161.505642 -137.644052) (xy 161.438909 -137.590099) (xy 161.377522 -137.530135) (xy 161.322019 -137.464685)
			(xy 161.27289 -137.394326) (xy 161.230564 -137.319675) (xy 161.195415 -137.241389) (xy 161.167752 -137.160155)
			(xy 161.147816 -137.076688) (xy 161.135785 -136.99172) (xy 161.131763 -136.906) (xy 152.853898 -136.906)
			(xy 152.853401 -136.959223) (xy 152.845446 -137.065371) (xy 152.829581 -137.170628) (xy 152.805895 -137.274405)
			(xy 152.774519 -137.376121) (xy 152.73563 -137.475209) (xy 152.689445 -137.571113) (xy 152.636222 -137.663298)
			(xy 152.576259 -137.751247) (xy 152.509891 -137.83447) (xy 152.43749 -137.9125) (xy 152.35946 -137.984901)
			(xy 152.276237 -138.051269) (xy 152.188288 -138.111232) (xy 152.096103 -138.164455) (xy 152.000199 -138.21064)
			(xy 151.901111 -138.249529) (xy 151.799395 -138.280905) (xy 151.695618 -138.304591) (xy 151.590361 -138.320456)
			(xy 151.484213 -138.328411) (xy 151.377767 -138.328411) (xy 151.271619 -138.320456) (xy 151.166362 -138.304591)
			(xy 151.062585 -138.280905) (xy 150.960869 -138.249529) (xy 150.861781 -138.21064) (xy 150.765877 -138.164455)
			(xy 150.673692 -138.111232) (xy 150.585743 -138.051269) (xy 150.50252 -137.984901) (xy 150.42449 -137.9125)
			(xy 150.352089 -137.83447) (xy 150.285721 -137.751247) (xy 150.225758 -137.663298) (xy 150.172535 -137.571113)
			(xy 150.12635 -137.475209) (xy 150.087461 -137.376121) (xy 150.056085 -137.274405) (xy 150.032399 -137.170628)
			(xy 150.016534 -137.065371) (xy 150.008579 -136.959223) (xy 147.344435 -136.959223) (xy 147.33737 -137.034345)
			(xy 147.321369 -137.118655) (xy 147.297543 -137.201096) (xy 147.266102 -137.280944) (xy 147.227322 -137.357496)
			(xy 147.181544 -137.430081) (xy 147.129171 -137.498061) (xy 147.070662 -137.560837) (xy 147.006531 -137.617858)
			(xy 146.937343 -137.668624) (xy 146.863704 -137.712688) (xy 146.786264 -137.749662) (xy 146.705701 -137.779223)
			(xy 146.622724 -137.801109) (xy 146.538062 -137.815129) (xy 146.45246 -137.82116) (xy 146.366668 -137.819148)
			(xy 146.281442 -137.809112) (xy 146.197531 -137.791139) (xy 146.115671 -137.765387) (xy 146.036582 -137.732083)
			(xy 145.96096 -137.691519) (xy 145.889468 -137.644052) (xy 145.822735 -137.590099) (xy 145.761348 -137.530135)
			(xy 145.705845 -137.464685) (xy 145.656716 -137.394326) (xy 145.61439 -137.319675) (xy 145.579241 -137.241389)
			(xy 145.551578 -137.160155) (xy 145.531642 -137.076688) (xy 145.519611 -136.99172) (xy 145.515589 -136.906)
			(xy 140.661898 -136.906) (xy 140.661401 -136.959223) (xy 140.653446 -137.065371) (xy 140.637581 -137.170628)
			(xy 140.613895 -137.274405) (xy 140.582519 -137.376121) (xy 140.54363 -137.475209) (xy 140.497445 -137.571113)
			(xy 140.444222 -137.663298) (xy 140.384259 -137.751247) (xy 140.317891 -137.83447) (xy 140.24549 -137.9125)
			(xy 140.16746 -137.984901) (xy 140.084237 -138.051269) (xy 139.996288 -138.111232) (xy 139.904103 -138.164455)
			(xy 139.808199 -138.21064) (xy 139.709111 -138.249529) (xy 139.607395 -138.280905) (xy 139.503618 -138.304591)
			(xy 139.398361 -138.320456) (xy 139.292213 -138.328411) (xy 139.185767 -138.328411) (xy 139.079619 -138.320456)
			(xy 138.974362 -138.304591) (xy 138.870585 -138.280905) (xy 138.768869 -138.249529) (xy 138.669781 -138.21064)
			(xy 138.573877 -138.164455) (xy 138.481692 -138.111232) (xy 138.393743 -138.051269) (xy 138.31052 -137.984901)
			(xy 138.23249 -137.9125) (xy 138.160089 -137.83447) (xy 138.093721 -137.751247) (xy 138.033758 -137.663298)
			(xy 137.980535 -137.571113) (xy 137.93435 -137.475209) (xy 137.895461 -137.376121) (xy 137.864085 -137.274405)
			(xy 137.840399 -137.170628) (xy 137.824534 -137.065371) (xy 137.816579 -136.959223) (xy 135.152435 -136.959223)
			(xy 135.14537 -137.034345) (xy 135.129369 -137.118655) (xy 135.105543 -137.201096) (xy 135.074102 -137.280944)
			(xy 135.035322 -137.357496) (xy 134.989544 -137.430081) (xy 134.937171 -137.498061) (xy 134.878662 -137.560837)
			(xy 134.814531 -137.617858) (xy 134.745343 -137.668624) (xy 134.671704 -137.712688) (xy 134.594264 -137.749662)
			(xy 134.513701 -137.779223) (xy 134.430724 -137.801109) (xy 134.346062 -137.815129) (xy 134.26046 -137.82116)
			(xy 134.174668 -137.819148) (xy 134.089442 -137.809112) (xy 134.005531 -137.791139) (xy 133.923671 -137.765387)
			(xy 133.844582 -137.732083) (xy 133.76896 -137.691519) (xy 133.697468 -137.644052) (xy 133.630735 -137.590099)
			(xy 133.569348 -137.530135) (xy 133.513845 -137.464685) (xy 133.464716 -137.394326) (xy 133.42239 -137.319675)
			(xy 133.387241 -137.241389) (xy 133.359578 -137.160155) (xy 133.339642 -137.076688) (xy 133.327611 -136.99172)
			(xy 133.323589 -136.906) (xy 128.469898 -136.906) (xy 128.469401 -136.959223) (xy 128.461446 -137.065371)
			(xy 128.445581 -137.170628) (xy 128.421895 -137.274405) (xy 128.390519 -137.376121) (xy 128.35163 -137.475209)
			(xy 128.305445 -137.571113) (xy 128.252222 -137.663298) (xy 128.192259 -137.751247) (xy 128.125891 -137.83447)
			(xy 128.05349 -137.9125) (xy 127.97546 -137.984901) (xy 127.892237 -138.051269) (xy 127.804288 -138.111232)
			(xy 127.712103 -138.164455) (xy 127.616199 -138.21064) (xy 127.517111 -138.249529) (xy 127.415395 -138.280905)
			(xy 127.311618 -138.304591) (xy 127.206361 -138.320456) (xy 127.100213 -138.328411) (xy 126.993767 -138.328411)
			(xy 126.887619 -138.320456) (xy 126.782362 -138.304591) (xy 126.678585 -138.280905) (xy 126.576869 -138.249529)
			(xy 126.477781 -138.21064) (xy 126.381877 -138.164455) (xy 126.289692 -138.111232) (xy 126.201743 -138.051269)
			(xy 126.11852 -137.984901) (xy 126.04049 -137.9125) (xy 125.968089 -137.83447) (xy 125.901721 -137.751247)
			(xy 125.841758 -137.663298) (xy 125.788535 -137.571113) (xy 125.74235 -137.475209) (xy 125.703461 -137.376121)
			(xy 125.672085 -137.274405) (xy 125.648399 -137.170628) (xy 125.632534 -137.065371) (xy 125.624579 -136.959223)
			(xy 122.960435 -136.959223) (xy 122.95337 -137.034345) (xy 122.937369 -137.118655) (xy 122.913543 -137.201096)
			(xy 122.882102 -137.280944) (xy 122.843322 -137.357496) (xy 122.797544 -137.430081) (xy 122.745171 -137.498061)
			(xy 122.686662 -137.560837) (xy 122.622531 -137.617858) (xy 122.553343 -137.668624) (xy 122.479704 -137.712688)
			(xy 122.402264 -137.749662) (xy 122.321701 -137.779223) (xy 122.238724 -137.801109) (xy 122.154062 -137.815129)
			(xy 122.06846 -137.82116) (xy 121.982668 -137.819148) (xy 121.897442 -137.809112) (xy 121.813531 -137.791139)
			(xy 121.731671 -137.765387) (xy 121.652582 -137.732083) (xy 121.57696 -137.691519) (xy 121.505468 -137.644052)
			(xy 121.438735 -137.590099) (xy 121.377348 -137.530135) (xy 121.321845 -137.464685) (xy 121.272716 -137.394326)
			(xy 121.23039 -137.319675) (xy 121.195241 -137.241389) (xy 121.167578 -137.160155) (xy 121.147642 -137.076688)
			(xy 121.135611 -136.99172) (xy 121.131589 -136.906) (xy 112.853724 -136.906) (xy 112.853227 -136.959223)
			(xy 112.845272 -137.065371) (xy 112.829407 -137.170628) (xy 112.805721 -137.274405) (xy 112.774345 -137.376121)
			(xy 112.735456 -137.475209) (xy 112.689271 -137.571113) (xy 112.636048 -137.663298) (xy 112.576085 -137.751247)
			(xy 112.509717 -137.83447) (xy 112.437316 -137.9125) (xy 112.359286 -137.984901) (xy 112.276063 -138.051269)
			(xy 112.188114 -138.111232) (xy 112.095929 -138.164455) (xy 112.000025 -138.21064) (xy 111.900937 -138.249529)
			(xy 111.799221 -138.280905) (xy 111.695444 -138.304591) (xy 111.590187 -138.320456) (xy 111.484039 -138.328411)
			(xy 111.377593 -138.328411) (xy 111.271445 -138.320456) (xy 111.166188 -138.304591) (xy 111.062411 -138.280905)
			(xy 110.960695 -138.249529) (xy 110.861607 -138.21064) (xy 110.765703 -138.164455) (xy 110.673518 -138.111232)
			(xy 110.585569 -138.051269) (xy 110.502346 -137.984901) (xy 110.424316 -137.9125) (xy 110.351915 -137.83447)
			(xy 110.285547 -137.751247) (xy 110.225584 -137.663298) (xy 110.172361 -137.571113) (xy 110.126176 -137.475209)
			(xy 110.087287 -137.376121) (xy 110.055911 -137.274405) (xy 110.032225 -137.170628) (xy 110.01636 -137.065371)
			(xy 110.008405 -136.959223) (xy 107.344261 -136.959223) (xy 107.337196 -137.034345) (xy 107.321195 -137.118655)
			(xy 107.297369 -137.201096) (xy 107.265928 -137.280944) (xy 107.227148 -137.357496) (xy 107.18137 -137.430081)
			(xy 107.128997 -137.498061) (xy 107.070488 -137.560837) (xy 107.006357 -137.617858) (xy 106.937169 -137.668624)
			(xy 106.86353 -137.712688) (xy 106.78609 -137.749662) (xy 106.705527 -137.779223) (xy 106.62255 -137.801109)
			(xy 106.537888 -137.815129) (xy 106.452286 -137.82116) (xy 106.366494 -137.819148) (xy 106.281268 -137.809112)
			(xy 106.197357 -137.791139) (xy 106.115497 -137.765387) (xy 106.036408 -137.732083) (xy 105.960786 -137.691519)
			(xy 105.889294 -137.644052) (xy 105.822561 -137.590099) (xy 105.761174 -137.530135) (xy 105.705671 -137.464685)
			(xy 105.656542 -137.394326) (xy 105.614216 -137.319675) (xy 105.579067 -137.241389) (xy 105.551404 -137.160155)
			(xy 105.531468 -137.076688) (xy 105.519437 -136.99172) (xy 105.515415 -136.906) (xy 100.661724 -136.906)
			(xy 100.661227 -136.959223) (xy 100.653272 -137.065371) (xy 100.637407 -137.170628) (xy 100.613721 -137.274405)
			(xy 100.582345 -137.376121) (xy 100.543456 -137.475209) (xy 100.497271 -137.571113) (xy 100.444048 -137.663298)
			(xy 100.384085 -137.751247) (xy 100.317717 -137.83447) (xy 100.245316 -137.9125) (xy 100.167286 -137.984901)
			(xy 100.084063 -138.051269) (xy 99.996114 -138.111232) (xy 99.903929 -138.164455) (xy 99.808025 -138.21064)
			(xy 99.708937 -138.249529) (xy 99.607221 -138.280905) (xy 99.503444 -138.304591) (xy 99.398187 -138.320456)
			(xy 99.292039 -138.328411) (xy 99.185593 -138.328411) (xy 99.079445 -138.320456) (xy 98.974188 -138.304591)
			(xy 98.870411 -138.280905) (xy 98.768695 -138.249529) (xy 98.669607 -138.21064) (xy 98.573703 -138.164455)
			(xy 98.481518 -138.111232) (xy 98.393569 -138.051269) (xy 98.310346 -137.984901) (xy 98.232316 -137.9125)
			(xy 98.159915 -137.83447) (xy 98.093547 -137.751247) (xy 98.033584 -137.663298) (xy 97.980361 -137.571113)
			(xy 97.934176 -137.475209) (xy 97.895287 -137.376121) (xy 97.863911 -137.274405) (xy 97.840225 -137.170628)
			(xy 97.82436 -137.065371) (xy 97.816405 -136.959223) (xy 95.152261 -136.959223) (xy 95.145196 -137.034345)
			(xy 95.129195 -137.118655) (xy 95.105369 -137.201096) (xy 95.073928 -137.280944) (xy 95.035148 -137.357496)
			(xy 94.98937 -137.430081) (xy 94.936997 -137.498061) (xy 94.878488 -137.560837) (xy 94.814357 -137.617858)
			(xy 94.745169 -137.668624) (xy 94.67153 -137.712688) (xy 94.59409 -137.749662) (xy 94.513527 -137.779223)
			(xy 94.43055 -137.801109) (xy 94.345888 -137.815129) (xy 94.260286 -137.82116) (xy 94.174494 -137.819148)
			(xy 94.089268 -137.809112) (xy 94.005357 -137.791139) (xy 93.923497 -137.765387) (xy 93.844408 -137.732083)
			(xy 93.768786 -137.691519) (xy 93.697294 -137.644052) (xy 93.630561 -137.590099) (xy 93.569174 -137.530135)
			(xy 93.513671 -137.464685) (xy 93.464542 -137.394326) (xy 93.422216 -137.319675) (xy 93.387067 -137.241389)
			(xy 93.359404 -137.160155) (xy 93.339468 -137.076688) (xy 93.327437 -136.99172) (xy 93.323415 -136.906)
			(xy 88.469724 -136.906) (xy 88.469227 -136.959223) (xy 88.461272 -137.065371) (xy 88.445407 -137.170628)
			(xy 88.421721 -137.274405) (xy 88.390345 -137.376121) (xy 88.351456 -137.475209) (xy 88.305271 -137.571113)
			(xy 88.252048 -137.663298) (xy 88.192085 -137.751247) (xy 88.125717 -137.83447) (xy 88.053316 -137.9125)
			(xy 87.975286 -137.984901) (xy 87.892063 -138.051269) (xy 87.804114 -138.111232) (xy 87.711929 -138.164455)
			(xy 87.616025 -138.21064) (xy 87.516937 -138.249529) (xy 87.415221 -138.280905) (xy 87.311444 -138.304591)
			(xy 87.206187 -138.320456) (xy 87.100039 -138.328411) (xy 86.993593 -138.328411) (xy 86.887445 -138.320456)
			(xy 86.782188 -138.304591) (xy 86.678411 -138.280905) (xy 86.576695 -138.249529) (xy 86.477607 -138.21064)
			(xy 86.381703 -138.164455) (xy 86.289518 -138.111232) (xy 86.201569 -138.051269) (xy 86.118346 -137.984901)
			(xy 86.040316 -137.9125) (xy 85.967915 -137.83447) (xy 85.901547 -137.751247) (xy 85.841584 -137.663298)
			(xy 85.788361 -137.571113) (xy 85.742176 -137.475209) (xy 85.703287 -137.376121) (xy 85.671911 -137.274405)
			(xy 85.648225 -137.170628) (xy 85.63236 -137.065371) (xy 85.624405 -136.959223) (xy 82.960261 -136.959223)
			(xy 82.953196 -137.034345) (xy 82.937195 -137.118655) (xy 82.913369 -137.201096) (xy 82.881928 -137.280944)
			(xy 82.843148 -137.357496) (xy 82.79737 -137.430081) (xy 82.744997 -137.498061) (xy 82.686488 -137.560837)
			(xy 82.622357 -137.617858) (xy 82.553169 -137.668624) (xy 82.47953 -137.712688) (xy 82.40209 -137.749662)
			(xy 82.321527 -137.779223) (xy 82.23855 -137.801109) (xy 82.153888 -137.815129) (xy 82.068286 -137.82116)
			(xy 81.982494 -137.819148) (xy 81.897268 -137.809112) (xy 81.813357 -137.791139) (xy 81.731497 -137.765387)
			(xy 81.652408 -137.732083) (xy 81.576786 -137.691519) (xy 81.505294 -137.644052) (xy 81.438561 -137.590099)
			(xy 81.377174 -137.530135) (xy 81.321671 -137.464685) (xy 81.272542 -137.394326) (xy 81.230216 -137.319675)
			(xy 81.195067 -137.241389) (xy 81.167404 -137.160155) (xy 81.147468 -137.076688) (xy 81.135437 -136.99172)
			(xy 81.131415 -136.906) (xy 72.853804 -136.906) (xy 72.853307 -136.959223) (xy 72.845352 -137.065371)
			(xy 72.829487 -137.170628) (xy 72.805801 -137.274405) (xy 72.774425 -137.376121) (xy 72.735536 -137.475209)
			(xy 72.689351 -137.571113) (xy 72.636128 -137.663298) (xy 72.576165 -137.751247) (xy 72.509797 -137.83447)
			(xy 72.437396 -137.9125) (xy 72.359366 -137.984901) (xy 72.276143 -138.051269) (xy 72.188194 -138.111232)
			(xy 72.096009 -138.164455) (xy 72.000105 -138.21064) (xy 71.901017 -138.249529) (xy 71.799301 -138.280905)
			(xy 71.695524 -138.304591) (xy 71.590267 -138.320456) (xy 71.484119 -138.328411) (xy 71.377673 -138.328411)
			(xy 71.271525 -138.320456) (xy 71.166268 -138.304591) (xy 71.062491 -138.280905) (xy 70.960775 -138.249529)
			(xy 70.861687 -138.21064) (xy 70.765783 -138.164455) (xy 70.673598 -138.111232) (xy 70.585649 -138.051269)
			(xy 70.502426 -137.984901) (xy 70.424396 -137.9125) (xy 70.351995 -137.83447) (xy 70.285627 -137.751247)
			(xy 70.225664 -137.663298) (xy 70.172441 -137.571113) (xy 70.126256 -137.475209) (xy 70.087367 -137.376121)
			(xy 70.055991 -137.274405) (xy 70.032305 -137.170628) (xy 70.01644 -137.065371) (xy 70.008485 -136.959223)
			(xy 67.344341 -136.959223) (xy 67.337276 -137.034345) (xy 67.321275 -137.118655) (xy 67.297449 -137.201096)
			(xy 67.266008 -137.280944) (xy 67.227228 -137.357496) (xy 67.18145 -137.430081) (xy 67.129077 -137.498061)
			(xy 67.070568 -137.560837) (xy 67.006437 -137.617858) (xy 66.937249 -137.668624) (xy 66.86361 -137.712688)
			(xy 66.78617 -137.749662) (xy 66.705607 -137.779223) (xy 66.62263 -137.801109) (xy 66.537968 -137.815129)
			(xy 66.452366 -137.82116) (xy 66.366574 -137.819148) (xy 66.281348 -137.809112) (xy 66.197437 -137.791139)
			(xy 66.115577 -137.765387) (xy 66.036488 -137.732083) (xy 65.960866 -137.691519) (xy 65.889374 -137.644052)
			(xy 65.822641 -137.590099) (xy 65.761254 -137.530135) (xy 65.705751 -137.464685) (xy 65.656622 -137.394326)
			(xy 65.614296 -137.319675) (xy 65.579147 -137.241389) (xy 65.551484 -137.160155) (xy 65.531548 -137.076688)
			(xy 65.519517 -136.99172) (xy 65.515495 -136.906) (xy 60.661804 -136.906) (xy 60.661307 -136.959223)
			(xy 60.653352 -137.065371) (xy 60.637487 -137.170628) (xy 60.613801 -137.274405) (xy 60.582425 -137.376121)
			(xy 60.543536 -137.475209) (xy 60.497351 -137.571113) (xy 60.444128 -137.663298) (xy 60.384165 -137.751247)
			(xy 60.317797 -137.83447) (xy 60.245396 -137.9125) (xy 60.167366 -137.984901) (xy 60.084143 -138.051269)
			(xy 59.996194 -138.111232) (xy 59.904009 -138.164455) (xy 59.808105 -138.21064) (xy 59.709017 -138.249529)
			(xy 59.607301 -138.280905) (xy 59.503524 -138.304591) (xy 59.398267 -138.320456) (xy 59.292119 -138.328411)
			(xy 59.185673 -138.328411) (xy 59.079525 -138.320456) (xy 58.974268 -138.304591) (xy 58.870491 -138.280905)
			(xy 58.768775 -138.249529) (xy 58.669687 -138.21064) (xy 58.573783 -138.164455) (xy 58.481598 -138.111232)
			(xy 58.393649 -138.051269) (xy 58.310426 -137.984901) (xy 58.232396 -137.9125) (xy 58.159995 -137.83447)
			(xy 58.093627 -137.751247) (xy 58.033664 -137.663298) (xy 57.980441 -137.571113) (xy 57.934256 -137.475209)
			(xy 57.895367 -137.376121) (xy 57.863991 -137.274405) (xy 57.840305 -137.170628) (xy 57.82444 -137.065371)
			(xy 57.816485 -136.959223) (xy 55.152341 -136.959223) (xy 55.145276 -137.034345) (xy 55.129275 -137.118655)
			(xy 55.105449 -137.201096) (xy 55.074008 -137.280944) (xy 55.035228 -137.357496) (xy 54.98945 -137.430081)
			(xy 54.937077 -137.498061) (xy 54.878568 -137.560837) (xy 54.814437 -137.617858) (xy 54.745249 -137.668624)
			(xy 54.67161 -137.712688) (xy 54.59417 -137.749662) (xy 54.513607 -137.779223) (xy 54.43063 -137.801109)
			(xy 54.345968 -137.815129) (xy 54.260366 -137.82116) (xy 54.174574 -137.819148) (xy 54.089348 -137.809112)
			(xy 54.005437 -137.791139) (xy 53.923577 -137.765387) (xy 53.844488 -137.732083) (xy 53.768866 -137.691519)
			(xy 53.697374 -137.644052) (xy 53.630641 -137.590099) (xy 53.569254 -137.530135) (xy 53.513751 -137.464685)
			(xy 53.464622 -137.394326) (xy 53.422296 -137.319675) (xy 53.387147 -137.241389) (xy 53.359484 -137.160155)
			(xy 53.339548 -137.076688) (xy 53.327517 -136.99172) (xy 53.323495 -136.906) (xy 48.469804 -136.906)
			(xy 48.469307 -136.959223) (xy 48.461352 -137.065371) (xy 48.445487 -137.170628) (xy 48.421801 -137.274405)
			(xy 48.390425 -137.376121) (xy 48.351536 -137.475209) (xy 48.305351 -137.571113) (xy 48.252128 -137.663298)
			(xy 48.192165 -137.751247) (xy 48.125797 -137.83447) (xy 48.053396 -137.9125) (xy 47.975366 -137.984901)
			(xy 47.892143 -138.051269) (xy 47.804194 -138.111232) (xy 47.712009 -138.164455) (xy 47.616105 -138.21064)
			(xy 47.517017 -138.249529) (xy 47.415301 -138.280905) (xy 47.311524 -138.304591) (xy 47.206267 -138.320456)
			(xy 47.100119 -138.328411) (xy 46.993673 -138.328411) (xy 46.887525 -138.320456) (xy 46.782268 -138.304591)
			(xy 46.678491 -138.280905) (xy 46.576775 -138.249529) (xy 46.477687 -138.21064) (xy 46.381783 -138.164455)
			(xy 46.289598 -138.111232) (xy 46.201649 -138.051269) (xy 46.118426 -137.984901) (xy 46.040396 -137.9125)
			(xy 45.967995 -137.83447) (xy 45.901627 -137.751247) (xy 45.841664 -137.663298) (xy 45.788441 -137.571113)
			(xy 45.742256 -137.475209) (xy 45.703367 -137.376121) (xy 45.671991 -137.274405) (xy 45.648305 -137.170628)
			(xy 45.63244 -137.065371) (xy 45.624485 -136.959223) (xy 42.960341 -136.959223) (xy 42.953276 -137.034345)
			(xy 42.937275 -137.118655) (xy 42.913449 -137.201096) (xy 42.882008 -137.280944) (xy 42.843228 -137.357496)
			(xy 42.79745 -137.430081) (xy 42.745077 -137.498061) (xy 42.686568 -137.560837) (xy 42.622437 -137.617858)
			(xy 42.553249 -137.668624) (xy 42.47961 -137.712688) (xy 42.40217 -137.749662) (xy 42.321607 -137.779223)
			(xy 42.23863 -137.801109) (xy 42.153968 -137.815129) (xy 42.068366 -137.82116) (xy 41.982574 -137.819148)
			(xy 41.897348 -137.809112) (xy 41.813437 -137.791139) (xy 41.731577 -137.765387) (xy 41.652488 -137.732083)
			(xy 41.576866 -137.691519) (xy 41.505374 -137.644052) (xy 41.438641 -137.590099) (xy 41.377254 -137.530135)
			(xy 41.321751 -137.464685) (xy 41.272622 -137.394326) (xy 41.230296 -137.319675) (xy 41.195147 -137.241389)
			(xy 41.167484 -137.160155) (xy 41.147548 -137.076688) (xy 41.135517 -136.99172) (xy 41.131495 -136.906)
			(xy 37.531802 -136.906) (xy 37.531802 -141.742414) (xy 37.531945 -141.747162) (xy 37.53374 -141.756489)
			(xy 37.535358 -141.760956) (xy 37.542978 -141.780006) (xy 37.542978 -141.78026) (xy 37.544736 -141.784826)
			(xy 37.546662 -141.794419) (xy 37.546788 -141.79931) (xy 37.546788 -143.547592) (xy 37.554408 -143.566388)
			(xy 37.561774 -143.5735) (xy 38.974014 -144.98574) (xy 38.981411 -144.992591) (xy 39.000009 -145.000329)
			(xy 39.010082 -145.000726)
		)
		(stroke
			(width 0)
			(type solid)
		)
		(fill yes)
		(layer "In2.Cu")
		(net "P52V_HS_FILTER")
	)
	(gr_poly
		(pts
			(xy 77.809598 -73.184004) (xy 77.819668 -73.183581) (xy 77.838274 -73.175868) (xy 77.845666 -73.169018)
			(xy 85.124798 -65.889886) (xy 85.132192 -65.88303) (xy 85.150791 -65.875281) (xy 85.160866 -65.8749)
			(xy 176.828958 -65.8749) (xy 176.839703 -65.874413) (xy 176.859296 -65.865586) (xy 176.866804 -65.857882)
			(xy 176.913794 -65.805304) (xy 176.920398 -65.788032) (xy 176.920398 -65.77838) (xy 176.920398 -65.776348)
			(xy 176.920398 -65.77584) (xy 176.920547 -65.754915) (xy 176.92258 -65.713115) (xy 176.924462 -65.692274)
			(xy 176.924716 -65.685924) (xy 176.924208 -65.661286) (xy 176.924712 -65.618938) (xy 176.932763 -65.534624)
			(xy 176.948792 -65.451458) (xy 176.972653 -65.370191) (xy 177.004132 -65.291561) (xy 177.042943 -65.21628)
			(xy 177.088733 -65.145028) (xy 177.141089 -65.078452) (xy 177.199537 -65.017154) (xy 177.263547 -64.961689)
			(xy 177.332539 -64.91256) (xy 177.405889 -64.870211) (xy 177.482932 -64.835027) (xy 177.562971 -64.807325)
			(xy 177.64528 -64.787357) (xy 177.729115 -64.775304) (xy 177.813716 -64.771274) (xy 177.898317 -64.775304)
			(xy 177.982152 -64.787357) (xy 178.064461 -64.807325) (xy 178.1445 -64.835027) (xy 178.221543 -64.870211)
			(xy 178.294893 -64.91256) (xy 178.363885 -64.961689) (xy 178.427895 -65.017154) (xy 178.486343 -65.078452)
			(xy 178.538699 -65.145028) (xy 178.584489 -65.21628) (xy 178.6233 -65.291561) (xy 178.654779 -65.370191)
			(xy 178.67864 -65.451458) (xy 178.694669 -65.534624) (xy 178.70272 -65.618938) (xy 178.703224 -65.661286)
			(xy 178.703134 -65.681443) (xy 178.701357 -65.721718) (xy 178.699668 -65.741804) (xy 178.699414 -65.7479)
			(xy 178.699922 -65.77076) (xy 178.699922 -65.780158) (xy 178.706526 -65.79743) (xy 178.760628 -65.857882)
			(xy 178.768193 -65.865502) (xy 178.787753 -65.874297) (xy 178.798474 -65.8749) (xy 181.244748 -65.8749)
			(xy 181.252481 -65.874639) (xy 181.267233 -65.869996) (xy 181.273704 -65.865756) (xy 181.280054 -65.861184)
			(xy 181.289452 -65.848992) (xy 181.292246 -65.841626) (xy 181.325266 -65.752472) (xy 181.328452 -65.742562)
			(xy 181.327403 -65.721795) (xy 181.318161 -65.703168) (xy 181.310534 -65.696084) (xy 181.278502 -65.66797)
			(xy 181.21939 -65.606568) (xy 181.166422 -65.539792) (xy 181.120084 -65.468257) (xy 181.080801 -65.392616)
			(xy 181.048933 -65.313566) (xy 181.024773 -65.231829) (xy 181.008543 -65.148156) (xy 181.00039 -65.063314)
			(xy 180.999892 -65.020698) (xy 181.000396 -64.97835) (xy 181.008447 -64.894036) (xy 181.024476 -64.81087)
			(xy 181.048337 -64.729603) (xy 181.079816 -64.650973) (xy 181.118627 -64.575692) (xy 181.164417 -64.50444)
			(xy 181.216773 -64.437864) (xy 181.275221 -64.376566) (xy 181.339231 -64.321101) (xy 181.408223 -64.271972)
			(xy 181.481573 -64.229623) (xy 181.558616 -64.194439) (xy 181.638655 -64.166737) (xy 181.720964 -64.146769)
			(xy 181.804799 -64.134716) (xy 181.8894 -64.130686) (xy 181.974001 -64.134716) (xy 182.057836 -64.146769)
			(xy 182.140145 -64.166737) (xy 182.220184 -64.194439) (xy 182.297227 -64.229623) (xy 182.370577 -64.271972)
			(xy 182.439569 -64.321101) (xy 182.503579 -64.376566) (xy 182.562027 -64.437864) (xy 182.614383 -64.50444)
			(xy 182.660173 -64.575692) (xy 182.698984 -64.650973) (xy 182.730463 -64.729603) (xy 182.754324 -64.81087)
			(xy 182.770353 -64.894036) (xy 182.778404 -64.97835) (xy 182.778908 -65.020698) (xy 182.778407 -65.063314)
			(xy 182.770255 -65.148156) (xy 182.754024 -65.231828) (xy 182.729864 -65.313565) (xy 182.697997 -65.392615)
			(xy 182.658714 -65.468255) (xy 182.612376 -65.539791) (xy 182.559408 -65.606566) (xy 182.500296 -65.667968)
			(xy 182.468266 -65.696084) (xy 182.460718 -65.703214) (xy 182.451572 -65.721835) (xy 182.450465 -65.74255)
			(xy 182.453534 -65.752472) (xy 182.486554 -65.841626) (xy 182.489483 -65.848798) (xy 182.498927 -65.861069)
			(xy 182.505096 -65.865756) (xy 182.511596 -65.869939) (xy 182.526329 -65.874594) (xy 182.534052 -65.8749)
			(xy 199.746362 -65.8749) (xy 199.77481 -65.849754) (xy 199.77735 -65.83045) (xy 199.783209 -65.787971)
			(xy 199.802048 -65.704309) (xy 199.828849 -65.622848) (xy 199.863366 -65.544345) (xy 199.905277 -65.469527)
			(xy 199.954193 -65.399089) (xy 200.00966 -65.333686) (xy 200.071163 -65.273924) (xy 200.138132 -65.220358)
			(xy 200.209945 -65.173485) (xy 200.285936 -65.13374) (xy 200.365398 -65.101492) (xy 200.447595 -65.07704)
			(xy 200.531763 -65.060612) (xy 200.617122 -65.052359) (xy 200.702878 -65.052359) (xy 200.788237 -65.060612)
			(xy 200.872405 -65.07704) (xy 200.954602 -65.101492) (xy 201.034064 -65.13374) (xy 201.110055 -65.173485)
			(xy 201.181868 -65.220358) (xy 201.248837 -65.273924) (xy 201.31034 -65.333686) (xy 201.365807 -65.399089)
			(xy 201.414723 -65.469527) (xy 201.456634 -65.544345) (xy 201.491151 -65.622848) (xy 201.517952 -65.704309)
			(xy 201.536791 -65.787971) (xy 201.54265 -65.83045) (xy 201.54519 -65.849754) (xy 201.573638 -65.8749)
			(xy 201.739246 -65.8749) (xy 201.768202 -65.848992) (xy 201.770234 -65.829434) (xy 201.77532 -65.786263)
			(xy 201.792837 -65.701115) (xy 201.818579 -65.618081) (xy 201.852299 -65.537956) (xy 201.893677 -65.461502)
			(xy 201.942316 -65.389451) (xy 201.997753 -65.322489) (xy 202.059459 -65.261256) (xy 202.126846 -65.206335)
			(xy 202.199269 -65.158251) (xy 202.276038 -65.117463) (xy 202.356421 -65.08436) (xy 202.43965 -65.059258)
			(xy 202.524931 -65.042396) (xy 202.61145 -65.033935) (xy 202.654916 -65.033398) (xy 202.694774 -65.033843)
			(xy 202.774169 -65.040975) (xy 202.852609 -65.055181) (xy 202.929463 -65.076346) (xy 203.004115 -65.104302)
			(xy 203.075968 -65.138823) (xy 203.144445 -65.179633) (xy 203.208996 -65.226405) (xy 203.269105 -65.278764)
			(xy 203.297028 -65.30721) (xy 203.304394 -65.31483) (xy 203.323444 -65.322958) (xy 203.417678 -65.322704)
			(xy 203.436728 -65.314576) (xy 203.44384 -65.306956) (xy 203.471773 -65.278173) (xy 203.532012 -65.225207)
			(xy 203.596775 -65.177881) (xy 203.665537 -65.136579) (xy 203.737739 -65.101636) (xy 203.812794 -65.073337)
			(xy 203.890092 -65.051911) (xy 203.969006 -65.037532) (xy 204.048894 -65.030318) (xy 204.089 -65.029842)
			(xy 204.131576 -65.030341) (xy 204.216338 -65.038479) (xy 204.299935 -65.05468) (xy 204.381601 -65.078797)
			(xy 204.460588 -65.110608) (xy 204.536173 -65.149821) (xy 204.607665 -65.196079) (xy 204.674408 -65.248958)
			(xy 204.735793 -65.307974) (xy 204.763878 -65.339976) (xy 204.771244 -65.348612) (xy 204.791818 -65.357756)
			(xy 204.892656 -65.356232) (xy 204.912976 -65.346326) (xy 204.920088 -65.337436) (xy 204.948188 -65.303391)
			(xy 205.010086 -65.240443) (xy 205.077914 -65.183937) (xy 205.151007 -65.134427) (xy 205.228644 -65.092403)
			(xy 205.310063 -65.058276) (xy 205.394462 -65.032383) (xy 205.481012 -65.014977) (xy 205.568859 -65.006232)
			(xy 205.613 -65.005712) (xy 205.654566 -65.006194) (xy 205.737334 -65.01395) (xy 205.819018 -65.029396)
			(xy 205.898904 -65.052396) (xy 205.976296 -65.082749) (xy 206.050518 -65.120192) (xy 206.120922 -65.164396)
			(xy 206.186895 -65.214976) (xy 206.247861 -65.271492) (xy 206.303287 -65.333449) (xy 206.35269 -65.400308)
			(xy 206.39564 -65.471485) (xy 206.431761 -65.546359) (xy 206.460738 -65.624276) (xy 206.482319 -65.704557)
			(xy 206.496315 -65.786502) (xy 206.499968 -65.82791) (xy 206.501088 -65.837368) (xy 206.509358 -65.854509)
			(xy 206.523299 -65.867465) (xy 206.541 -65.874457) (xy 206.550514 -65.8749) (xy 208.931002 -65.8749)
			(xy 208.932272 -65.8749) (xy 208.94218 -65.874184) (xy 208.960355 -65.866211) (xy 208.974155 -65.851947)
			(xy 208.978246 -65.842896) (xy 208.99379 -65.805254) (xy 209.030819 -65.732712) (xy 209.074327 -65.663861)
			(xy 209.12395 -65.599277) (xy 209.179272 -65.539503) (xy 209.239829 -65.485039) (xy 209.305113 -65.436342)
			(xy 209.374578 -65.39382) (xy 209.44764 -65.357829) (xy 209.523688 -65.328672) (xy 209.602084 -65.306592)
			(xy 209.682171 -65.291774) (xy 209.763277 -65.284343) (xy 209.804 -65.283842) (xy 209.84376 -65.284283)
			(xy 209.922961 -65.291383) (xy 210.001212 -65.305526) (xy 210.077888 -65.3266) (xy 210.152376 -65.354436)
			(xy 210.224081 -65.388812) (xy 210.292431 -65.429452) (xy 210.356878 -65.476033) (xy 210.387184 -65.501774)
			(xy 210.394416 -65.507521) (xy 210.411734 -65.513908) (xy 210.420966 -65.51422) (xy 210.44154 -65.513966)
			(xy 210.446088 -65.513845) (xy 210.455033 -65.512188) (xy 210.45932 -65.510664) (xy 210.483958 -65.501266)
			(xy 210.490562 -65.495424) (xy 210.520886 -65.469682) (xy 210.58537 -65.423101) (xy 210.653754 -65.38246)
			(xy 210.725491 -65.348083) (xy 210.800009 -65.320245) (xy 210.876715 -65.299168) (xy 210.954995 -65.285019)
			(xy 211.034226 -65.277911) (xy 211.074 -65.277492) (xy 211.119133 -65.278043) (xy 211.208935 -65.287183)
			(xy 211.297347 -65.30538) (xy 211.38346 -65.332445) (xy 211.466385 -65.3681) (xy 211.545268 -65.411978)
			(xy 211.619298 -65.463626) (xy 211.653882 -65.49263) (xy 211.66074 -65.498472) (xy 211.685378 -65.507616)
			(xy 211.689664 -65.509146) (xy 211.698609 -65.510814) (xy 211.703158 -65.510918) (xy 211.714842 -65.510918)
			(xy 211.71939 -65.510796) (xy 211.728335 -65.509138) (xy 211.732622 -65.507616) (xy 211.75726 -65.498472)
			(xy 211.764118 -65.49263) (xy 211.798702 -65.463631) (xy 211.872752 -65.412023) (xy 211.951645 -65.368174)
			(xy 212.03457 -65.332533) (xy 212.120675 -65.305467) (xy 212.209078 -65.287253) (xy 212.29887 -65.278079)
			(xy 212.344 -65.277492) (xy 212.344254 -65.277492) (xy 212.384105 -65.277935) (xy 212.463487 -65.285066)
			(xy 212.541913 -65.299274) (xy 212.618751 -65.320445) (xy 212.693386 -65.34841) (xy 212.765218 -65.382944)
			(xy 212.799676 -65.402968) (xy 212.814662 -65.411858) (xy 212.84946 -65.40754) (xy 213.599014 -64.657986)
			(xy 213.605868 -64.650591) (xy 213.61361 -64.631992) (xy 213.614 -64.621918) (xy 213.614 -47.900082)
			(xy 213.613573 -47.890013) (xy 213.605854 -47.871414) (xy 213.599014 -47.864014) (xy 212.358986 -46.623986)
			(xy 212.351874 -46.61662) (xy 212.333078 -46.609) (xy 203.475082 -46.609) (xy 203.465013 -46.608573)
			(xy 203.446414 -46.600854) (xy 203.439014 -46.594014) (xy 202.75169 -45.90669) (xy 202.744835 -45.899295)
			(xy 202.73709 -45.880696) (xy 202.736704 -45.870622) (xy 202.736704 -22.393148) (xy 202.736271 -22.383082)
			(xy 202.728544 -22.364491) (xy 202.721718 -22.35708) (xy 200.70445 -20.339812) (xy 200.697338 -20.332446)
			(xy 200.678542 -20.324826) (xy 165.273482 -20.324826) (xy 165.263413 -20.3244) (xy 165.24481 -20.316684)
			(xy 165.237414 -20.30984) (xy 163.463986 -18.536412) (xy 163.457128 -18.529018) (xy 163.449376 -18.510419)
			(xy 163.449 -18.500344) (xy 163.449 -2.510282) (xy 163.448573 -2.500213) (xy 163.440854 -2.481614)
			(xy 163.434014 -2.474214) (xy 162.879786 -1.919986) (xy 162.872391 -1.913132) (xy 162.853792 -1.90539)
			(xy 162.843718 -1.905) (xy 37.354764 -1.905) (xy 37.344697 -1.90543) (xy 37.326102 -1.913153) (xy 37.318696 -1.919986)
			(xy 35.859466 -3.379216) (xy 35.8521 -3.386328) (xy 35.84448 -3.405124) (xy 35.84448 -12.111916)
			(xy 101.729784 -12.111916) (xy 101.729784 -11.888044) (xy 101.737774 -11.664316) (xy 101.753745 -11.441015)
			(xy 101.777676 -11.218426) (xy 101.809536 -10.996833) (xy 101.849285 -10.776519) (xy 101.896872 -10.557764)
			(xy 101.952237 -10.340846) (xy 102.015309 -10.126043) (xy 102.086007 -9.913629) (xy 102.164242 -9.703872)
			(xy 102.249914 -9.497042) (xy 102.342914 -9.293402) (xy 102.443122 -9.09321) (xy 102.550412 -8.896723)
			(xy 102.664647 -8.70419) (xy 102.785681 -8.515858) (xy 102.91336 -8.331965) (xy 103.047521 -8.152747)
			(xy 103.187993 -7.978431) (xy 103.334598 -7.809241) (xy 103.487148 -7.64539) (xy 103.645449 -7.487089)
			(xy 103.809299 -7.334539) (xy 103.97849 -7.187935) (xy 104.152805 -7.047462) (xy 104.332024 -6.913301)
			(xy 104.515916 -6.785622) (xy 104.704249 -6.664588) (xy 104.896781 -6.550353) (xy 105.093268 -6.443063)
			(xy 105.29346 -6.342855) (xy 105.4971 -6.249855) (xy 105.70393 -6.164183) (xy 105.913687 -6.085948)
			(xy 106.126102 -6.015249) (xy 106.340905 -5.952178) (xy 106.557822 -5.896813) (xy 106.776577 -5.849225)
			(xy 106.996891 -5.809476) (xy 107.218484 -5.777616) (xy 107.441073 -5.753685) (xy 107.664374 -5.737714)
			(xy 107.888102 -5.729724) (xy 108.000038 -5.729224) (xy 129.999994 -5.729224) (xy 130.11193 -5.729732)
			(xy 130.335658 -5.737722) (xy 130.558959 -5.753693) (xy 130.781547 -5.777624) (xy 131.003139 -5.809484)
			(xy 131.223453 -5.849233) (xy 131.442208 -5.896821) (xy 131.659125 -5.952186) (xy 131.873928 -6.015258)
			(xy 132.086342 -6.085956) (xy 132.296098 -6.164191) (xy 132.502928 -6.249863) (xy 132.706568 -6.342862)
			(xy 132.906759 -6.443071) (xy 133.103246 -6.550361) (xy 133.295778 -6.664596) (xy 133.484111 -6.78563)
			(xy 133.668003 -6.913308) (xy 133.847221 -7.047469) (xy 134.021536 -7.187942) (xy 134.190726 -7.334546)
			(xy 134.354576 -7.487096) (xy 134.512877 -7.645397) (xy 134.665427 -7.809247) (xy 134.812031 -7.978437)
			(xy 134.952503 -8.152752) (xy 135.086664 -8.33197) (xy 135.214343 -8.515863) (xy 135.335376 -8.704195)
			(xy 135.449611 -8.896727) (xy 135.556901 -9.093214) (xy 135.657109 -9.293406) (xy 135.750109 -9.497046)
			(xy 135.83578 -9.703876) (xy 135.914015 -9.913632) (xy 135.984714 -10.126046) (xy 136.047785 -10.340849)
			(xy 136.10315 -10.557766) (xy 136.150737 -10.776521) (xy 136.190486 -10.996835) (xy 136.222346 -11.218427)
			(xy 136.246277 -11.441015) (xy 136.262248 -11.664316) (xy 136.270238 -11.888044) (xy 136.270238 -12.111916)
			(xy 136.262248 -12.335644) (xy 136.246277 -12.558945) (xy 136.222346 -12.781533) (xy 136.190486 -13.003125)
			(xy 136.150737 -13.223439) (xy 136.10315 -13.442194) (xy 136.047785 -13.659111) (xy 135.984714 -13.873914)
			(xy 135.914015 -14.086328) (xy 135.83578 -14.296084) (xy 135.750109 -14.502914) (xy 135.657109 -14.706554)
			(xy 135.556901 -14.906746) (xy 135.449611 -15.103233) (xy 135.335376 -15.295765) (xy 135.214343 -15.484097)
			(xy 135.086664 -15.66799) (xy 134.952503 -15.847208) (xy 134.812031 -16.021523) (xy 134.665427 -16.190713)
			(xy 134.512877 -16.354563) (xy 134.354576 -16.512864) (xy 134.190726 -16.665414) (xy 134.021536 -16.812018)
			(xy 133.847221 -16.952491) (xy 133.668003 -17.086652) (xy 133.484111 -17.21433) (xy 133.295778 -17.335364)
			(xy 133.103246 -17.449599) (xy 132.906759 -17.556889) (xy 132.706568 -17.657098) (xy 132.502928 -17.750097)
			(xy 132.296098 -17.835769) (xy 132.086342 -17.914004) (xy 131.873928 -17.984702) (xy 131.659125 -18.047774)
			(xy 131.442208 -18.103139) (xy 131.223453 -18.150727) (xy 131.003139 -18.190476) (xy 130.781547 -18.222336)
			(xy 130.558959 -18.246267) (xy 130.335658 -18.262238) (xy 130.11193 -18.270228) (xy 129.999994 -18.270728)
			(xy 108.000038 -18.270728) (xy 107.888102 -18.270236) (xy 107.664374 -18.262246) (xy 107.441073 -18.246275)
			(xy 107.218484 -18.222344) (xy 106.996891 -18.190484) (xy 106.776577 -18.150735) (xy 106.557822 -18.103147)
			(xy 106.340905 -18.047782) (xy 106.126102 -17.984711) (xy 105.913687 -17.914012) (xy 105.70393 -17.835777)
			(xy 105.4971 -17.750105) (xy 105.29346 -17.657105) (xy 105.093268 -17.556897) (xy 104.896781 -17.449607)
			(xy 104.704249 -17.335372) (xy 104.515916 -17.214338) (xy 104.332024 -17.086659) (xy 104.152805 -16.952498)
			(xy 103.97849 -16.812025) (xy 103.809299 -16.665421) (xy 103.645449 -16.512871) (xy 103.487148 -16.35457)
			(xy 103.334598 -16.190719) (xy 103.187993 -16.021529) (xy 103.047521 -15.847213) (xy 102.91336 -15.667995)
			(xy 102.785681 -15.484102) (xy 102.664647 -15.29577) (xy 102.550412 -15.103237) (xy 102.443122 -14.90675)
			(xy 102.342914 -14.706558) (xy 102.249914 -14.502918) (xy 102.164242 -14.296088) (xy 102.086007 -14.086331)
			(xy 102.015309 -13.873917) (xy 101.952237 -13.659114) (xy 101.896872 -13.442196) (xy 101.849285 -13.223441)
			(xy 101.809536 -13.003127) (xy 101.777676 -12.781534) (xy 101.753745 -12.558945) (xy 101.737774 -12.335644)
			(xy 101.729784 -12.111916) (xy 35.84448 -12.111916) (xy 35.84448 -25.59157) (xy 42.354235 -25.59157)
			(xy 42.354235 -25.46243) (xy 42.362185 -25.333535) (xy 42.378055 -25.205375) (xy 42.401784 -25.078434)
			(xy 42.433283 -24.953195) (xy 42.472432 -24.830132) (xy 42.519083 -24.709713) (xy 42.573058 -24.592394)
			(xy 42.634153 -24.47862) (xy 42.702136 -24.368823) (xy 42.77675 -24.26342) (xy 42.857711 -24.16281)
			(xy 42.944711 -24.067375) (xy 43.037422 -23.977476) (xy 43.135492 -23.893455) (xy 43.238547 -23.815631)
			(xy 43.346198 -23.744299) (xy 43.458037 -23.679729) (xy 43.573638 -23.622167) (xy 43.692563 -23.57183)
			(xy 43.814362 -23.52891) (xy 43.938572 -23.493569) (xy 44.064721 -23.465942) (xy 44.192333 -23.446133)
			(xy 44.320922 -23.434217) (xy 44.45 -23.430241) (xy 44.579078 -23.434217) (xy 44.707667 -23.446133)
			(xy 44.835279 -23.465942) (xy 44.961428 -23.493569) (xy 45.085638 -23.52891) (xy 45.207437 -23.57183)
			(xy 45.326362 -23.622167) (xy 45.441963 -23.679729) (xy 45.553802 -23.744299) (xy 45.661453 -23.815631)
			(xy 45.764508 -23.893455) (xy 45.862578 -23.977476) (xy 45.955289 -24.067375) (xy 46.042289 -24.16281)
			(xy 46.12325 -24.26342) (xy 46.197864 -24.368823) (xy 46.265847 -24.47862) (xy 46.326942 -24.592394)
			(xy 46.380917 -24.709713) (xy 46.427568 -24.830132) (xy 46.466717 -24.953195) (xy 46.498216 -25.078434)
			(xy 46.521945 -25.205375) (xy 46.537815 -25.333535) (xy 46.545765 -25.46243) (xy 46.546262 -25.527)
			(xy 46.545765 -25.59157) (xy 46.537815 -25.720465) (xy 46.521945 -25.848625) (xy 46.498216 -25.975566)
			(xy 46.466717 -26.100805) (xy 46.427568 -26.223868) (xy 46.380917 -26.344287) (xy 46.326942 -26.461606)
			(xy 46.265847 -26.57538) (xy 46.197864 -26.685177) (xy 46.12325 -26.79058) (xy 46.042289 -26.89119)
			(xy 45.955289 -26.986625) (xy 45.862578 -27.076524) (xy 45.764508 -27.160545) (xy 45.661453 -27.238369)
			(xy 45.553802 -27.309701) (xy 45.441963 -27.374271) (xy 45.326362 -27.431833) (xy 45.207437 -27.48217)
			(xy 45.085638 -27.52509) (xy 44.961428 -27.560431) (xy 44.835279 -27.588058) (xy 44.707667 -27.607867)
			(xy 44.579078 -27.619783) (xy 44.45 -27.62376) (xy 44.320922 -27.619783) (xy 44.192333 -27.607867)
			(xy 44.064721 -27.588058) (xy 43.938572 -27.560431) (xy 43.814362 -27.52509) (xy 43.692563 -27.48217)
			(xy 43.573638 -27.431833) (xy 43.458037 -27.374271) (xy 43.346198 -27.309701) (xy 43.238547 -27.238369)
			(xy 43.135492 -27.160545) (xy 43.037422 -27.076524) (xy 42.944711 -26.986625) (xy 42.857711 -26.89119)
			(xy 42.77675 -26.79058) (xy 42.702136 -26.685177) (xy 42.634153 -26.57538) (xy 42.573058 -26.461606)
			(xy 42.519083 -26.344287) (xy 42.472432 -26.223868) (xy 42.433283 -26.100805) (xy 42.401784 -25.975566)
			(xy 42.378055 -25.848625) (xy 42.362185 -25.720465) (xy 42.354235 -25.59157) (xy 35.84448 -25.59157)
			(xy 35.84448 -30.559756) (xy 35.844913 -30.569822) (xy 35.852639 -30.588414) (xy 35.859466 -30.595824)
			(xy 38.292117 -33.028475) (xy 59.423804 -33.028475) (xy 59.423804 -32.851505) (xy 59.431858 -32.674717)
			(xy 59.447951 -32.49848) (xy 59.472049 -32.323157) (xy 59.504101 -32.149113) (xy 59.544042 -31.976709)
			(xy 59.591788 -31.806301) (xy 59.647241 -31.638242) (xy 59.710285 -31.472882) (xy 59.78079 -31.310562)
			(xy 59.85861 -31.15162) (xy 59.943584 -30.996384) (xy 60.035535 -30.845177) (xy 60.134273 -30.698312)
			(xy 60.239593 -30.556092) (xy 60.351278 -30.418814) (xy 60.469094 -30.286762) (xy 60.592799 -30.160208)
			(xy 60.722135 -30.039416) (xy 60.856836 -29.924636) (xy 60.996621 -29.816106) (xy 61.1412 -29.71405)
			(xy 61.290275 -29.618681) (xy 61.443536 -29.530196) (xy 61.600666 -29.448778) (xy 61.761339 -29.374596)
			(xy 61.925221 -29.307804) (xy 62.091974 -29.24854) (xy 62.261251 -29.196927) (xy 62.432702 -29.153072)
			(xy 62.605971 -29.117066) (xy 62.780699 -29.088984) (xy 62.956525 -29.068884) (xy 63.133083 -29.056807)
			(xy 63.310008 -29.052779) (xy 63.486933 -29.056807) (xy 63.663491 -29.068884) (xy 63.839317 -29.088984)
			(xy 64.014045 -29.117066) (xy 64.187314 -29.153072) (xy 64.358765 -29.196927) (xy 64.528042 -29.24854)
			(xy 64.694795 -29.307804) (xy 64.858677 -29.374596) (xy 65.01935 -29.448778) (xy 65.17648 -29.530196)
			(xy 65.329741 -29.618681) (xy 65.478816 -29.71405) (xy 65.623395 -29.816106) (xy 65.76318 -29.924636)
			(xy 65.897881 -30.039416) (xy 66.027217 -30.160208) (xy 66.150922 -30.286762) (xy 66.268738 -30.418814)
			(xy 66.380423 -30.556092) (xy 66.485743 -30.698312) (xy 66.584481 -30.845177) (xy 66.676432 -30.996384)
			(xy 66.761406 -31.15162) (xy 66.839226 -31.310562) (xy 66.909731 -31.472882) (xy 66.972775 -31.638242)
			(xy 67.028228 -31.806301) (xy 67.075974 -31.976709) (xy 67.115915 -32.149113) (xy 67.147967 -32.323157)
			(xy 67.172065 -32.49848) (xy 67.188158 -32.674717) (xy 67.196212 -32.851505) (xy 67.196716 -32.93999)
			(xy 67.196212 -33.028475) (xy 67.188158 -33.205263) (xy 67.172065 -33.3815) (xy 67.147967 -33.556823)
			(xy 67.115915 -33.730867) (xy 67.075974 -33.903271) (xy 67.028228 -34.073679) (xy 66.972775 -34.241738)
			(xy 66.909731 -34.407098) (xy 66.839226 -34.569418) (xy 66.761406 -34.72836) (xy 66.676432 -34.883596)
			(xy 66.584481 -35.034803) (xy 66.485743 -35.181668) (xy 66.380423 -35.323888) (xy 66.268738 -35.461166)
			(xy 66.150922 -35.593218) (xy 66.027217 -35.719772) (xy 65.897881 -35.840564) (xy 65.76318 -35.955344)
			(xy 65.623395 -36.063874) (xy 65.478816 -36.16593) (xy 65.329741 -36.261299) (xy 65.17648 -36.349784)
			(xy 65.01935 -36.431202) (xy 64.858677 -36.505384) (xy 64.694795 -36.572176) (xy 64.528042 -36.63144)
			(xy 64.358765 -36.683053) (xy 64.187314 -36.726908) (xy 64.014045 -36.762914) (xy 63.839317 -36.790996)
			(xy 63.663491 -36.811096) (xy 63.486933 -36.823173) (xy 63.310008 -36.827202) (xy 63.133083 -36.823173)
			(xy 62.956525 -36.811096) (xy 62.780699 -36.790996) (xy 62.605971 -36.762914) (xy 62.432702 -36.726908)
			(xy 62.261251 -36.683053) (xy 62.091974 -36.63144) (xy 61.925221 -36.572176) (xy 61.761339 -36.505384)
			(xy 61.600666 -36.431202) (xy 61.443536 -36.349784) (xy 61.290275 -36.261299) (xy 61.1412 -36.16593)
			(xy 60.996621 -36.063874) (xy 60.856836 -35.955344) (xy 60.722135 -35.840564) (xy 60.592799 -35.719772)
			(xy 60.469094 -35.593218) (xy 60.351278 -35.461166) (xy 60.239593 -35.323888) (xy 60.134273 -35.181668)
			(xy 60.035535 -35.034803) (xy 59.943584 -34.883596) (xy 59.85861 -34.72836) (xy 59.78079 -34.569418)
			(xy 59.710285 -34.407098) (xy 59.647241 -34.241738) (xy 59.591788 -34.073679) (xy 59.544042 -33.903271)
			(xy 59.504101 -33.730867) (xy 59.472049 -33.556823) (xy 59.447951 -33.3815) (xy 59.431858 -33.205263)
			(xy 59.423804 -33.028475) (xy 38.292117 -33.028475) (xy 40.498014 -35.234372) (xy 40.504858 -35.24177)
			(xy 40.51258 -35.26037) (xy 40.513 -35.27044) (xy 40.513 -38.019995) (xy 73.975375 -38.019995) (xy 73.979281 -37.915487)
			(xy 73.990979 -37.811562) (xy 74.010402 -37.7088) (xy 74.037443 -37.607775) (xy 74.07195 -37.509051)
			(xy 74.11373 -37.413178) (xy 74.162551 -37.320692) (xy 74.218141 -37.232108) (xy 74.280188 -37.147922)
			(xy 74.348347 -37.068602) (xy 74.422237 -36.994592) (xy 74.501445 -36.926305) (xy 74.585531 -36.864121)
			(xy 74.629518 -36.835842) (xy 74.640694 -36.82873) (xy 74.65314 -36.806124) (xy 74.65314 -36.693856)
			(xy 74.640694 -36.67125) (xy 74.629518 -36.664138) (xy 74.585522 -36.635873) (xy 74.501437 -36.573689)
			(xy 74.422229 -36.505401) (xy 74.348339 -36.43139) (xy 74.280181 -36.35207) (xy 74.218135 -36.267883)
			(xy 74.162546 -36.179299) (xy 74.113726 -36.086812) (xy 74.071946 -35.990939) (xy 74.03744 -35.892215)
			(xy 74.0104 -35.79119) (xy 73.990977 -35.688428) (xy 73.979281 -35.584503) (xy 73.975375 -35.479995)
			(xy 73.979281 -35.375487) (xy 73.990979 -35.271562) (xy 74.010402 -35.1688) (xy 74.037443 -35.067775)
			(xy 74.07195 -34.969051) (xy 74.11373 -34.873178) (xy 74.162551 -34.780692) (xy 74.218141 -34.692108)
			(xy 74.280188 -34.607922) (xy 74.348347 -34.528602) (xy 74.422237 -34.454592) (xy 74.501445 -34.386305)
			(xy 74.585531 -34.324121) (xy 74.629518 -34.295842) (xy 74.640694 -34.28873) (xy 74.65314 -34.266124)
			(xy 74.65314 -34.153856) (xy 74.640694 -34.13125) (xy 74.629518 -34.124138) (xy 74.583824 -34.094786)
			(xy 74.496672 -34.029968) (xy 74.414808 -33.958589) (xy 74.338725 -33.881076) (xy 74.268881 -33.797899)
			(xy 74.205695 -33.709556) (xy 74.149549 -33.616581) (xy 74.100781 -33.519532) (xy 74.059684 -33.418994)
			(xy 74.026506 -33.315573) (xy 74.001446 -33.20989) (xy 73.984656 -33.102583) (xy 73.976235 -32.994297)
			(xy 73.975722 -32.93999) (xy 73.976194 -32.88765) (xy 73.984017 -32.783264) (xy 73.99962 -32.679754)
			(xy 74.022914 -32.5777) (xy 74.053769 -32.477671) (xy 74.092013 -32.380228) (xy 74.137432 -32.285916)
			(xy 74.189773 -32.195261) (xy 74.248741 -32.108772) (xy 74.314008 -32.026931) (xy 74.385209 -31.950196)
			(xy 74.461944 -31.878996) (xy 74.543786 -31.81373) (xy 74.630277 -31.754763) (xy 74.720932 -31.702424)
			(xy 74.815245 -31.657006) (xy 74.912688 -31.618763) (xy 75.012717 -31.587909) (xy 75.114772 -31.564616)
			(xy 75.218282 -31.549015) (xy 75.322668 -31.541193) (xy 75.375008 -31.540704) (xy 75.429314 -31.54123)
			(xy 75.537599 -31.549652) (xy 75.644904 -31.566443) (xy 75.750585 -31.591504) (xy 75.854005 -31.624682)
			(xy 75.954542 -31.665779) (xy 76.051589 -31.714547) (xy 76.144563 -31.770693) (xy 76.232904 -31.833877)
			(xy 76.316081 -31.903721) (xy 76.393592 -31.979804) (xy 76.464971 -32.061666) (xy 76.529789 -32.148817)
			(xy 76.559156 -32.1945) (xy 76.566268 -32.205676) (xy 76.588874 -32.218122) (xy 76.701142 -32.218122)
			(xy 76.723748 -32.205676) (xy 76.73086 -32.1945) (xy 76.760243 -32.148827) (xy 76.825056 -32.061673)
			(xy 76.896432 -31.979806) (xy 76.97394 -31.903721) (xy 77.057115 -31.833874) (xy 77.145454 -31.770687)
			(xy 77.238427 -31.714539) (xy 77.335474 -31.665769) (xy 77.43601 -31.62467) (xy 77.53943 -31.591491)
			(xy 77.645111 -31.56643) (xy 77.752417 -31.549638) (xy 77.860702 -31.541218) (xy 77.915008 -31.540704)
			(xy 77.967347 -31.541196) (xy 78.071733 -31.549019) (xy 78.175242 -31.564621) (xy 78.277295 -31.587914)
			(xy 78.377323 -31.618769) (xy 78.474765 -31.657013) (xy 78.569077 -31.702431) (xy 78.659731 -31.75477)
			(xy 78.74622 -31.813738) (xy 78.828061 -31.879004) (xy 78.904796 -31.950203) (xy 78.975995 -32.026937)
			(xy 79.041261 -32.108778) (xy 79.100229 -32.195267) (xy 79.152568 -32.285921) (xy 79.197987 -32.380233)
			(xy 79.23623 -32.477675) (xy 79.267085 -32.577703) (xy 79.290379 -32.679756) (xy 79.305981 -32.783265)
			(xy 79.313804 -32.887651) (xy 79.314294 -32.93999) (xy 79.313835 -32.994297) (xy 79.305407 -33.102584)
			(xy 79.28861 -33.209891) (xy 79.263543 -33.315573) (xy 79.230358 -33.418994) (xy 79.189255 -33.51953)
			(xy 79.140482 -33.616578) (xy 79.084331 -33.709552) (xy 79.021141 -33.797892) (xy 78.951292 -33.881068)
			(xy 78.875205 -33.958578) (xy 78.793338 -34.029956) (xy 78.706183 -34.094771) (xy 78.660498 -34.124138)
			(xy 78.649322 -34.13125) (xy 78.636876 -34.153856) (xy 78.636876 -34.266124) (xy 78.649322 -34.28873)
			(xy 78.660498 -34.295842) (xy 78.704478 -34.324133) (xy 78.788567 -34.386313) (xy 78.867779 -34.454598)
			(xy 78.941672 -34.528605) (xy 79.009834 -34.607923) (xy 79.071885 -34.692108) (xy 79.127477 -34.780691)
			(xy 79.1763 -34.873176) (xy 79.218083 -34.969049) (xy 79.252592 -35.067773) (xy 79.279634 -35.168798)
			(xy 79.299058 -35.27156) (xy 79.310757 -35.375486) (xy 79.314664 -35.479995) (xy 79.310758 -35.584503)
			(xy 79.29906 -35.688429) (xy 79.279636 -35.791191) (xy 79.252595 -35.892217) (xy 79.218087 -35.990941)
			(xy 79.176305 -36.086814) (xy 79.127482 -36.1793) (xy 79.071891 -36.267883) (xy 79.009841 -36.352069)
			(xy 78.94168 -36.431387) (xy 78.867787 -36.505395) (xy 78.788575 -36.57368) (xy 78.704486 -36.635861)
			(xy 78.660498 -36.664138) (xy 78.649322 -36.67125) (xy 78.636876 -36.693856) (xy 78.636876 -36.806124)
			(xy 78.649322 -36.82873) (xy 78.660498 -36.835842) (xy 78.704478 -36.864133) (xy 78.788567 -36.926313)
			(xy 78.867779 -36.994598) (xy 78.941672 -37.068605) (xy 79.009834 -37.147923) (xy 79.071885 -37.232108)
			(xy 79.127477 -37.320691) (xy 79.1763 -37.413176) (xy 79.218083 -37.509049) (xy 79.252592 -37.607773)
			(xy 79.279634 -37.708798) (xy 79.299058 -37.81156) (xy 79.310757 -37.915486) (xy 79.314664 -38.019995)
			(xy 82.865375 -38.019995) (xy 82.869281 -37.915487) (xy 82.880979 -37.811562) (xy 82.900402 -37.7088)
			(xy 82.927443 -37.607775) (xy 82.96195 -37.509051) (xy 83.00373 -37.413178) (xy 83.052551 -37.320692)
			(xy 83.108141 -37.232108) (xy 83.170188 -37.147922) (xy 83.238347 -37.068602) (xy 83.312237 -36.994592)
			(xy 83.391445 -36.926305) (xy 83.475531 -36.864121) (xy 83.519518 -36.835842) (xy 83.530694 -36.82873)
			(xy 83.54314 -36.806124) (xy 83.54314 -36.693856) (xy 83.530694 -36.67125) (xy 83.519518 -36.664138)
			(xy 83.475522 -36.635873) (xy 83.391437 -36.573689) (xy 83.312229 -36.505401) (xy 83.238339 -36.43139)
			(xy 83.170181 -36.35207) (xy 83.108135 -36.267883) (xy 83.052546 -36.179299) (xy 83.003726 -36.086812)
			(xy 82.961946 -35.990939) (xy 82.92744 -35.892215) (xy 82.9004 -35.79119) (xy 82.880977 -35.688428)
			(xy 82.869281 -35.584503) (xy 82.865375 -35.479995) (xy 82.869281 -35.375487) (xy 82.880979 -35.271562)
			(xy 82.900402 -35.1688) (xy 82.927443 -35.067775) (xy 82.96195 -34.969051) (xy 83.00373 -34.873178)
			(xy 83.052551 -34.780692) (xy 83.108141 -34.692108) (xy 83.170188 -34.607922) (xy 83.238347 -34.528602)
			(xy 83.312237 -34.454592) (xy 83.391445 -34.386305) (xy 83.475531 -34.324121) (xy 83.519518 -34.295842)
			(xy 83.530694 -34.28873) (xy 83.54314 -34.266124) (xy 83.54314 -34.153856) (xy 83.530694 -34.13125)
			(xy 83.519518 -34.124138) (xy 83.473824 -34.094786) (xy 83.386672 -34.029968) (xy 83.304808 -33.958589)
			(xy 83.228725 -33.881076) (xy 83.158881 -33.797899) (xy 83.095695 -33.709556) (xy 83.039549 -33.616581)
			(xy 82.990781 -33.519532) (xy 82.949684 -33.418994) (xy 82.916506 -33.315573) (xy 82.891446 -33.20989)
			(xy 82.874656 -33.102583) (xy 82.866235 -32.994297) (xy 82.865722 -32.93999) (xy 82.866194 -32.88765)
			(xy 82.874017 -32.783264) (xy 82.88962 -32.679754) (xy 82.912914 -32.5777) (xy 82.943769 -32.477671)
			(xy 82.982013 -32.380228) (xy 83.027432 -32.285916) (xy 83.079773 -32.195261) (xy 83.138741 -32.108772)
			(xy 83.204008 -32.026931) (xy 83.275209 -31.950196) (xy 83.351944 -31.878996) (xy 83.433786 -31.81373)
			(xy 83.520277 -31.754763) (xy 83.610932 -31.702424) (xy 83.705245 -31.657006) (xy 83.802688 -31.618763)
			(xy 83.902717 -31.587909) (xy 84.004772 -31.564616) (xy 84.108282 -31.549015) (xy 84.212668 -31.541193)
			(xy 84.265008 -31.540704) (xy 84.319314 -31.54123) (xy 84.427599 -31.549652) (xy 84.534904 -31.566443)
			(xy 84.640585 -31.591504) (xy 84.744005 -31.624682) (xy 84.844542 -31.665779) (xy 84.941589 -31.714547)
			(xy 85.034563 -31.770693) (xy 85.122904 -31.833877) (xy 85.206081 -31.903721) (xy 85.283592 -31.979804)
			(xy 85.354971 -32.061666) (xy 85.419789 -32.148817) (xy 85.449156 -32.1945) (xy 85.456268 -32.205676)
			(xy 85.478874 -32.218122) (xy 85.591142 -32.218122) (xy 85.613748 -32.205676) (xy 85.62086 -32.1945)
			(xy 85.650243 -32.148827) (xy 85.715056 -32.061673) (xy 85.786432 -31.979806) (xy 85.86394 -31.903721)
			(xy 85.947115 -31.833874) (xy 86.035454 -31.770687) (xy 86.128427 -31.714539) (xy 86.225474 -31.665769)
			(xy 86.32601 -31.62467) (xy 86.42943 -31.591491) (xy 86.535111 -31.56643) (xy 86.642417 -31.549638)
			(xy 86.750702 -31.541218) (xy 86.805008 -31.540704) (xy 86.857347 -31.541196) (xy 86.961733 -31.549019)
			(xy 87.065242 -31.564621) (xy 87.167295 -31.587914) (xy 87.267323 -31.618769) (xy 87.364765 -31.657013)
			(xy 87.459077 -31.702431) (xy 87.549731 -31.75477) (xy 87.63622 -31.813738) (xy 87.718061 -31.879004)
			(xy 87.794796 -31.950203) (xy 87.865995 -32.026937) (xy 87.931261 -32.108778) (xy 87.990229 -32.195267)
			(xy 88.042568 -32.285921) (xy 88.087987 -32.380233) (xy 88.12623 -32.477675) (xy 88.157085 -32.577703)
			(xy 88.180379 -32.679756) (xy 88.195981 -32.783265) (xy 88.203804 -32.887651) (xy 88.204294 -32.93999)
			(xy 88.203835 -32.994297) (xy 88.195407 -33.102584) (xy 88.17861 -33.209891) (xy 88.153543 -33.315573)
			(xy 88.120358 -33.418994) (xy 88.079255 -33.51953) (xy 88.030482 -33.616578) (xy 87.974331 -33.709552)
			(xy 87.911141 -33.797892) (xy 87.841292 -33.881068) (xy 87.765205 -33.958578) (xy 87.683338 -34.029956)
			(xy 87.596183 -34.094771) (xy 87.550498 -34.124138) (xy 87.539322 -34.13125) (xy 87.526876 -34.153856)
			(xy 87.526876 -34.266124) (xy 87.539322 -34.28873) (xy 87.550498 -34.295842) (xy 87.594478 -34.324133)
			(xy 87.678567 -34.386313) (xy 87.757779 -34.454598) (xy 87.831672 -34.528605) (xy 87.899834 -34.607923)
			(xy 87.961885 -34.692108) (xy 88.017477 -34.780691) (xy 88.0663 -34.873176) (xy 88.108083 -34.969049)
			(xy 88.142592 -35.067773) (xy 88.169634 -35.168798) (xy 88.189058 -35.27156) (xy 88.200757 -35.375486)
			(xy 88.204664 -35.479995) (xy 88.200758 -35.584503) (xy 88.18906 -35.688429) (xy 88.169636 -35.791191)
			(xy 88.142595 -35.892217) (xy 88.108087 -35.990941) (xy 88.066305 -36.086814) (xy 88.017482 -36.1793)
			(xy 87.961891 -36.267883) (xy 87.899841 -36.352069) (xy 87.83168 -36.431387) (xy 87.757787 -36.505395)
			(xy 87.678575 -36.57368) (xy 87.594486 -36.635861) (xy 87.550498 -36.664138) (xy 87.539322 -36.67125)
			(xy 87.526876 -36.693856) (xy 87.526876 -36.806124) (xy 87.539322 -36.82873) (xy 87.550498 -36.835842)
			(xy 87.594478 -36.864133) (xy 87.678567 -36.926313) (xy 87.757779 -36.994598) (xy 87.831672 -37.068605)
			(xy 87.899834 -37.147923) (xy 87.961885 -37.232108) (xy 88.017477 -37.320691) (xy 88.0663 -37.413176)
			(xy 88.108083 -37.509049) (xy 88.142592 -37.607773) (xy 88.169634 -37.708798) (xy 88.189058 -37.81156)
			(xy 88.200757 -37.915486) (xy 88.204664 -38.019995) (xy 91.755375 -38.019995) (xy 91.759281 -37.915487)
			(xy 91.770979 -37.811562) (xy 91.790402 -37.7088) (xy 91.817443 -37.607775) (xy 91.85195 -37.509051)
			(xy 91.89373 -37.413178) (xy 91.942551 -37.320692) (xy 91.998141 -37.232108) (xy 92.060188 -37.147922)
			(xy 92.128347 -37.068602) (xy 92.202237 -36.994592) (xy 92.281445 -36.926305) (xy 92.365531 -36.864121)
			(xy 92.409518 -36.835842) (xy 92.420694 -36.82873) (xy 92.43314 -36.806124) (xy 92.43314 -36.693856)
			(xy 92.420694 -36.67125) (xy 92.409518 -36.664138) (xy 92.365522 -36.635873) (xy 92.281437 -36.573689)
			(xy 92.202229 -36.505401) (xy 92.128339 -36.43139) (xy 92.060181 -36.35207) (xy 91.998135 -36.267883)
			(xy 91.942546 -36.179299) (xy 91.893726 -36.086812) (xy 91.851946 -35.990939) (xy 91.81744 -35.892215)
			(xy 91.7904 -35.79119) (xy 91.770977 -35.688428) (xy 91.759281 -35.584503) (xy 91.755375 -35.479995)
			(xy 91.759281 -35.375487) (xy 91.770979 -35.271562) (xy 91.790402 -35.1688) (xy 91.817443 -35.067775)
			(xy 91.85195 -34.969051) (xy 91.89373 -34.873178) (xy 91.942551 -34.780692) (xy 91.998141 -34.692108)
			(xy 92.060188 -34.607922) (xy 92.128347 -34.528602) (xy 92.202237 -34.454592) (xy 92.281445 -34.386305)
			(xy 92.365531 -34.324121) (xy 92.409518 -34.295842) (xy 92.420694 -34.28873) (xy 92.43314 -34.266124)
			(xy 92.43314 -34.153856) (xy 92.420694 -34.13125) (xy 92.409518 -34.124138) (xy 92.363824 -34.094786)
			(xy 92.276672 -34.029968) (xy 92.194808 -33.958589) (xy 92.118725 -33.881076) (xy 92.048881 -33.797899)
			(xy 91.985695 -33.709556) (xy 91.929549 -33.616581) (xy 91.880781 -33.519532) (xy 91.839684 -33.418994)
			(xy 91.806506 -33.315573) (xy 91.781446 -33.20989) (xy 91.764656 -33.102583) (xy 91.756235 -32.994297)
			(xy 91.755722 -32.93999) (xy 91.756194 -32.88765) (xy 91.764017 -32.783264) (xy 91.77962 -32.679754)
			(xy 91.802914 -32.5777) (xy 91.833769 -32.477671) (xy 91.872013 -32.380228) (xy 91.917432 -32.285916)
			(xy 91.969773 -32.195261) (xy 92.028741 -32.108772) (xy 92.094008 -32.026931) (xy 92.165209 -31.950196)
			(xy 92.241944 -31.878996) (xy 92.323786 -31.81373) (xy 92.410277 -31.754763) (xy 92.500932 -31.702424)
			(xy 92.595245 -31.657006) (xy 92.692688 -31.618763) (xy 92.792717 -31.587909) (xy 92.894772 -31.564616)
			(xy 92.998282 -31.549015) (xy 93.102668 -31.541193) (xy 93.155008 -31.540704) (xy 93.209314 -31.54123)
			(xy 93.317599 -31.549652) (xy 93.424904 -31.566443) (xy 93.530585 -31.591504) (xy 93.634005 -31.624682)
			(xy 93.734542 -31.665779) (xy 93.831589 -31.714547) (xy 93.924563 -31.770693) (xy 94.012904 -31.833877)
			(xy 94.096081 -31.903721) (xy 94.173592 -31.979804) (xy 94.244971 -32.061666) (xy 94.309789 -32.148817)
			(xy 94.339156 -32.1945) (xy 94.346268 -32.205676) (xy 94.368874 -32.218122) (xy 94.481142 -32.218122)
			(xy 94.503748 -32.205676) (xy 94.51086 -32.1945) (xy 94.540243 -32.148827) (xy 94.605056 -32.061673)
			(xy 94.676432 -31.979806) (xy 94.75394 -31.903721) (xy 94.837115 -31.833874) (xy 94.925454 -31.770687)
			(xy 95.018427 -31.714539) (xy 95.115474 -31.665769) (xy 95.21601 -31.62467) (xy 95.31943 -31.591491)
			(xy 95.425111 -31.56643) (xy 95.532417 -31.549638) (xy 95.640702 -31.541218) (xy 95.695008 -31.540704)
			(xy 95.747347 -31.541196) (xy 95.851733 -31.549019) (xy 95.955242 -31.564621) (xy 96.057295 -31.587914)
			(xy 96.157323 -31.618769) (xy 96.254765 -31.657013) (xy 96.349077 -31.702431) (xy 96.439731 -31.75477)
			(xy 96.52622 -31.813738) (xy 96.608061 -31.879004) (xy 96.684796 -31.950203) (xy 96.755995 -32.026937)
			(xy 96.821261 -32.108778) (xy 96.880229 -32.195267) (xy 96.932568 -32.285921) (xy 96.977987 -32.380233)
			(xy 97.01623 -32.477675) (xy 97.047085 -32.577703) (xy 97.070379 -32.679756) (xy 97.085981 -32.783265)
			(xy 97.093804 -32.887651) (xy 97.094294 -32.93999) (xy 97.093835 -32.994297) (xy 97.091175 -33.028475)
			(xy 130.543804 -33.028475) (xy 130.543804 -32.851505) (xy 130.551858 -32.674717) (xy 130.567951 -32.49848)
			(xy 130.592049 -32.323157) (xy 130.624101 -32.149113) (xy 130.664042 -31.976709) (xy 130.711788 -31.806301)
			(xy 130.767241 -31.638242) (xy 130.830285 -31.472882) (xy 130.90079 -31.310562) (xy 130.97861 -31.15162)
			(xy 131.063584 -30.996384) (xy 131.155535 -30.845177) (xy 131.254273 -30.698312) (xy 131.359593 -30.556092)
			(xy 131.471278 -30.418814) (xy 131.589094 -30.286762) (xy 131.712799 -30.160208) (xy 131.842135 -30.039416)
			(xy 131.976836 -29.924636) (xy 132.116621 -29.816106) (xy 132.2612 -29.71405) (xy 132.410275 -29.618681)
			(xy 132.563536 -29.530196) (xy 132.720666 -29.448778) (xy 132.881339 -29.374596) (xy 133.045221 -29.307804)
			(xy 133.211974 -29.24854) (xy 133.381251 -29.196927) (xy 133.552702 -29.153072) (xy 133.725971 -29.117066)
			(xy 133.900699 -29.088984) (xy 134.076525 -29.068884) (xy 134.253083 -29.056807) (xy 134.430008 -29.052779)
			(xy 134.606933 -29.056807) (xy 134.783491 -29.068884) (xy 134.959317 -29.088984) (xy 135.134045 -29.117066)
			(xy 135.307314 -29.153072) (xy 135.478765 -29.196927) (xy 135.648042 -29.24854) (xy 135.814795 -29.307804)
			(xy 135.978677 -29.374596) (xy 136.13935 -29.448778) (xy 136.29648 -29.530196) (xy 136.449741 -29.618681)
			(xy 136.598816 -29.71405) (xy 136.743395 -29.816106) (xy 136.88318 -29.924636) (xy 137.017881 -30.039416)
			(xy 137.147217 -30.160208) (xy 137.270922 -30.286762) (xy 137.388738 -30.418814) (xy 137.500423 -30.556092)
			(xy 137.605743 -30.698312) (xy 137.704481 -30.845177) (xy 137.796432 -30.996384) (xy 137.881406 -31.15162)
			(xy 137.959226 -31.310562) (xy 138.029731 -31.472882) (xy 138.092775 -31.638242) (xy 138.148228 -31.806301)
			(xy 138.195974 -31.976709) (xy 138.235915 -32.149113) (xy 138.267967 -32.323157) (xy 138.292065 -32.49848)
			(xy 138.308158 -32.674717) (xy 138.316212 -32.851505) (xy 138.316716 -32.93999) (xy 138.316212 -33.028475)
			(xy 138.308158 -33.205263) (xy 138.292065 -33.3815) (xy 138.267967 -33.556823) (xy 138.235915 -33.730867)
			(xy 138.195974 -33.903271) (xy 138.148228 -34.073679) (xy 138.092775 -34.241738) (xy 138.029731 -34.407098)
			(xy 137.959226 -34.569418) (xy 137.881406 -34.72836) (xy 137.796432 -34.883596) (xy 137.704481 -35.034803)
			(xy 137.605743 -35.181668) (xy 137.500423 -35.323888) (xy 137.388738 -35.461166) (xy 137.270922 -35.593218)
			(xy 137.147217 -35.719772) (xy 137.017881 -35.840564) (xy 136.88318 -35.955344) (xy 136.743395 -36.063874)
			(xy 136.598816 -36.16593) (xy 136.449741 -36.261299) (xy 136.29648 -36.349784) (xy 136.13935 -36.431202)
			(xy 135.978677 -36.505384) (xy 135.814795 -36.572176) (xy 135.648042 -36.63144) (xy 135.478765 -36.683053)
			(xy 135.307314 -36.726908) (xy 135.134045 -36.762914) (xy 134.959317 -36.790996) (xy 134.783491 -36.811096)
			(xy 134.606933 -36.823173) (xy 134.430008 -36.827202) (xy 134.253083 -36.823173) (xy 134.076525 -36.811096)
			(xy 133.900699 -36.790996) (xy 133.725971 -36.762914) (xy 133.552702 -36.726908) (xy 133.381251 -36.683053)
			(xy 133.211974 -36.63144) (xy 133.045221 -36.572176) (xy 132.881339 -36.505384) (xy 132.720666 -36.431202)
			(xy 132.563536 -36.349784) (xy 132.410275 -36.261299) (xy 132.2612 -36.16593) (xy 132.116621 -36.063874)
			(xy 131.976836 -35.955344) (xy 131.842135 -35.840564) (xy 131.712799 -35.719772) (xy 131.589094 -35.593218)
			(xy 131.471278 -35.461166) (xy 131.359593 -35.323888) (xy 131.254273 -35.181668) (xy 131.155535 -35.034803)
			(xy 131.063584 -34.883596) (xy 130.97861 -34.72836) (xy 130.90079 -34.569418) (xy 130.830285 -34.407098)
			(xy 130.767241 -34.241738) (xy 130.711788 -34.073679) (xy 130.664042 -33.903271) (xy 130.624101 -33.730867)
			(xy 130.592049 -33.556823) (xy 130.567951 -33.3815) (xy 130.551858 -33.205263) (xy 130.543804 -33.028475)
			(xy 97.091175 -33.028475) (xy 97.085407 -33.102584) (xy 97.06861 -33.209891) (xy 97.043543 -33.315573)
			(xy 97.010358 -33.418994) (xy 96.969255 -33.51953) (xy 96.920482 -33.616578) (xy 96.864331 -33.709552)
			(xy 96.801141 -33.797892) (xy 96.731292 -33.881068) (xy 96.655205 -33.958578) (xy 96.573338 -34.029956)
			(xy 96.486183 -34.094771) (xy 96.440498 -34.124138) (xy 96.429322 -34.13125) (xy 96.416876 -34.153856)
			(xy 96.416876 -34.266124) (xy 96.429322 -34.28873) (xy 96.440498 -34.295842) (xy 96.484478 -34.324133)
			(xy 96.568567 -34.386313) (xy 96.647779 -34.454598) (xy 96.721672 -34.528605) (xy 96.789834 -34.607923)
			(xy 96.851885 -34.692108) (xy 96.907477 -34.780691) (xy 96.9563 -34.873176) (xy 96.998083 -34.969049)
			(xy 97.032592 -35.067773) (xy 97.059634 -35.168798) (xy 97.079058 -35.27156) (xy 97.090757 -35.375486)
			(xy 97.094664 -35.479995) (xy 97.090758 -35.584503) (xy 97.07906 -35.688429) (xy 97.059636 -35.791191)
			(xy 97.032595 -35.892217) (xy 96.998087 -35.990941) (xy 96.956305 -36.086814) (xy 96.907482 -36.1793)
			(xy 96.851891 -36.267883) (xy 96.789841 -36.352069) (xy 96.72168 -36.431387) (xy 96.647787 -36.505395)
			(xy 96.568575 -36.57368) (xy 96.484486 -36.635861) (xy 96.440498 -36.664138) (xy 96.429322 -36.67125)
			(xy 96.416876 -36.693856) (xy 96.416876 -36.806124) (xy 96.429322 -36.82873) (xy 96.440498 -36.835842)
			(xy 96.484478 -36.864133) (xy 96.568567 -36.926313) (xy 96.647779 -36.994598) (xy 96.721672 -37.068605)
			(xy 96.789834 -37.147923) (xy 96.851885 -37.232108) (xy 96.907477 -37.320691) (xy 96.9563 -37.413176)
			(xy 96.998083 -37.509049) (xy 97.032592 -37.607773) (xy 97.059634 -37.708798) (xy 97.079058 -37.81156)
			(xy 97.090757 -37.915486) (xy 97.094664 -38.019995) (xy 97.093987 -38.038117) (xy 165.038782 -38.038117)
			(xy 165.038782 -37.861147) (xy 165.046836 -37.684359) (xy 165.062929 -37.508122) (xy 165.087027 -37.332799)
			(xy 165.119079 -37.158755) (xy 165.15902 -36.986351) (xy 165.206766 -36.815943) (xy 165.262219 -36.647884)
			(xy 165.325263 -36.482524) (xy 165.395768 -36.320204) (xy 165.473588 -36.161262) (xy 165.558562 -36.006026)
			(xy 165.650513 -35.854819) (xy 165.749251 -35.707954) (xy 165.854571 -35.565734) (xy 165.966256 -35.428456)
			(xy 166.084072 -35.296404) (xy 166.207777 -35.16985) (xy 166.337113 -35.049058) (xy 166.471814 -34.934278)
			(xy 166.611599 -34.825748) (xy 166.756178 -34.723692) (xy 166.905253 -34.628323) (xy 167.058514 -34.539838)
			(xy 167.215644 -34.45842) (xy 167.376317 -34.384238) (xy 167.540199 -34.317446) (xy 167.706952 -34.258182)
			(xy 167.876229 -34.206569) (xy 168.04768 -34.162714) (xy 168.220949 -34.126708) (xy 168.395677 -34.098626)
			(xy 168.571503 -34.078526) (xy 168.748061 -34.066449) (xy 168.924986 -34.062421) (xy 169.101911 -34.066449)
			(xy 169.278469 -34.078526) (xy 169.454295 -34.098626) (xy 169.629023 -34.126708) (xy 169.802292 -34.162714)
			(xy 169.973743 -34.206569) (xy 170.14302 -34.258182) (xy 170.309773 -34.317446) (xy 170.473655 -34.384238)
			(xy 170.634328 -34.45842) (xy 170.791458 -34.539838) (xy 170.944719 -34.628323) (xy 171.093794 -34.723692)
			(xy 171.238373 -34.825748) (xy 171.378158 -34.934278) (xy 171.512859 -35.049058) (xy 171.642195 -35.16985)
			(xy 171.7659 -35.296404) (xy 171.883716 -35.428456) (xy 171.995401 -35.565734) (xy 172.100721 -35.707954)
			(xy 172.199459 -35.854819) (xy 172.29141 -36.006026) (xy 172.376384 -36.161262) (xy 172.454204 -36.320204)
			(xy 172.524709 -36.482524) (xy 172.587753 -36.647884) (xy 172.643206 -36.815943) (xy 172.690952 -36.986351)
			(xy 172.730893 -37.158755) (xy 172.762945 -37.332799) (xy 172.787043 -37.508122) (xy 172.803136 -37.684359)
			(xy 172.81119 -37.861147) (xy 172.811694 -37.949632) (xy 172.81119 -38.038117) (xy 172.803136 -38.214905)
			(xy 172.787043 -38.391142) (xy 172.762945 -38.566465) (xy 172.730893 -38.740509) (xy 172.690952 -38.912913)
			(xy 172.643206 -39.083321) (xy 172.587753 -39.25138) (xy 172.524709 -39.41674) (xy 172.454204 -39.57906)
			(xy 172.376384 -39.738002) (xy 172.29141 -39.893238) (xy 172.199459 -40.044445) (xy 172.100721 -40.19131)
			(xy 171.995401 -40.33353) (xy 171.883716 -40.470808) (xy 171.7659 -40.60286) (xy 171.642195 -40.729414)
			(xy 171.512859 -40.850206) (xy 171.378158 -40.964986) (xy 171.238373 -41.073516) (xy 171.093794 -41.175572)
			(xy 170.944719 -41.270941) (xy 170.791458 -41.359426) (xy 170.634328 -41.440844) (xy 170.473655 -41.515026)
			(xy 170.309773 -41.581818) (xy 170.14302 -41.641082) (xy 169.973743 -41.692695) (xy 169.802292 -41.73655)
			(xy 169.629023 -41.772556) (xy 169.454295 -41.800638) (xy 169.278469 -41.820738) (xy 169.101911 -41.832815)
			(xy 168.924986 -41.836844) (xy 168.748061 -41.832815) (xy 168.571503 -41.820738) (xy 168.395677 -41.800638)
			(xy 168.220949 -41.772556) (xy 168.04768 -41.73655) (xy 167.876229 -41.692695) (xy 167.706952 -41.641082)
			(xy 167.540199 -41.581818) (xy 167.376317 -41.515026) (xy 167.215644 -41.440844) (xy 167.058514 -41.359426)
			(xy 166.905253 -41.270941) (xy 166.756178 -41.175572) (xy 166.611599 -41.073516) (xy 166.471814 -40.964986)
			(xy 166.337113 -40.850206) (xy 166.207777 -40.729414) (xy 166.084072 -40.60286) (xy 165.966256 -40.470808)
			(xy 165.854571 -40.33353) (xy 165.749251 -40.19131) (xy 165.650513 -40.044445) (xy 165.558562 -39.893238)
			(xy 165.473588 -39.738002) (xy 165.395768 -39.57906) (xy 165.325263 -39.41674) (xy 165.262219 -39.25138)
			(xy 165.206766 -39.083321) (xy 165.15902 -38.912913) (xy 165.119079 -38.740509) (xy 165.087027 -38.566465)
			(xy 165.062929 -38.391142) (xy 165.046836 -38.214905) (xy 165.038782 -38.038117) (xy 97.093987 -38.038117)
			(xy 97.090758 -38.124503) (xy 97.07906 -38.228429) (xy 97.059636 -38.331191) (xy 97.032595 -38.432217)
			(xy 96.998087 -38.530941) (xy 96.956305 -38.626814) (xy 96.907482 -38.7193) (xy 96.851891 -38.807883)
			(xy 96.789841 -38.892069) (xy 96.72168 -38.971387) (xy 96.647787 -39.045395) (xy 96.568575 -39.11368)
			(xy 96.484486 -39.175861) (xy 96.440498 -39.204138) (xy 96.429322 -39.21125) (xy 96.416876 -39.233856)
			(xy 96.416876 -39.346124) (xy 96.429322 -39.36873) (xy 96.440498 -39.375842) (xy 96.486163 -39.405238)
			(xy 96.573317 -39.47005) (xy 96.655183 -39.541425) (xy 96.731269 -39.618932) (xy 96.801116 -39.702105)
			(xy 96.864304 -39.790444) (xy 96.920452 -39.883415) (xy 96.969223 -39.980461) (xy 97.010322 -40.080996)
			(xy 97.043503 -40.184415) (xy 97.068565 -40.290095) (xy 97.085358 -40.3974) (xy 97.09378 -40.505684)
			(xy 97.094294 -40.55999) (xy 97.093799 -40.612329) (xy 97.085977 -40.716716) (xy 97.070376 -40.820225)
			(xy 97.047084 -40.92228) (xy 97.01623 -41.022308) (xy 96.977987 -41.119751) (xy 96.932569 -41.214064)
			(xy 96.88023 -41.304719) (xy 96.821263 -41.391209) (xy 96.755998 -41.47305) (xy 96.684799 -41.549786)
			(xy 96.608064 -41.620986) (xy 96.526223 -41.686253) (xy 96.439734 -41.745221) (xy 96.34908 -41.797561)
			(xy 96.254768 -41.84298) (xy 96.157325 -41.881224) (xy 96.057297 -41.912079) (xy 95.955243 -41.935373)
			(xy 95.851733 -41.950975) (xy 95.747347 -41.958798) (xy 95.695008 -41.959276) (xy 95.640702 -41.95878)
			(xy 95.532417 -41.950353) (xy 95.425111 -41.933556) (xy 95.319431 -41.908491) (xy 95.216012 -41.875309)
			(xy 95.115476 -41.834208) (xy 95.018429 -41.785438) (xy 94.925456 -41.72929) (xy 94.837115 -41.666104)
			(xy 94.753938 -41.596259) (xy 94.676427 -41.520176) (xy 94.605047 -41.438313) (xy 94.540228 -41.351163)
			(xy 94.51086 -41.30548) (xy 94.503748 -41.294304) (xy 94.481142 -41.281858) (xy 94.368874 -41.281858)
			(xy 94.346268 -41.294304) (xy 94.339156 -41.30548) (xy 94.309791 -41.351165) (xy 94.244974 -41.438317)
			(xy 94.173596 -41.520181) (xy 94.096085 -41.596265) (xy 94.012908 -41.66611) (xy 93.924567 -41.729295)
			(xy 93.831592 -41.785442) (xy 93.734545 -41.834211) (xy 93.634008 -41.875308) (xy 93.530588 -41.908488)
			(xy 93.424906 -41.933549) (xy 93.3176 -41.95034) (xy 93.209314 -41.958762) (xy 93.155008 -41.959276)
			(xy 93.102668 -41.958801) (xy 92.998281 -41.950979) (xy 92.894771 -41.935377) (xy 92.792715 -41.912084)
			(xy 92.692686 -41.88123) (xy 92.595242 -41.842986) (xy 92.500929 -41.797568) (xy 92.410274 -41.745228)
			(xy 92.323783 -41.68626) (xy 92.241941 -41.620993) (xy 92.165206 -41.549793) (xy 92.094006 -41.473057)
			(xy 92.028739 -41.391215) (xy 91.969771 -41.304725) (xy 91.917431 -41.214069) (xy 91.872013 -41.119756)
			(xy 91.833769 -41.022312) (xy 91.802915 -40.922283) (xy 91.779622 -40.820228) (xy 91.764021 -40.716717)
			(xy 91.756199 -40.61233) (xy 91.755722 -40.55999) (xy 91.756285 -40.505685) (xy 91.764706 -40.397402)
			(xy 91.781496 -40.290098) (xy 91.806555 -40.184419) (xy 91.839732 -40.081) (xy 91.880826 -39.980465)
			(xy 91.929591 -39.883418) (xy 91.985733 -39.790444) (xy 92.048915 -39.702103) (xy 92.118754 -39.618925)
			(xy 92.194833 -39.541412) (xy 92.276691 -39.470031) (xy 92.363837 -39.405211) (xy 92.409518 -39.375842)
			(xy 92.420694 -39.36873) (xy 92.43314 -39.346124) (xy 92.43314 -39.233856) (xy 92.420694 -39.21125)
			(xy 92.409518 -39.204138) (xy 92.365522 -39.175873) (xy 92.281437 -39.113689) (xy 92.202229 -39.045401)
			(xy 92.128339 -38.97139) (xy 92.060181 -38.89207) (xy 91.998135 -38.807883) (xy 91.942546 -38.719299)
			(xy 91.893726 -38.626812) (xy 91.851946 -38.530939) (xy 91.81744 -38.432215) (xy 91.7904 -38.33119)
			(xy 91.770977 -38.228428) (xy 91.759281 -38.124503) (xy 91.755375 -38.019995) (xy 88.204664 -38.019995)
			(xy 88.200758 -38.124503) (xy 88.18906 -38.228429) (xy 88.169636 -38.331191) (xy 88.142595 -38.432217)
			(xy 88.108087 -38.530941) (xy 88.066305 -38.626814) (xy 88.017482 -38.7193) (xy 87.961891 -38.807883)
			(xy 87.899841 -38.892069) (xy 87.83168 -38.971387) (xy 87.757787 -39.045395) (xy 87.678575 -39.11368)
			(xy 87.594486 -39.175861) (xy 87.550498 -39.204138) (xy 87.539322 -39.21125) (xy 87.526876 -39.233856)
			(xy 87.526876 -39.346124) (xy 87.539322 -39.36873) (xy 87.550498 -39.375842) (xy 87.596163 -39.405238)
			(xy 87.683317 -39.47005) (xy 87.765183 -39.541425) (xy 87.841269 -39.618932) (xy 87.911116 -39.702105)
			(xy 87.974304 -39.790444) (xy 88.030452 -39.883415) (xy 88.079223 -39.980461) (xy 88.120322 -40.080996)
			(xy 88.153503 -40.184415) (xy 88.178565 -40.290095) (xy 88.195358 -40.3974) (xy 88.20378 -40.505684)
			(xy 88.204294 -40.55999) (xy 88.203799 -40.612329) (xy 88.195977 -40.716716) (xy 88.180376 -40.820225)
			(xy 88.157084 -40.92228) (xy 88.12623 -41.022308) (xy 88.087987 -41.119751) (xy 88.042569 -41.214064)
			(xy 87.99023 -41.304719) (xy 87.931263 -41.391209) (xy 87.865998 -41.47305) (xy 87.794799 -41.549786)
			(xy 87.718064 -41.620986) (xy 87.636223 -41.686253) (xy 87.549734 -41.745221) (xy 87.45908 -41.797561)
			(xy 87.364768 -41.84298) (xy 87.267325 -41.881224) (xy 87.167297 -41.912079) (xy 87.065243 -41.935373)
			(xy 86.961733 -41.950975) (xy 86.857347 -41.958798) (xy 86.805008 -41.959276) (xy 86.750702 -41.95878)
			(xy 86.642417 -41.950353) (xy 86.535111 -41.933556) (xy 86.429431 -41.908491) (xy 86.326012 -41.875309)
			(xy 86.225476 -41.834208) (xy 86.128429 -41.785438) (xy 86.035456 -41.72929) (xy 85.947115 -41.666104)
			(xy 85.863938 -41.596259) (xy 85.786427 -41.520176) (xy 85.715047 -41.438313) (xy 85.650228 -41.351163)
			(xy 85.62086 -41.30548) (xy 85.613748 -41.294304) (xy 85.591142 -41.281858) (xy 85.478874 -41.281858)
			(xy 85.456268 -41.294304) (xy 85.449156 -41.30548) (xy 85.419791 -41.351165) (xy 85.354974 -41.438317)
			(xy 85.283596 -41.520181) (xy 85.206085 -41.596265) (xy 85.122908 -41.66611) (xy 85.034567 -41.729295)
			(xy 84.941592 -41.785442) (xy 84.844545 -41.834211) (xy 84.744008 -41.875308) (xy 84.640588 -41.908488)
			(xy 84.534906 -41.933549) (xy 84.4276 -41.95034) (xy 84.319314 -41.958762) (xy 84.265008 -41.959276)
			(xy 84.212668 -41.958801) (xy 84.108281 -41.950979) (xy 84.004771 -41.935377) (xy 83.902715 -41.912084)
			(xy 83.802686 -41.88123) (xy 83.705242 -41.842986) (xy 83.610929 -41.797568) (xy 83.520274 -41.745228)
			(xy 83.433783 -41.68626) (xy 83.351941 -41.620993) (xy 83.275206 -41.549793) (xy 83.204006 -41.473057)
			(xy 83.138739 -41.391215) (xy 83.079771 -41.304725) (xy 83.027431 -41.214069) (xy 82.982013 -41.119756)
			(xy 82.943769 -41.022312) (xy 82.912915 -40.922283) (xy 82.889622 -40.820228) (xy 82.874021 -40.716717)
			(xy 82.866199 -40.61233) (xy 82.865722 -40.55999) (xy 82.866285 -40.505685) (xy 82.874706 -40.397402)
			(xy 82.891496 -40.290098) (xy 82.916555 -40.184419) (xy 82.949732 -40.081) (xy 82.990826 -39.980465)
			(xy 83.039591 -39.883418) (xy 83.095733 -39.790444) (xy 83.158915 -39.702103) (xy 83.228754 -39.618925)
			(xy 83.304833 -39.541412) (xy 83.386691 -39.470031) (xy 83.473837 -39.405211) (xy 83.519518 -39.375842)
			(xy 83.530694 -39.36873) (xy 83.54314 -39.346124) (xy 83.54314 -39.233856) (xy 83.530694 -39.21125)
			(xy 83.519518 -39.204138) (xy 83.475522 -39.175873) (xy 83.391437 -39.113689) (xy 83.312229 -39.045401)
			(xy 83.238339 -38.97139) (xy 83.170181 -38.89207) (xy 83.108135 -38.807883) (xy 83.052546 -38.719299)
			(xy 83.003726 -38.626812) (xy 82.961946 -38.530939) (xy 82.92744 -38.432215) (xy 82.9004 -38.33119)
			(xy 82.880977 -38.228428) (xy 82.869281 -38.124503) (xy 82.865375 -38.019995) (xy 79.314664 -38.019995)
			(xy 79.310758 -38.124503) (xy 79.29906 -38.228429) (xy 79.279636 -38.331191) (xy 79.252595 -38.432217)
			(xy 79.218087 -38.530941) (xy 79.176305 -38.626814) (xy 79.127482 -38.7193) (xy 79.071891 -38.807883)
			(xy 79.009841 -38.892069) (xy 78.94168 -38.971387) (xy 78.867787 -39.045395) (xy 78.788575 -39.11368)
			(xy 78.704486 -39.175861) (xy 78.660498 -39.204138) (xy 78.649322 -39.21125) (xy 78.636876 -39.233856)
			(xy 78.636876 -39.346124) (xy 78.649322 -39.36873) (xy 78.660498 -39.375842) (xy 78.706163 -39.405238)
			(xy 78.793317 -39.47005) (xy 78.875183 -39.541425) (xy 78.951269 -39.618932) (xy 79.021116 -39.702105)
			(xy 79.084304 -39.790444) (xy 79.140452 -39.883415) (xy 79.189223 -39.980461) (xy 79.230322 -40.080996)
			(xy 79.263503 -40.184415) (xy 79.288565 -40.290095) (xy 79.305358 -40.3974) (xy 79.31378 -40.505684)
			(xy 79.314294 -40.55999) (xy 79.313799 -40.612329) (xy 79.305977 -40.716716) (xy 79.290376 -40.820225)
			(xy 79.267084 -40.92228) (xy 79.23623 -41.022308) (xy 79.197987 -41.119751) (xy 79.152569 -41.214064)
			(xy 79.10023 -41.304719) (xy 79.041263 -41.391209) (xy 78.975998 -41.47305) (xy 78.904799 -41.549786)
			(xy 78.828064 -41.620986) (xy 78.746223 -41.686253) (xy 78.659734 -41.745221) (xy 78.56908 -41.797561)
			(xy 78.474768 -41.84298) (xy 78.377325 -41.881224) (xy 78.277297 -41.912079) (xy 78.175243 -41.935373)
			(xy 78.071733 -41.950975) (xy 77.967347 -41.958798) (xy 77.915008 -41.959276) (xy 77.860702 -41.95878)
			(xy 77.752417 -41.950353) (xy 77.645111 -41.933556) (xy 77.539431 -41.908491) (xy 77.436012 -41.875309)
			(xy 77.335476 -41.834208) (xy 77.238429 -41.785438) (xy 77.145456 -41.72929) (xy 77.057115 -41.666104)
			(xy 76.973938 -41.596259) (xy 76.896427 -41.520176) (xy 76.825047 -41.438313) (xy 76.760228 -41.351163)
			(xy 76.73086 -41.30548) (xy 76.723748 -41.294304) (xy 76.701142 -41.281858) (xy 76.588874 -41.281858)
			(xy 76.566268 -41.294304) (xy 76.559156 -41.30548) (xy 76.529791 -41.351165) (xy 76.464974 -41.438317)
			(xy 76.393596 -41.520181) (xy 76.316085 -41.596265) (xy 76.232908 -41.66611) (xy 76.144567 -41.729295)
			(xy 76.051592 -41.785442) (xy 75.954545 -41.834211) (xy 75.854008 -41.875308) (xy 75.750588 -41.908488)
			(xy 75.644906 -41.933549) (xy 75.5376 -41.95034) (xy 75.429314 -41.958762) (xy 75.375008 -41.959276)
			(xy 75.322668 -41.958801) (xy 75.218281 -41.950979) (xy 75.114771 -41.935377) (xy 75.012715 -41.912084)
			(xy 74.912686 -41.88123) (xy 74.815242 -41.842986) (xy 74.720929 -41.797568) (xy 74.630274 -41.745228)
			(xy 74.543783 -41.68626) (xy 74.461941 -41.620993) (xy 74.385206 -41.549793) (xy 74.314006 -41.473057)
			(xy 74.248739 -41.391215) (xy 74.189771 -41.304725) (xy 74.137431 -41.214069) (xy 74.092013 -41.119756)
			(xy 74.053769 -41.022312) (xy 74.022915 -40.922283) (xy 73.999622 -40.820228) (xy 73.984021 -40.716717)
			(xy 73.976199 -40.61233) (xy 73.975722 -40.55999) (xy 73.976285 -40.505685) (xy 73.984706 -40.397402)
			(xy 74.001496 -40.290098) (xy 74.026555 -40.184419) (xy 74.059732 -40.081) (xy 74.100826 -39.980465)
			(xy 74.149591 -39.883418) (xy 74.205733 -39.790444) (xy 74.268915 -39.702103) (xy 74.338754 -39.618925)
			(xy 74.414833 -39.541412) (xy 74.496691 -39.470031) (xy 74.583837 -39.405211) (xy 74.629518 -39.375842)
			(xy 74.640694 -39.36873) (xy 74.65314 -39.346124) (xy 74.65314 -39.233856) (xy 74.640694 -39.21125)
			(xy 74.629518 -39.204138) (xy 74.585522 -39.175873) (xy 74.501437 -39.113689) (xy 74.422229 -39.045401)
			(xy 74.348339 -38.97139) (xy 74.280181 -38.89207) (xy 74.218135 -38.807883) (xy 74.162546 -38.719299)
			(xy 74.113726 -38.626812) (xy 74.071946 -38.530939) (xy 74.03744 -38.432215) (xy 74.0104 -38.33119)
			(xy 73.990977 -38.228428) (xy 73.979281 -38.124503) (xy 73.975375 -38.019995) (xy 40.513 -38.019995)
			(xy 40.513 -52.324) (xy 74.548492 -52.324) (xy 74.548938 -52.285712) (xy 74.555556 -52.209422) (xy 74.5687 -52.133982)
			(xy 74.588274 -52.05995) (xy 74.600816 -52.023772) (xy 74.603457 -52.015334) (xy 74.603457 -51.997666)
			(xy 74.600816 -51.989228) (xy 74.58826 -51.953053) (xy 74.568663 -51.879024) (xy 74.555512 -51.803583)
			(xy 74.548903 -51.727289) (xy 74.548492 -51.689) (xy 74.548925 -51.648968) (xy 74.556121 -51.569229)
			(xy 74.570453 -51.490459) (xy 74.591806 -51.413296) (xy 74.620008 -51.338365) (xy 74.654829 -51.26627)
			(xy 74.695989 -51.197597) (xy 74.743154 -51.132901) (xy 74.769218 -51.102514) (xy 74.775568 -51.095402)
			(xy 74.781918 -51.078384) (xy 74.781918 -51.029616) (xy 74.775568 -51.012598) (xy 74.769218 -51.005486)
			(xy 74.743142 -50.975109) (xy 74.695981 -50.91041) (xy 74.654825 -50.841734) (xy 74.620007 -50.769638)
			(xy 74.591808 -50.694705) (xy 74.570457 -50.617541) (xy 74.556126 -50.538771) (xy 74.548931 -50.459032)
			(xy 74.548492 -50.419) (xy 74.548938 -50.380712) (xy 74.555556 -50.304422) (xy 74.5687 -50.228982)
			(xy 74.588274 -50.15495) (xy 74.600816 -50.118772) (xy 74.603457 -50.110334) (xy 74.603457 -50.092666)
			(xy 74.600816 -50.084228) (xy 74.58826 -50.048053) (xy 74.568663 -49.974024) (xy 74.555512 -49.898583)
			(xy 74.548903 -49.822289) (xy 74.548492 -49.784) (xy 74.548967 -49.742898) (xy 74.556552 -49.661043)
			(xy 74.571657 -49.580238) (xy 74.594153 -49.501171) (xy 74.623849 -49.424517) (xy 74.660491 -49.35093)
			(xy 74.703766 -49.281038) (xy 74.753306 -49.215437) (xy 74.808687 -49.154687) (xy 74.869437 -49.099306)
			(xy 74.935038 -49.049766) (xy 75.00493 -49.006491) (xy 75.078517 -48.969849) (xy 75.155171 -48.940153)
			(xy 75.234238 -48.917657) (xy 75.315043 -48.902552) (xy 75.396898 -48.894967) (xy 75.438 -48.894492)
			(xy 75.479102 -48.894967) (xy 75.560957 -48.902552) (xy 75.641762 -48.917657) (xy 75.720829 -48.940153)
			(xy 75.797483 -48.969849) (xy 75.87107 -49.006491) (xy 75.940962 -49.049766) (xy 76.006563 -49.099306)
			(xy 76.067313 -49.154687) (xy 76.122694 -49.215437) (xy 76.172234 -49.281038) (xy 76.215509 -49.35093)
			(xy 76.252151 -49.424517) (xy 76.281847 -49.501171) (xy 76.304343 -49.580238) (xy 76.319448 -49.661043)
			(xy 76.327033 -49.742898) (xy 76.327508 -49.784) (xy 76.327062 -49.822288) (xy 76.320444 -49.898578)
			(xy 76.3073 -49.974018) (xy 76.287726 -50.04805) (xy 76.275184 -50.084228) (xy 76.272543 -50.092666)
			(xy 76.272543 -50.110334) (xy 76.275184 -50.118772) (xy 76.28774 -50.154947) (xy 76.307337 -50.228976)
			(xy 76.320488 -50.304417) (xy 76.327097 -50.380711) (xy 76.327508 -50.419) (xy 76.327075 -50.459032)
			(xy 76.319879 -50.538771) (xy 76.305547 -50.617541) (xy 76.284194 -50.694704) (xy 76.255992 -50.769635)
			(xy 76.221171 -50.84173) (xy 76.180011 -50.910403) (xy 76.132846 -50.975099) (xy 76.106782 -51.005486)
			(xy 76.100432 -51.012598) (xy 76.094082 -51.029616) (xy 76.094082 -51.078384) (xy 76.100432 -51.095402)
			(xy 76.106782 -51.102514) (xy 76.132858 -51.132891) (xy 76.180019 -51.19759) (xy 76.221175 -51.266266)
			(xy 76.255993 -51.338362) (xy 76.284192 -51.413295) (xy 76.305543 -51.490459) (xy 76.319874 -51.569229)
			(xy 76.327069 -51.648968) (xy 76.327508 -51.689) (xy 76.327062 -51.727288) (xy 76.320444 -51.803578)
			(xy 76.3073 -51.879018) (xy 76.287726 -51.95305) (xy 76.275184 -51.989228) (xy 76.272543 -51.997666)
			(xy 76.272543 -52.015334) (xy 76.275184 -52.023772) (xy 76.28774 -52.059947) (xy 76.307337 -52.133976)
			(xy 76.320488 -52.209417) (xy 76.327097 -52.285711) (xy 76.327508 -52.324) (xy 80.009492 -52.324)
			(xy 80.009938 -52.285712) (xy 80.016556 -52.209422) (xy 80.0297 -52.133982) (xy 80.049274 -52.05995)
			(xy 80.061816 -52.023772) (xy 80.064457 -52.015334) (xy 80.064457 -51.997666) (xy 80.061816 -51.989228)
			(xy 80.04926 -51.953053) (xy 80.029663 -51.879024) (xy 80.016512 -51.803583) (xy 80.009903 -51.727289)
			(xy 80.009492 -51.689) (xy 80.009925 -51.648968) (xy 80.017121 -51.569229) (xy 80.031453 -51.490459)
			(xy 80.052806 -51.413296) (xy 80.081008 -51.338365) (xy 80.115829 -51.26627) (xy 80.156989 -51.197597)
			(xy 80.204154 -51.132901) (xy 80.230218 -51.102514) (xy 80.236568 -51.095402) (xy 80.242918 -51.078384)
			(xy 80.242918 -51.029616) (xy 80.236568 -51.012598) (xy 80.230218 -51.005486) (xy 80.204142 -50.975109)
			(xy 80.156981 -50.91041) (xy 80.115825 -50.841734) (xy 80.081007 -50.769638) (xy 80.052808 -50.694705)
			(xy 80.031457 -50.617541) (xy 80.017126 -50.538771) (xy 80.009931 -50.459032) (xy 80.009492 -50.419)
			(xy 80.009938 -50.380712) (xy 80.016556 -50.304422) (xy 80.0297 -50.228982) (xy 80.049274 -50.15495)
			(xy 80.061816 -50.118772) (xy 80.064457 -50.110334) (xy 80.064457 -50.092666) (xy 80.061816 -50.084228)
			(xy 80.04926 -50.048053) (xy 80.029663 -49.974024) (xy 80.016512 -49.898583) (xy 80.009903 -49.822289)
			(xy 80.009492 -49.784) (xy 80.009967 -49.742898) (xy 80.017552 -49.661043) (xy 80.032657 -49.580238)
			(xy 80.055153 -49.501171) (xy 80.084849 -49.424517) (xy 80.121491 -49.35093) (xy 80.164766 -49.281038)
			(xy 80.214306 -49.215437) (xy 80.269687 -49.154687) (xy 80.330437 -49.099306) (xy 80.396038 -49.049766)
			(xy 80.46593 -49.006491) (xy 80.539517 -48.969849) (xy 80.616171 -48.940153) (xy 80.695238 -48.917657)
			(xy 80.776043 -48.902552) (xy 80.857898 -48.894967) (xy 80.899 -48.894492) (xy 80.940102 -48.894967)
			(xy 81.021957 -48.902552) (xy 81.102762 -48.917657) (xy 81.181829 -48.940153) (xy 81.258483 -48.969849)
			(xy 81.33207 -49.006491) (xy 81.401962 -49.049766) (xy 81.467563 -49.099306) (xy 81.528313 -49.154687)
			(xy 81.583694 -49.215437) (xy 81.633234 -49.281038) (xy 81.676509 -49.35093) (xy 81.713151 -49.424517)
			(xy 81.742847 -49.501171) (xy 81.765343 -49.580238) (xy 81.780448 -49.661043) (xy 81.788033 -49.742898)
			(xy 81.788508 -49.784) (xy 81.788062 -49.822288) (xy 81.781444 -49.898578) (xy 81.7683 -49.974018)
			(xy 81.748726 -50.04805) (xy 81.736184 -50.084228) (xy 81.733543 -50.092666) (xy 81.733543 -50.110334)
			(xy 81.736184 -50.118772) (xy 81.74874 -50.154947) (xy 81.768337 -50.228976) (xy 81.781488 -50.304417)
			(xy 81.788097 -50.380711) (xy 81.788508 -50.419) (xy 81.788075 -50.459032) (xy 81.780879 -50.538771)
			(xy 81.766547 -50.617541) (xy 81.745194 -50.694704) (xy 81.716992 -50.769635) (xy 81.682171 -50.84173)
			(xy 81.641011 -50.910403) (xy 81.593846 -50.975099) (xy 81.567782 -51.005486) (xy 81.561432 -51.012598)
			(xy 81.555082 -51.029616) (xy 81.555082 -51.078384) (xy 81.561432 -51.095402) (xy 81.567782 -51.102514)
			(xy 81.593858 -51.132891) (xy 81.641019 -51.19759) (xy 81.682175 -51.266266) (xy 81.716993 -51.338362)
			(xy 81.745192 -51.413295) (xy 81.766543 -51.490459) (xy 81.780874 -51.569229) (xy 81.788069 -51.648968)
			(xy 81.788508 -51.689) (xy 81.788062 -51.727288) (xy 81.781444 -51.803578) (xy 81.7683 -51.879018)
			(xy 81.748726 -51.95305) (xy 81.736184 -51.989228) (xy 81.733543 -51.997666) (xy 81.733543 -52.015334)
			(xy 81.736184 -52.023772) (xy 81.74874 -52.059947) (xy 81.768337 -52.133976) (xy 81.781488 -52.209417)
			(xy 81.788097 -52.285711) (xy 81.788508 -52.324) (xy 85.470492 -52.324) (xy 85.470938 -52.285712)
			(xy 85.477556 -52.209422) (xy 85.4907 -52.133982) (xy 85.510274 -52.05995) (xy 85.522816 -52.023772)
			(xy 85.525457 -52.015334) (xy 85.525457 -51.997666) (xy 85.522816 -51.989228) (xy 85.51026 -51.953053)
			(xy 85.490663 -51.879024) (xy 85.477512 -51.803583) (xy 85.470903 -51.727289) (xy 85.470492 -51.689)
			(xy 85.470925 -51.648968) (xy 85.478121 -51.569229) (xy 85.492453 -51.490459) (xy 85.513806 -51.413296)
			(xy 85.542008 -51.338365) (xy 85.576829 -51.26627) (xy 85.617989 -51.197597) (xy 85.665154 -51.132901)
			(xy 85.691218 -51.102514) (xy 85.697568 -51.095402) (xy 85.703918 -51.078384) (xy 85.703918 -51.029616)
			(xy 85.697568 -51.012598) (xy 85.691218 -51.005486) (xy 85.665142 -50.975109) (xy 85.617981 -50.91041)
			(xy 85.576825 -50.841734) (xy 85.542007 -50.769638) (xy 85.513808 -50.694705) (xy 85.492457 -50.617541)
			(xy 85.478126 -50.538771) (xy 85.470931 -50.459032) (xy 85.470492 -50.419) (xy 85.470938 -50.380712)
			(xy 85.477556 -50.304422) (xy 85.4907 -50.228982) (xy 85.510274 -50.15495) (xy 85.522816 -50.118772)
			(xy 85.525457 -50.110334) (xy 85.525457 -50.092666) (xy 85.522816 -50.084228) (xy 85.51026 -50.048053)
			(xy 85.490663 -49.974024) (xy 85.477512 -49.898583) (xy 85.470903 -49.822289) (xy 85.470492 -49.784)
			(xy 85.470967 -49.742898) (xy 85.478552 -49.661043) (xy 85.493657 -49.580238) (xy 85.516153 -49.501171)
			(xy 85.545849 -49.424517) (xy 85.582491 -49.35093) (xy 85.625766 -49.281038) (xy 85.675306 -49.215437)
			(xy 85.730687 -49.154687) (xy 85.791437 -49.099306) (xy 85.857038 -49.049766) (xy 85.92693 -49.006491)
			(xy 86.000517 -48.969849) (xy 86.077171 -48.940153) (xy 86.156238 -48.917657) (xy 86.237043 -48.902552)
			(xy 86.318898 -48.894967) (xy 86.36 -48.894492) (xy 86.401102 -48.894967) (xy 86.482957 -48.902552)
			(xy 86.563762 -48.917657) (xy 86.642829 -48.940153) (xy 86.719483 -48.969849) (xy 86.79307 -49.006491)
			(xy 86.862962 -49.049766) (xy 86.928563 -49.099306) (xy 86.989313 -49.154687) (xy 87.044694 -49.215437)
			(xy 87.094234 -49.281038) (xy 87.137509 -49.35093) (xy 87.174151 -49.424517) (xy 87.203847 -49.501171)
			(xy 87.226343 -49.580238) (xy 87.241448 -49.661043) (xy 87.249033 -49.742898) (xy 87.249508 -49.784)
			(xy 87.249062 -49.822288) (xy 87.242444 -49.898578) (xy 87.2293 -49.974018) (xy 87.209726 -50.04805)
			(xy 87.197184 -50.084228) (xy 87.194543 -50.092666) (xy 87.194543 -50.110334) (xy 87.197184 -50.118772)
			(xy 87.20974 -50.154947) (xy 87.229337 -50.228976) (xy 87.242488 -50.304417) (xy 87.249097 -50.380711)
			(xy 87.249508 -50.419) (xy 87.249075 -50.459032) (xy 87.241879 -50.538771) (xy 87.227547 -50.617541)
			(xy 87.206194 -50.694704) (xy 87.177992 -50.769635) (xy 87.143171 -50.84173) (xy 87.102011 -50.910403)
			(xy 87.054846 -50.975099) (xy 87.028782 -51.005486) (xy 87.022432 -51.012598) (xy 87.016082 -51.029616)
			(xy 87.016082 -51.078384) (xy 87.022432 -51.095402) (xy 87.028782 -51.102514) (xy 87.054858 -51.132891)
			(xy 87.102019 -51.19759) (xy 87.143175 -51.266266) (xy 87.177993 -51.338362) (xy 87.206192 -51.413295)
			(xy 87.227543 -51.490459) (xy 87.241874 -51.569229) (xy 87.249069 -51.648968) (xy 87.249508 -51.689)
			(xy 87.249062 -51.727288) (xy 87.242444 -51.803578) (xy 87.2293 -51.879018) (xy 87.209726 -51.95305)
			(xy 87.197184 -51.989228) (xy 87.194543 -51.997666) (xy 87.194543 -52.015334) (xy 87.197184 -52.023772)
			(xy 87.20974 -52.059947) (xy 87.229337 -52.133976) (xy 87.242488 -52.209417) (xy 87.249097 -52.285711)
			(xy 87.249508 -52.324) (xy 90.931492 -52.324) (xy 90.931938 -52.285712) (xy 90.938556 -52.209422)
			(xy 90.9517 -52.133982) (xy 90.971274 -52.05995) (xy 90.983816 -52.023772) (xy 90.986457 -52.015334)
			(xy 90.986457 -51.997666) (xy 90.983816 -51.989228) (xy 90.97126 -51.953053) (xy 90.951663 -51.879024)
			(xy 90.938512 -51.803583) (xy 90.931903 -51.727289) (xy 90.931492 -51.689) (xy 90.931925 -51.648968)
			(xy 90.939121 -51.569229) (xy 90.953453 -51.490459) (xy 90.974806 -51.413296) (xy 91.003008 -51.338365)
			(xy 91.037829 -51.26627) (xy 91.078989 -51.197597) (xy 91.126154 -51.132901) (xy 91.152218 -51.102514)
			(xy 91.158568 -51.095402) (xy 91.164918 -51.078384) (xy 91.164918 -51.029616) (xy 91.158568 -51.012598)
			(xy 91.152218 -51.005486) (xy 91.126142 -50.975109) (xy 91.078981 -50.91041) (xy 91.037825 -50.841734)
			(xy 91.003007 -50.769638) (xy 90.974808 -50.694705) (xy 90.953457 -50.617541) (xy 90.939126 -50.538771)
			(xy 90.931931 -50.459032) (xy 90.931492 -50.419) (xy 90.931938 -50.380712) (xy 90.938556 -50.304422)
			(xy 90.9517 -50.228982) (xy 90.971274 -50.15495) (xy 90.983816 -50.118772) (xy 90.986457 -50.110334)
			(xy 90.986457 -50.092666) (xy 90.983816 -50.084228) (xy 90.97126 -50.048053) (xy 90.951663 -49.974024)
			(xy 90.938512 -49.898583) (xy 90.931903 -49.822289) (xy 90.931492 -49.784) (xy 90.931967 -49.742898)
			(xy 90.939552 -49.661043) (xy 90.954657 -49.580238) (xy 90.977153 -49.501171) (xy 91.006849 -49.424517)
			(xy 91.043491 -49.35093) (xy 91.086766 -49.281038) (xy 91.136306 -49.215437) (xy 91.191687 -49.154687)
			(xy 91.252437 -49.099306) (xy 91.318038 -49.049766) (xy 91.38793 -49.006491) (xy 91.461517 -48.969849)
			(xy 91.538171 -48.940153) (xy 91.617238 -48.917657) (xy 91.698043 -48.902552) (xy 91.779898 -48.894967)
			(xy 91.821 -48.894492) (xy 91.862102 -48.894967) (xy 91.943957 -48.902552) (xy 92.024762 -48.917657)
			(xy 92.103829 -48.940153) (xy 92.180483 -48.969849) (xy 92.25407 -49.006491) (xy 92.323962 -49.049766)
			(xy 92.389563 -49.099306) (xy 92.450313 -49.154687) (xy 92.505694 -49.215437) (xy 92.555234 -49.281038)
			(xy 92.598509 -49.35093) (xy 92.635151 -49.424517) (xy 92.664847 -49.501171) (xy 92.687343 -49.580238)
			(xy 92.702448 -49.661043) (xy 92.710033 -49.742898) (xy 92.710508 -49.784) (xy 92.710062 -49.822288)
			(xy 92.703444 -49.898578) (xy 92.6903 -49.974018) (xy 92.670726 -50.04805) (xy 92.658184 -50.084228)
			(xy 92.655543 -50.092666) (xy 92.655543 -50.110334) (xy 92.658184 -50.118772) (xy 92.67074 -50.154947)
			(xy 92.690337 -50.228976) (xy 92.703488 -50.304417) (xy 92.710097 -50.380711) (xy 92.710508 -50.419)
			(xy 92.710075 -50.459032) (xy 92.702879 -50.538771) (xy 92.688547 -50.617541) (xy 92.667194 -50.694704)
			(xy 92.638992 -50.769635) (xy 92.604171 -50.84173) (xy 92.563011 -50.910403) (xy 92.515846 -50.975099)
			(xy 92.489782 -51.005486) (xy 92.483432 -51.012598) (xy 92.477082 -51.029616) (xy 92.477082 -51.078384)
			(xy 92.483432 -51.095402) (xy 92.489782 -51.102514) (xy 92.515858 -51.132891) (xy 92.563019 -51.19759)
			(xy 92.604175 -51.266266) (xy 92.638993 -51.338362) (xy 92.667192 -51.413295) (xy 92.688543 -51.490459)
			(xy 92.702874 -51.569229) (xy 92.710069 -51.648968) (xy 92.710508 -51.689) (xy 92.710062 -51.727288)
			(xy 92.703444 -51.803578) (xy 92.6903 -51.879018) (xy 92.670726 -51.95305) (xy 92.658184 -51.989228)
			(xy 92.655543 -51.997666) (xy 92.655543 -52.015334) (xy 92.658184 -52.023772) (xy 92.67074 -52.059947)
			(xy 92.690337 -52.133976) (xy 92.703488 -52.209417) (xy 92.710097 -52.285711) (xy 92.710508 -52.324)
			(xy 96.392492 -52.324) (xy 96.392938 -52.285712) (xy 96.399556 -52.209422) (xy 96.4127 -52.133982)
			(xy 96.432274 -52.05995) (xy 96.444816 -52.023772) (xy 96.447457 -52.015334) (xy 96.447457 -51.997666)
			(xy 96.444816 -51.989228) (xy 96.43226 -51.953053) (xy 96.412663 -51.879024) (xy 96.399512 -51.803583)
			(xy 96.392903 -51.727289) (xy 96.392492 -51.689) (xy 96.392925 -51.648968) (xy 96.400121 -51.569229)
			(xy 96.414453 -51.490459) (xy 96.435806 -51.413296) (xy 96.464008 -51.338365) (xy 96.498829 -51.26627)
			(xy 96.539989 -51.197597) (xy 96.587154 -51.132901) (xy 96.613218 -51.102514) (xy 96.619568 -51.095402)
			(xy 96.625918 -51.078384) (xy 96.625918 -51.029616) (xy 96.619568 -51.012598) (xy 96.613218 -51.005486)
			(xy 96.587142 -50.975109) (xy 96.539981 -50.91041) (xy 96.498825 -50.841734) (xy 96.464007 -50.769638)
			(xy 96.435808 -50.694705) (xy 96.414457 -50.617541) (xy 96.400126 -50.538771) (xy 96.392931 -50.459032)
			(xy 96.392492 -50.419) (xy 96.392938 -50.380712) (xy 96.399556 -50.304422) (xy 96.4127 -50.228982)
			(xy 96.432274 -50.15495) (xy 96.444816 -50.118772) (xy 96.447457 -50.110334) (xy 96.447457 -50.092666)
			(xy 96.444816 -50.084228) (xy 96.43226 -50.048053) (xy 96.412663 -49.974024) (xy 96.399512 -49.898583)
			(xy 96.392903 -49.822289) (xy 96.392492 -49.784) (xy 96.392967 -49.742898) (xy 96.400552 -49.661043)
			(xy 96.415657 -49.580238) (xy 96.438153 -49.501171) (xy 96.467849 -49.424517) (xy 96.504491 -49.35093)
			(xy 96.547766 -49.281038) (xy 96.597306 -49.215437) (xy 96.652687 -49.154687) (xy 96.713437 -49.099306)
			(xy 96.779038 -49.049766) (xy 96.84893 -49.006491) (xy 96.922517 -48.969849) (xy 96.999171 -48.940153)
			(xy 97.078238 -48.917657) (xy 97.159043 -48.902552) (xy 97.240898 -48.894967) (xy 97.282 -48.894492)
			(xy 97.323102 -48.894967) (xy 97.404957 -48.902552) (xy 97.485762 -48.917657) (xy 97.564829 -48.940153)
			(xy 97.641483 -48.969849) (xy 97.71507 -49.006491) (xy 97.784962 -49.049766) (xy 97.850563 -49.099306)
			(xy 97.911313 -49.154687) (xy 97.966694 -49.215437) (xy 98.016234 -49.281038) (xy 98.059509 -49.35093)
			(xy 98.096151 -49.424517) (xy 98.125847 -49.501171) (xy 98.148343 -49.580238) (xy 98.163448 -49.661043)
			(xy 98.171033 -49.742898) (xy 98.171508 -49.784) (xy 98.171062 -49.822288) (xy 98.164444 -49.898578)
			(xy 98.1513 -49.974018) (xy 98.131726 -50.04805) (xy 98.119184 -50.084228) (xy 98.116543 -50.092666)
			(xy 98.116543 -50.110334) (xy 98.119184 -50.118772) (xy 98.13174 -50.154947) (xy 98.151337 -50.228976)
			(xy 98.164488 -50.304417) (xy 98.171097 -50.380711) (xy 98.171508 -50.419) (xy 98.171075 -50.459032)
			(xy 98.163879 -50.538771) (xy 98.149547 -50.617541) (xy 98.128194 -50.694704) (xy 98.099992 -50.769635)
			(xy 98.065171 -50.84173) (xy 98.024011 -50.910403) (xy 97.976846 -50.975099) (xy 97.950782 -51.005486)
			(xy 97.944432 -51.012598) (xy 97.938082 -51.029616) (xy 97.938082 -51.078384) (xy 97.944432 -51.095402)
			(xy 97.950782 -51.102514) (xy 97.976858 -51.132891) (xy 98.024019 -51.19759) (xy 98.065175 -51.266266)
			(xy 98.099993 -51.338362) (xy 98.128192 -51.413295) (xy 98.149543 -51.490459) (xy 98.163874 -51.569229)
			(xy 98.171069 -51.648968) (xy 98.171508 -51.689) (xy 98.171062 -51.727288) (xy 98.164444 -51.803578)
			(xy 98.1513 -51.879018) (xy 98.131726 -51.95305) (xy 98.119184 -51.989228) (xy 98.116543 -51.997666)
			(xy 98.116543 -52.015334) (xy 98.119184 -52.023772) (xy 98.13174 -52.059947) (xy 98.151337 -52.133976)
			(xy 98.164488 -52.209417) (xy 98.171097 -52.285711) (xy 98.171508 -52.324) (xy 101.853492 -52.324)
			(xy 101.853938 -52.285712) (xy 101.860556 -52.209422) (xy 101.8737 -52.133982) (xy 101.893274 -52.05995)
			(xy 101.905816 -52.023772) (xy 101.908457 -52.015334) (xy 101.908457 -51.997666) (xy 101.905816 -51.989228)
			(xy 101.89326 -51.953053) (xy 101.873663 -51.879024) (xy 101.860512 -51.803583) (xy 101.853903 -51.727289)
			(xy 101.853492 -51.689) (xy 101.853925 -51.648968) (xy 101.861121 -51.569229) (xy 101.875453 -51.490459)
			(xy 101.896806 -51.413296) (xy 101.925008 -51.338365) (xy 101.959829 -51.26627) (xy 102.000989 -51.197597)
			(xy 102.048154 -51.132901) (xy 102.074218 -51.102514) (xy 102.080568 -51.095402) (xy 102.086918 -51.078384)
			(xy 102.086918 -51.029616) (xy 102.080568 -51.012598) (xy 102.074218 -51.005486) (xy 102.048142 -50.975109)
			(xy 102.000981 -50.91041) (xy 101.959825 -50.841734) (xy 101.925007 -50.769638) (xy 101.896808 -50.694705)
			(xy 101.875457 -50.617541) (xy 101.861126 -50.538771) (xy 101.853931 -50.459032) (xy 101.853492 -50.419)
			(xy 101.853938 -50.380712) (xy 101.860556 -50.304422) (xy 101.8737 -50.228982) (xy 101.893274 -50.15495)
			(xy 101.905816 -50.118772) (xy 101.908457 -50.110334) (xy 101.908457 -50.092666) (xy 101.905816 -50.084228)
			(xy 101.89326 -50.048053) (xy 101.873663 -49.974024) (xy 101.860512 -49.898583) (xy 101.853903 -49.822289)
			(xy 101.853492 -49.784) (xy 101.853967 -49.742898) (xy 101.861552 -49.661043) (xy 101.876657 -49.580238)
			(xy 101.899153 -49.501171) (xy 101.928849 -49.424517) (xy 101.965491 -49.35093) (xy 102.008766 -49.281038)
			(xy 102.058306 -49.215437) (xy 102.113687 -49.154687) (xy 102.174437 -49.099306) (xy 102.240038 -49.049766)
			(xy 102.30993 -49.006491) (xy 102.383517 -48.969849) (xy 102.460171 -48.940153) (xy 102.539238 -48.917657)
			(xy 102.620043 -48.902552) (xy 102.701898 -48.894967) (xy 102.743 -48.894492) (xy 102.784102 -48.894967)
			(xy 102.865957 -48.902552) (xy 102.946762 -48.917657) (xy 103.025829 -48.940153) (xy 103.102483 -48.969849)
			(xy 103.17607 -49.006491) (xy 103.245962 -49.049766) (xy 103.311563 -49.099306) (xy 103.372313 -49.154687)
			(xy 103.427694 -49.215437) (xy 103.477234 -49.281038) (xy 103.520509 -49.35093) (xy 103.557151 -49.424517)
			(xy 103.586847 -49.501171) (xy 103.609343 -49.580238) (xy 103.624448 -49.661043) (xy 103.632033 -49.742898)
			(xy 103.632508 -49.784) (xy 103.632062 -49.822288) (xy 103.625444 -49.898578) (xy 103.6123 -49.974018)
			(xy 103.592726 -50.04805) (xy 103.580184 -50.084228) (xy 103.577543 -50.092666) (xy 103.577543 -50.110334)
			(xy 103.580184 -50.118772) (xy 103.59274 -50.154947) (xy 103.612337 -50.228976) (xy 103.625488 -50.304417)
			(xy 103.632097 -50.380711) (xy 103.632508 -50.419) (xy 103.632075 -50.459032) (xy 103.624879 -50.538771)
			(xy 103.610547 -50.617541) (xy 103.589194 -50.694704) (xy 103.560992 -50.769635) (xy 103.526171 -50.84173)
			(xy 103.485011 -50.910403) (xy 103.437846 -50.975099) (xy 103.411782 -51.005486) (xy 103.405432 -51.012598)
			(xy 103.399082 -51.029616) (xy 103.399082 -51.078384) (xy 103.405432 -51.095402) (xy 103.411782 -51.102514)
			(xy 103.437858 -51.132891) (xy 103.485019 -51.19759) (xy 103.526175 -51.266266) (xy 103.560993 -51.338362)
			(xy 103.589192 -51.413295) (xy 103.610543 -51.490459) (xy 103.624874 -51.569229) (xy 103.632069 -51.648968)
			(xy 103.632508 -51.689) (xy 103.632062 -51.727288) (xy 103.625444 -51.803578) (xy 103.6123 -51.879018)
			(xy 103.592726 -51.95305) (xy 103.580184 -51.989228) (xy 103.577543 -51.997666) (xy 103.577543 -52.015334)
			(xy 103.580184 -52.023772) (xy 103.59274 -52.059947) (xy 103.612337 -52.133976) (xy 103.625488 -52.209417)
			(xy 103.632097 -52.285711) (xy 103.632508 -52.324) (xy 107.314492 -52.324) (xy 107.314938 -52.285712)
			(xy 107.321556 -52.209422) (xy 107.3347 -52.133982) (xy 107.354274 -52.05995) (xy 107.366816 -52.023772)
			(xy 107.369457 -52.015334) (xy 107.369457 -51.997666) (xy 107.366816 -51.989228) (xy 107.35426 -51.953053)
			(xy 107.334663 -51.879024) (xy 107.321512 -51.803583) (xy 107.314903 -51.727289) (xy 107.314492 -51.689)
			(xy 107.314925 -51.648968) (xy 107.322121 -51.569229) (xy 107.336453 -51.490459) (xy 107.357806 -51.413296)
			(xy 107.386008 -51.338365) (xy 107.420829 -51.26627) (xy 107.461989 -51.197597) (xy 107.509154 -51.132901)
			(xy 107.535218 -51.102514) (xy 107.541568 -51.095402) (xy 107.547918 -51.078384) (xy 107.547918 -51.029616)
			(xy 107.541568 -51.012598) (xy 107.535218 -51.005486) (xy 107.509142 -50.975109) (xy 107.461981 -50.91041)
			(xy 107.420825 -50.841734) (xy 107.386007 -50.769638) (xy 107.357808 -50.694705) (xy 107.336457 -50.617541)
			(xy 107.322126 -50.538771) (xy 107.314931 -50.459032) (xy 107.314492 -50.419) (xy 107.314938 -50.380712)
			(xy 107.321556 -50.304422) (xy 107.3347 -50.228982) (xy 107.354274 -50.15495) (xy 107.366816 -50.118772)
			(xy 107.369457 -50.110334) (xy 107.369457 -50.092666) (xy 107.366816 -50.084228) (xy 107.35426 -50.048053)
			(xy 107.334663 -49.974024) (xy 107.321512 -49.898583) (xy 107.314903 -49.822289) (xy 107.314492 -49.784)
			(xy 107.314967 -49.742898) (xy 107.322552 -49.661043) (xy 107.337657 -49.580238) (xy 107.360153 -49.501171)
			(xy 107.389849 -49.424517) (xy 107.426491 -49.35093) (xy 107.469766 -49.281038) (xy 107.519306 -49.215437)
			(xy 107.574687 -49.154687) (xy 107.635437 -49.099306) (xy 107.701038 -49.049766) (xy 107.77093 -49.006491)
			(xy 107.844517 -48.969849) (xy 107.921171 -48.940153) (xy 108.000238 -48.917657) (xy 108.081043 -48.902552)
			(xy 108.162898 -48.894967) (xy 108.204 -48.894492) (xy 108.245102 -48.894967) (xy 108.326957 -48.902552)
			(xy 108.407762 -48.917657) (xy 108.486829 -48.940153) (xy 108.563483 -48.969849) (xy 108.63707 -49.006491)
			(xy 108.706962 -49.049766) (xy 108.772563 -49.099306) (xy 108.833313 -49.154687) (xy 108.888694 -49.215437)
			(xy 108.938234 -49.281038) (xy 108.981509 -49.35093) (xy 109.018151 -49.424517) (xy 109.047847 -49.501171)
			(xy 109.070343 -49.580238) (xy 109.085448 -49.661043) (xy 109.093033 -49.742898) (xy 109.093508 -49.784)
			(xy 109.093062 -49.822288) (xy 109.086444 -49.898578) (xy 109.0733 -49.974018) (xy 109.053726 -50.04805)
			(xy 109.041184 -50.084228) (xy 109.038543 -50.092666) (xy 109.038543 -50.110334) (xy 109.041184 -50.118772)
			(xy 109.05374 -50.154947) (xy 109.073337 -50.228976) (xy 109.086488 -50.304417) (xy 109.093097 -50.380711)
			(xy 109.093508 -50.419) (xy 109.093075 -50.459032) (xy 109.085879 -50.538771) (xy 109.071547 -50.617541)
			(xy 109.050194 -50.694704) (xy 109.021992 -50.769635) (xy 108.987171 -50.84173) (xy 108.946011 -50.910403)
			(xy 108.898846 -50.975099) (xy 108.872782 -51.005486) (xy 108.866432 -51.012598) (xy 108.860082 -51.029616)
			(xy 108.860082 -51.078384) (xy 108.866432 -51.095402) (xy 108.872782 -51.102514) (xy 108.898858 -51.132891)
			(xy 108.946019 -51.19759) (xy 108.987175 -51.266266) (xy 109.021993 -51.338362) (xy 109.050192 -51.413295)
			(xy 109.071543 -51.490459) (xy 109.085874 -51.569229) (xy 109.093069 -51.648968) (xy 109.093508 -51.689)
			(xy 109.093062 -51.727288) (xy 109.086444 -51.803578) (xy 109.0733 -51.879018) (xy 109.053726 -51.95305)
			(xy 109.041184 -51.989228) (xy 109.038543 -51.997666) (xy 109.038543 -52.015334) (xy 109.041184 -52.023772)
			(xy 109.05374 -52.059947) (xy 109.073337 -52.133976) (xy 109.084323 -52.197) (xy 152.653492 -52.197)
			(xy 152.653938 -52.158712) (xy 152.660556 -52.082422) (xy 152.6737 -52.006982) (xy 152.693274 -51.93295)
			(xy 152.705816 -51.896772) (xy 152.708457 -51.888334) (xy 152.708457 -51.870666) (xy 152.705816 -51.862228)
			(xy 152.69326 -51.826053) (xy 152.673663 -51.752024) (xy 152.660512 -51.676583) (xy 152.653903 -51.600289)
			(xy 152.653492 -51.562) (xy 152.653925 -51.521968) (xy 152.661121 -51.442229) (xy 152.675453 -51.363459)
			(xy 152.696806 -51.286296) (xy 152.725008 -51.211365) (xy 152.759829 -51.13927) (xy 152.800989 -51.070597)
			(xy 152.848154 -51.005901) (xy 152.874218 -50.975514) (xy 152.880568 -50.968402) (xy 152.886918 -50.951384)
			(xy 152.886918 -50.902616) (xy 152.880568 -50.885598) (xy 152.874218 -50.878486) (xy 152.848142 -50.848109)
			(xy 152.800981 -50.78341) (xy 152.759825 -50.714734) (xy 152.725007 -50.642638) (xy 152.696808 -50.567705)
			(xy 152.675457 -50.490541) (xy 152.661126 -50.411771) (xy 152.653931 -50.332032) (xy 152.653492 -50.292)
			(xy 152.653938 -50.253712) (xy 152.660556 -50.177422) (xy 152.6737 -50.101982) (xy 152.693274 -50.02795)
			(xy 152.705816 -49.991772) (xy 152.708457 -49.983334) (xy 152.708457 -49.965666) (xy 152.705816 -49.957228)
			(xy 152.69326 -49.921053) (xy 152.673663 -49.847024) (xy 152.660512 -49.771583) (xy 152.653903 -49.695289)
			(xy 152.653492 -49.657) (xy 152.653967 -49.615898) (xy 152.661552 -49.534043) (xy 152.676657 -49.453238)
			(xy 152.699153 -49.374171) (xy 152.728849 -49.297517) (xy 152.765491 -49.22393) (xy 152.808766 -49.154038)
			(xy 152.858306 -49.088437) (xy 152.913687 -49.027687) (xy 152.974437 -48.972306) (xy 153.040038 -48.922766)
			(xy 153.10993 -48.879491) (xy 153.183517 -48.842849) (xy 153.260171 -48.813153) (xy 153.339238 -48.790657)
			(xy 153.420043 -48.775552) (xy 153.501898 -48.767967) (xy 153.543 -48.767492) (xy 153.584102 -48.767967)
			(xy 153.665957 -48.775552) (xy 153.746762 -48.790657) (xy 153.825829 -48.813153) (xy 153.902483 -48.842849)
			(xy 153.97607 -48.879491) (xy 154.045962 -48.922766) (xy 154.111563 -48.972306) (xy 154.172313 -49.027687)
			(xy 154.227694 -49.088437) (xy 154.277234 -49.154038) (xy 154.320509 -49.22393) (xy 154.357151 -49.297517)
			(xy 154.386847 -49.374171) (xy 154.409343 -49.453238) (xy 154.424448 -49.534043) (xy 154.432033 -49.615898)
			(xy 154.432508 -49.657) (xy 154.432062 -49.695288) (xy 154.425444 -49.771578) (xy 154.4123 -49.847018)
			(xy 154.392726 -49.92105) (xy 154.380184 -49.957228) (xy 154.377543 -49.965666) (xy 154.377543 -49.983334)
			(xy 154.380184 -49.991772) (xy 154.39274 -50.027947) (xy 154.412337 -50.101976) (xy 154.425488 -50.177417)
			(xy 154.432097 -50.253711) (xy 154.432508 -50.292) (xy 154.432075 -50.332032) (xy 154.424879 -50.411771)
			(xy 154.410547 -50.490541) (xy 154.389194 -50.567704) (xy 154.360992 -50.642635) (xy 154.326171 -50.71473)
			(xy 154.285011 -50.783403) (xy 154.237846 -50.848099) (xy 154.211782 -50.878486) (xy 154.205432 -50.885598)
			(xy 154.199082 -50.902616) (xy 154.199082 -50.951384) (xy 154.205432 -50.968402) (xy 154.211782 -50.975514)
			(xy 154.237858 -51.005891) (xy 154.285019 -51.07059) (xy 154.326175 -51.139266) (xy 154.360993 -51.211362)
			(xy 154.389192 -51.286295) (xy 154.410543 -51.363459) (xy 154.424874 -51.442229) (xy 154.432069 -51.521968)
			(xy 154.432508 -51.562) (xy 154.432062 -51.600288) (xy 154.425444 -51.676578) (xy 154.4123 -51.752018)
			(xy 154.392726 -51.82605) (xy 154.380184 -51.862228) (xy 154.377543 -51.870666) (xy 154.377543 -51.888334)
			(xy 154.380184 -51.896772) (xy 154.39274 -51.932947) (xy 154.412337 -52.006976) (xy 154.425488 -52.082417)
			(xy 154.432097 -52.158711) (xy 154.432508 -52.197) (xy 158.114492 -52.197) (xy 158.114938 -52.158712)
			(xy 158.121556 -52.082422) (xy 158.1347 -52.006982) (xy 158.154274 -51.93295) (xy 158.166816 -51.896772)
			(xy 158.169457 -51.888334) (xy 158.169457 -51.870666) (xy 158.166816 -51.862228) (xy 158.15426 -51.826053)
			(xy 158.134663 -51.752024) (xy 158.121512 -51.676583) (xy 158.114903 -51.600289) (xy 158.114492 -51.562)
			(xy 158.114925 -51.521968) (xy 158.122121 -51.442229) (xy 158.136453 -51.363459) (xy 158.157806 -51.286296)
			(xy 158.186008 -51.211365) (xy 158.220829 -51.13927) (xy 158.261989 -51.070597) (xy 158.309154 -51.005901)
			(xy 158.335218 -50.975514) (xy 158.341568 -50.968402) (xy 158.347918 -50.951384) (xy 158.347918 -50.902616)
			(xy 158.341568 -50.885598) (xy 158.335218 -50.878486) (xy 158.309142 -50.848109) (xy 158.261981 -50.78341)
			(xy 158.220825 -50.714734) (xy 158.186007 -50.642638) (xy 158.157808 -50.567705) (xy 158.136457 -50.490541)
			(xy 158.122126 -50.411771) (xy 158.114931 -50.332032) (xy 158.114492 -50.292) (xy 158.114938 -50.253712)
			(xy 158.121556 -50.177422) (xy 158.1347 -50.101982) (xy 158.154274 -50.02795) (xy 158.166816 -49.991772)
			(xy 158.169457 -49.983334) (xy 158.169457 -49.965666) (xy 158.166816 -49.957228) (xy 158.15426 -49.921053)
			(xy 158.134663 -49.847024) (xy 158.121512 -49.771583) (xy 158.114903 -49.695289) (xy 158.114492 -49.657)
			(xy 158.114967 -49.615898) (xy 158.122552 -49.534043) (xy 158.137657 -49.453238) (xy 158.160153 -49.374171)
			(xy 158.189849 -49.297517) (xy 158.226491 -49.22393) (xy 158.269766 -49.154038) (xy 158.319306 -49.088437)
			(xy 158.374687 -49.027687) (xy 158.435437 -48.972306) (xy 158.501038 -48.922766) (xy 158.57093 -48.879491)
			(xy 158.644517 -48.842849) (xy 158.721171 -48.813153) (xy 158.800238 -48.790657) (xy 158.881043 -48.775552)
			(xy 158.962898 -48.767967) (xy 159.004 -48.767492) (xy 159.045102 -48.767967) (xy 159.126957 -48.775552)
			(xy 159.207762 -48.790657) (xy 159.286829 -48.813153) (xy 159.363483 -48.842849) (xy 159.43707 -48.879491)
			(xy 159.506962 -48.922766) (xy 159.572563 -48.972306) (xy 159.633313 -49.027687) (xy 159.688694 -49.088437)
			(xy 159.738234 -49.154038) (xy 159.781509 -49.22393) (xy 159.818151 -49.297517) (xy 159.847847 -49.374171)
			(xy 159.870343 -49.453238) (xy 159.885448 -49.534043) (xy 159.893033 -49.615898) (xy 159.893508 -49.657)
			(xy 159.893062 -49.695288) (xy 159.886444 -49.771578) (xy 159.8733 -49.847018) (xy 159.853726 -49.92105)
			(xy 159.841184 -49.957228) (xy 159.838543 -49.965666) (xy 159.838543 -49.983334) (xy 159.841184 -49.991772)
			(xy 159.85374 -50.027947) (xy 159.873337 -50.101976) (xy 159.886488 -50.177417) (xy 159.893097 -50.253711)
			(xy 159.893508 -50.292) (xy 159.893075 -50.332032) (xy 159.885879 -50.411771) (xy 159.871547 -50.490541)
			(xy 159.850194 -50.567704) (xy 159.821992 -50.642635) (xy 159.787171 -50.71473) (xy 159.746011 -50.783403)
			(xy 159.698846 -50.848099) (xy 159.672782 -50.878486) (xy 159.666432 -50.885598) (xy 159.660082 -50.902616)
			(xy 159.660082 -50.951384) (xy 159.666432 -50.968402) (xy 159.672782 -50.975514) (xy 159.698858 -51.005891)
			(xy 159.746019 -51.07059) (xy 159.787175 -51.139266) (xy 159.821993 -51.211362) (xy 159.850192 -51.286295)
			(xy 159.871543 -51.363459) (xy 159.885874 -51.442229) (xy 159.893069 -51.521968) (xy 159.893508 -51.562)
			(xy 159.893062 -51.600288) (xy 159.886444 -51.676578) (xy 159.8733 -51.752018) (xy 159.853726 -51.82605)
			(xy 159.841184 -51.862228) (xy 159.838543 -51.870666) (xy 159.838543 -51.888334) (xy 159.841184 -51.896772)
			(xy 159.85374 -51.932947) (xy 159.873337 -52.006976) (xy 159.886488 -52.082417) (xy 159.893097 -52.158711)
			(xy 159.893508 -52.197) (xy 163.575492 -52.197) (xy 163.575938 -52.158712) (xy 163.582556 -52.082422)
			(xy 163.5957 -52.006982) (xy 163.615274 -51.93295) (xy 163.627816 -51.896772) (xy 163.630457 -51.888334)
			(xy 163.630457 -51.870666) (xy 163.627816 -51.862228) (xy 163.61526 -51.826053) (xy 163.595663 -51.752024)
			(xy 163.582512 -51.676583) (xy 163.575903 -51.600289) (xy 163.575492 -51.562) (xy 163.575925 -51.521968)
			(xy 163.583121 -51.442229) (xy 163.597453 -51.363459) (xy 163.618806 -51.286296) (xy 163.647008 -51.211365)
			(xy 163.681829 -51.13927) (xy 163.722989 -51.070597) (xy 163.770154 -51.005901) (xy 163.796218 -50.975514)
			(xy 163.802568 -50.968402) (xy 163.808918 -50.951384) (xy 163.808918 -50.902616) (xy 163.802568 -50.885598)
			(xy 163.796218 -50.878486) (xy 163.770142 -50.848109) (xy 163.722981 -50.78341) (xy 163.681825 -50.714734)
			(xy 163.647007 -50.642638) (xy 163.618808 -50.567705) (xy 163.597457 -50.490541) (xy 163.583126 -50.411771)
			(xy 163.575931 -50.332032) (xy 163.575492 -50.292) (xy 163.575938 -50.253712) (xy 163.582556 -50.177422)
			(xy 163.5957 -50.101982) (xy 163.615274 -50.02795) (xy 163.627816 -49.991772) (xy 163.630457 -49.983334)
			(xy 163.630457 -49.965666) (xy 163.627816 -49.957228) (xy 163.61526 -49.921053) (xy 163.595663 -49.847024)
			(xy 163.582512 -49.771583) (xy 163.575903 -49.695289) (xy 163.575492 -49.657) (xy 163.575996 -49.614652)
			(xy 163.584047 -49.530338) (xy 163.600076 -49.447172) (xy 163.623937 -49.365905) (xy 163.655416 -49.287275)
			(xy 163.694227 -49.211994) (xy 163.740017 -49.140742) (xy 163.792373 -49.074166) (xy 163.850821 -49.012868)
			(xy 163.914831 -48.957403) (xy 163.983823 -48.908274) (xy 164.057173 -48.865925) (xy 164.134216 -48.830741)
			(xy 164.214255 -48.803039) (xy 164.296564 -48.783071) (xy 164.380399 -48.771018) (xy 164.465 -48.766988)
			(xy 164.549601 -48.771018) (xy 164.633436 -48.783071) (xy 164.715745 -48.803039) (xy 164.795784 -48.830741)
			(xy 164.872827 -48.865925) (xy 164.946177 -48.908274) (xy 165.015169 -48.957403) (xy 165.079179 -49.012868)
			(xy 165.137627 -49.074166) (xy 165.189983 -49.140742) (xy 165.235773 -49.211994) (xy 165.274584 -49.287275)
			(xy 165.306063 -49.365905) (xy 165.329924 -49.447172) (xy 165.345953 -49.530338) (xy 165.354004 -49.614652)
			(xy 165.354508 -49.657) (xy 165.354062 -49.695288) (xy 165.347444 -49.771578) (xy 165.3343 -49.847018)
			(xy 165.314726 -49.92105) (xy 165.302184 -49.957228) (xy 165.299543 -49.965666) (xy 165.299543 -49.983334)
			(xy 165.302184 -49.991772) (xy 165.31474 -50.027947) (xy 165.334337 -50.101976) (xy 165.347488 -50.177417)
			(xy 165.354097 -50.253711) (xy 165.354508 -50.292) (xy 165.354075 -50.332032) (xy 165.346879 -50.411771)
			(xy 165.332547 -50.490541) (xy 165.311194 -50.567704) (xy 165.282992 -50.642635) (xy 165.248171 -50.71473)
			(xy 165.207011 -50.783403) (xy 165.159846 -50.848099) (xy 165.133782 -50.878486) (xy 165.127432 -50.885598)
			(xy 165.121082 -50.902616) (xy 165.121082 -50.951384) (xy 165.127432 -50.968402) (xy 165.133782 -50.975514)
			(xy 165.159858 -51.005891) (xy 165.207019 -51.07059) (xy 165.248175 -51.139266) (xy 165.282993 -51.211362)
			(xy 165.311192 -51.286295) (xy 165.332543 -51.363459) (xy 165.346874 -51.442229) (xy 165.354069 -51.521968)
			(xy 165.354508 -51.562) (xy 165.354062 -51.600288) (xy 165.347444 -51.676578) (xy 165.3343 -51.752018)
			(xy 165.314726 -51.82605) (xy 165.302184 -51.862228) (xy 165.299543 -51.870666) (xy 165.299543 -51.888334)
			(xy 165.302184 -51.896772) (xy 165.31474 -51.932947) (xy 165.334337 -52.006976) (xy 165.347488 -52.082417)
			(xy 165.354097 -52.158711) (xy 165.354508 -52.197) (xy 169.036492 -52.197) (xy 169.036938 -52.158712)
			(xy 169.043556 -52.082422) (xy 169.0567 -52.006982) (xy 169.076274 -51.93295) (xy 169.088816 -51.896772)
			(xy 169.091457 -51.888334) (xy 169.091457 -51.870666) (xy 169.088816 -51.862228) (xy 169.07626 -51.826053)
			(xy 169.056663 -51.752024) (xy 169.043512 -51.676583) (xy 169.036903 -51.600289) (xy 169.036492 -51.562)
			(xy 169.036925 -51.521968) (xy 169.044121 -51.442229) (xy 169.058453 -51.363459) (xy 169.079806 -51.286296)
			(xy 169.108008 -51.211365) (xy 169.142829 -51.13927) (xy 169.183989 -51.070597) (xy 169.231154 -51.005901)
			(xy 169.257218 -50.975514) (xy 169.263568 -50.968402) (xy 169.269918 -50.951384) (xy 169.269918 -50.902616)
			(xy 169.263568 -50.885598) (xy 169.257218 -50.878486) (xy 169.231142 -50.848109) (xy 169.183981 -50.78341)
			(xy 169.142825 -50.714734) (xy 169.108007 -50.642638) (xy 169.079808 -50.567705) (xy 169.058457 -50.490541)
			(xy 169.044126 -50.411771) (xy 169.036931 -50.332032) (xy 169.036492 -50.292) (xy 169.036938 -50.253712)
			(xy 169.043556 -50.177422) (xy 169.0567 -50.101982) (xy 169.076274 -50.02795) (xy 169.088816 -49.991772)
			(xy 169.091457 -49.983334) (xy 169.091457 -49.965666) (xy 169.088816 -49.957228) (xy 169.07626 -49.921053)
			(xy 169.056663 -49.847024) (xy 169.043512 -49.771583) (xy 169.036903 -49.695289) (xy 169.036492 -49.657)
			(xy 169.036996 -49.614652) (xy 169.045047 -49.530338) (xy 169.061076 -49.447172) (xy 169.084937 -49.365905)
			(xy 169.116416 -49.287275) (xy 169.155227 -49.211994) (xy 169.201017 -49.140742) (xy 169.253373 -49.074166)
			(xy 169.311821 -49.012868) (xy 169.375831 -48.957403) (xy 169.444823 -48.908274) (xy 169.518173 -48.865925)
			(xy 169.595216 -48.830741) (xy 169.675255 -48.803039) (xy 169.757564 -48.783071) (xy 169.841399 -48.771018)
			(xy 169.926 -48.766988) (xy 170.010601 -48.771018) (xy 170.094436 -48.783071) (xy 170.176745 -48.803039)
			(xy 170.256784 -48.830741) (xy 170.333827 -48.865925) (xy 170.407177 -48.908274) (xy 170.476169 -48.957403)
			(xy 170.540179 -49.012868) (xy 170.598627 -49.074166) (xy 170.650983 -49.140742) (xy 170.696773 -49.211994)
			(xy 170.735584 -49.287275) (xy 170.767063 -49.365905) (xy 170.790924 -49.447172) (xy 170.806953 -49.530338)
			(xy 170.815004 -49.614652) (xy 170.815508 -49.657) (xy 170.815062 -49.695288) (xy 170.808444 -49.771578)
			(xy 170.7953 -49.847018) (xy 170.775726 -49.92105) (xy 170.763184 -49.957228) (xy 170.760543 -49.965666)
			(xy 170.760543 -49.983334) (xy 170.763184 -49.991772) (xy 170.77574 -50.027947) (xy 170.795337 -50.101976)
			(xy 170.808488 -50.177417) (xy 170.815097 -50.253711) (xy 170.815508 -50.292) (xy 170.815075 -50.332032)
			(xy 170.807879 -50.411771) (xy 170.793547 -50.490541) (xy 170.772194 -50.567704) (xy 170.743992 -50.642635)
			(xy 170.709171 -50.71473) (xy 170.668011 -50.783403) (xy 170.620846 -50.848099) (xy 170.594782 -50.878486)
			(xy 170.588432 -50.885598) (xy 170.582082 -50.902616) (xy 170.582082 -50.951384) (xy 170.588432 -50.968402)
			(xy 170.594782 -50.975514) (xy 170.620858 -51.005891) (xy 170.668019 -51.07059) (xy 170.709175 -51.139266)
			(xy 170.743993 -51.211362) (xy 170.772192 -51.286295) (xy 170.793543 -51.363459) (xy 170.807874 -51.442229)
			(xy 170.815069 -51.521968) (xy 170.815508 -51.562) (xy 170.815062 -51.600288) (xy 170.808444 -51.676578)
			(xy 170.7953 -51.752018) (xy 170.775726 -51.82605) (xy 170.763184 -51.862228) (xy 170.760543 -51.870666)
			(xy 170.760543 -51.888334) (xy 170.763184 -51.896772) (xy 170.77574 -51.932947) (xy 170.795337 -52.006976)
			(xy 170.808488 -52.082417) (xy 170.815097 -52.158711) (xy 170.815508 -52.197) (xy 174.497492 -52.197)
			(xy 174.497938 -52.158712) (xy 174.504556 -52.082422) (xy 174.5177 -52.006982) (xy 174.537274 -51.93295)
			(xy 174.549816 -51.896772) (xy 174.552457 -51.888334) (xy 174.552457 -51.870666) (xy 174.549816 -51.862228)
			(xy 174.53726 -51.826053) (xy 174.517663 -51.752024) (xy 174.504512 -51.676583) (xy 174.497903 -51.600289)
			(xy 174.497492 -51.562) (xy 174.497925 -51.521968) (xy 174.505121 -51.442229) (xy 174.519453 -51.363459)
			(xy 174.540806 -51.286296) (xy 174.569008 -51.211365) (xy 174.603829 -51.13927) (xy 174.644989 -51.070597)
			(xy 174.692154 -51.005901) (xy 174.718218 -50.975514) (xy 174.724568 -50.968402) (xy 174.730918 -50.951384)
			(xy 174.730918 -50.902616) (xy 174.724568 -50.885598) (xy 174.718218 -50.878486) (xy 174.692142 -50.848109)
			(xy 174.644981 -50.78341) (xy 174.603825 -50.714734) (xy 174.569007 -50.642638) (xy 174.540808 -50.567705)
			(xy 174.519457 -50.490541) (xy 174.505126 -50.411771) (xy 174.497931 -50.332032) (xy 174.497492 -50.292)
			(xy 174.497938 -50.253712) (xy 174.504556 -50.177422) (xy 174.5177 -50.101982) (xy 174.537274 -50.02795)
			(xy 174.549816 -49.991772) (xy 174.552457 -49.983334) (xy 174.552457 -49.965666) (xy 174.549816 -49.957228)
			(xy 174.53726 -49.921053) (xy 174.517663 -49.847024) (xy 174.504512 -49.771583) (xy 174.497903 -49.695289)
			(xy 174.497492 -49.657) (xy 174.497996 -49.614652) (xy 174.506047 -49.530338) (xy 174.522076 -49.447172)
			(xy 174.545937 -49.365905) (xy 174.577416 -49.287275) (xy 174.616227 -49.211994) (xy 174.662017 -49.140742)
			(xy 174.714373 -49.074166) (xy 174.772821 -49.012868) (xy 174.836831 -48.957403) (xy 174.905823 -48.908274)
			(xy 174.979173 -48.865925) (xy 175.056216 -48.830741) (xy 175.136255 -48.803039) (xy 175.218564 -48.783071)
			(xy 175.302399 -48.771018) (xy 175.387 -48.766988) (xy 175.471601 -48.771018) (xy 175.555436 -48.783071)
			(xy 175.637745 -48.803039) (xy 175.717784 -48.830741) (xy 175.794827 -48.865925) (xy 175.868177 -48.908274)
			(xy 175.937169 -48.957403) (xy 176.001179 -49.012868) (xy 176.059627 -49.074166) (xy 176.111983 -49.140742)
			(xy 176.157773 -49.211994) (xy 176.196584 -49.287275) (xy 176.228063 -49.365905) (xy 176.251924 -49.447172)
			(xy 176.267953 -49.530338) (xy 176.276004 -49.614652) (xy 176.276508 -49.657) (xy 176.276062 -49.695288)
			(xy 176.269444 -49.771578) (xy 176.2563 -49.847018) (xy 176.236726 -49.92105) (xy 176.224184 -49.957228)
			(xy 176.221543 -49.965666) (xy 176.221543 -49.983334) (xy 176.224184 -49.991772) (xy 176.23674 -50.027947)
			(xy 176.256337 -50.101976) (xy 176.269488 -50.177417) (xy 176.276097 -50.253711) (xy 176.276508 -50.292)
			(xy 176.276075 -50.332032) (xy 176.268879 -50.411771) (xy 176.254547 -50.490541) (xy 176.233194 -50.567704)
			(xy 176.204992 -50.642635) (xy 176.170171 -50.71473) (xy 176.129011 -50.783403) (xy 176.081846 -50.848099)
			(xy 176.055782 -50.878486) (xy 176.049432 -50.885598) (xy 176.043082 -50.902616) (xy 176.043082 -50.951384)
			(xy 176.049432 -50.968402) (xy 176.055782 -50.975514) (xy 176.081858 -51.005891) (xy 176.129019 -51.07059)
			(xy 176.170175 -51.139266) (xy 176.204993 -51.211362) (xy 176.233192 -51.286295) (xy 176.254543 -51.363459)
			(xy 176.268874 -51.442229) (xy 176.276069 -51.521968) (xy 176.276508 -51.562) (xy 176.276062 -51.600288)
			(xy 176.269444 -51.676578) (xy 176.2563 -51.752018) (xy 176.236726 -51.82605) (xy 176.224184 -51.862228)
			(xy 176.221543 -51.870666) (xy 176.221543 -51.888334) (xy 176.224184 -51.896772) (xy 176.23674 -51.932947)
			(xy 176.256337 -52.006976) (xy 176.269488 -52.082417) (xy 176.276097 -52.158711) (xy 176.276508 -52.197)
			(xy 179.955952 -52.197) (xy 179.956401 -52.158712) (xy 179.963018 -52.082422) (xy 179.976162 -52.006983)
			(xy 179.995734 -51.93295) (xy 180.008276 -51.896772) (xy 180.010919 -51.888334) (xy 180.010919 -51.870666)
			(xy 180.008276 -51.862228) (xy 179.995718 -51.826054) (xy 179.976122 -51.752024) (xy 179.962971 -51.676583)
			(xy 179.956363 -51.600289) (xy 179.955952 -51.562) (xy 179.95637 -51.521968) (xy 179.963566 -51.442228)
			(xy 179.9779 -51.363457) (xy 179.999254 -51.286294) (xy 180.027458 -51.211362) (xy 180.062282 -51.139268)
			(xy 180.103445 -51.070596) (xy 180.150613 -51.005901) (xy 180.176678 -50.975514) (xy 180.183028 -50.968402)
			(xy 180.189378 -50.951384) (xy 180.189378 -50.902616) (xy 180.183028 -50.885598) (xy 180.176678 -50.878486)
			(xy 180.150612 -50.848101) (xy 180.103449 -50.783403) (xy 180.062291 -50.71473) (xy 180.027471 -50.642635)
			(xy 179.99927 -50.567703) (xy 179.977918 -50.49054) (xy 179.963586 -50.41177) (xy 179.956391 -50.332031)
			(xy 179.955952 -50.292) (xy 179.956401 -50.253712) (xy 179.963018 -50.177422) (xy 179.976162 -50.101983)
			(xy 179.995734 -50.02795) (xy 180.008276 -49.991772) (xy 180.010919 -49.983334) (xy 180.010919 -49.965666)
			(xy 180.008276 -49.957228) (xy 179.995718 -49.921054) (xy 179.976122 -49.847024) (xy 179.962971 -49.771583)
			(xy 179.956363 -49.695289) (xy 179.955952 -49.657) (xy 179.956456 -49.614652) (xy 179.964507 -49.530338)
			(xy 179.980536 -49.447172) (xy 180.004397 -49.365905) (xy 180.035876 -49.287275) (xy 180.074687 -49.211994)
			(xy 180.120477 -49.140742) (xy 180.172833 -49.074166) (xy 180.231281 -49.012868) (xy 180.295291 -48.957403)
			(xy 180.364283 -48.908274) (xy 180.437633 -48.865925) (xy 180.514676 -48.830741) (xy 180.594715 -48.803039)
			(xy 180.677024 -48.783071) (xy 180.760859 -48.771018) (xy 180.84546 -48.766988) (xy 180.930061 -48.771018)
			(xy 181.013896 -48.783071) (xy 181.096205 -48.803039) (xy 181.176244 -48.830741) (xy 181.253287 -48.865925)
			(xy 181.326637 -48.908274) (xy 181.395629 -48.957403) (xy 181.459639 -49.012868) (xy 181.518087 -49.074166)
			(xy 181.570443 -49.140742) (xy 181.616233 -49.211994) (xy 181.655044 -49.287275) (xy 181.686523 -49.365905)
			(xy 181.710384 -49.447172) (xy 181.726413 -49.530338) (xy 181.734464 -49.614652) (xy 181.734968 -49.657)
			(xy 181.734524 -49.695288) (xy 181.727906 -49.771578) (xy 181.714761 -49.847018) (xy 181.695187 -49.92105)
			(xy 181.682644 -49.957228) (xy 181.680001 -49.965666) (xy 181.680001 -49.983334) (xy 181.682644 -49.991772)
			(xy 181.695203 -50.027946) (xy 181.714798 -50.101975) (xy 181.727949 -50.177417) (xy 181.734557 -50.25371)
			(xy 181.734968 -50.292) (xy 181.734545 -50.332032) (xy 181.727349 -50.411772) (xy 181.713016 -50.490542)
			(xy 181.691662 -50.567705) (xy 181.663459 -50.642637) (xy 181.628635 -50.714731) (xy 181.587474 -50.783404)
			(xy 181.540307 -50.848099) (xy 181.514242 -50.878486) (xy 181.507892 -50.885598) (xy 181.501542 -50.902616)
			(xy 181.501542 -50.951384) (xy 181.507892 -50.968402) (xy 181.514242 -50.975514) (xy 181.540311 -51.005897)
			(xy 181.587474 -51.070594) (xy 181.628631 -51.139269) (xy 181.663451 -51.211364) (xy 181.69165 -51.286296)
			(xy 181.713003 -51.363459) (xy 181.727334 -51.442229) (xy 181.734529 -51.521968) (xy 181.734968 -51.562)
			(xy 181.734524 -51.600288) (xy 181.727906 -51.676578) (xy 181.714761 -51.752018) (xy 181.695187 -51.82605)
			(xy 181.682644 -51.862228) (xy 181.680001 -51.870666) (xy 181.680001 -51.888334) (xy 181.682644 -51.896772)
			(xy 181.695203 -51.932946) (xy 181.714798 -52.006975) (xy 181.727949 -52.082417) (xy 181.734557 -52.15871)
			(xy 181.734968 -52.197) (xy 185.416952 -52.197) (xy 185.417401 -52.158712) (xy 185.424018 -52.082422)
			(xy 185.437162 -52.006983) (xy 185.456734 -51.93295) (xy 185.469276 -51.896772) (xy 185.471919 -51.888334)
			(xy 185.471919 -51.870666) (xy 185.469276 -51.862228) (xy 185.456718 -51.826054) (xy 185.437122 -51.752024)
			(xy 185.423971 -51.676583) (xy 185.417363 -51.600289) (xy 185.416952 -51.562) (xy 185.41737 -51.521968)
			(xy 185.424566 -51.442228) (xy 185.4389 -51.363457) (xy 185.460254 -51.286294) (xy 185.488458 -51.211362)
			(xy 185.523282 -51.139268) (xy 185.564445 -51.070596) (xy 185.611613 -51.005901) (xy 185.637678 -50.975514)
			(xy 185.644028 -50.968402) (xy 185.650378 -50.951384) (xy 185.650378 -50.902616) (xy 185.644028 -50.885598)
			(xy 185.637678 -50.878486) (xy 185.611612 -50.848101) (xy 185.564449 -50.783403) (xy 185.523291 -50.71473)
			(xy 185.488471 -50.642635) (xy 185.46027 -50.567703) (xy 185.438918 -50.49054) (xy 185.424586 -50.41177)
			(xy 185.417391 -50.332031) (xy 185.416952 -50.292) (xy 185.417401 -50.253712) (xy 185.424018 -50.177422)
			(xy 185.437162 -50.101983) (xy 185.456734 -50.02795) (xy 185.469276 -49.991772) (xy 185.471919 -49.983334)
			(xy 185.471919 -49.965666) (xy 185.469276 -49.957228) (xy 185.456718 -49.921054) (xy 185.437122 -49.847024)
			(xy 185.423971 -49.771583) (xy 185.417363 -49.695289) (xy 185.416952 -49.657) (xy 185.417456 -49.614652)
			(xy 185.425507 -49.530338) (xy 185.441536 -49.447172) (xy 185.465397 -49.365905) (xy 185.496876 -49.287275)
			(xy 185.535687 -49.211994) (xy 185.581477 -49.140742) (xy 185.633833 -49.074166) (xy 185.692281 -49.012868)
			(xy 185.756291 -48.957403) (xy 185.825283 -48.908274) (xy 185.898633 -48.865925) (xy 185.975676 -48.830741)
			(xy 186.055715 -48.803039) (xy 186.138024 -48.783071) (xy 186.221859 -48.771018) (xy 186.30646 -48.766988)
			(xy 186.391061 -48.771018) (xy 186.474896 -48.783071) (xy 186.557205 -48.803039) (xy 186.637244 -48.830741)
			(xy 186.714287 -48.865925) (xy 186.787637 -48.908274) (xy 186.856629 -48.957403) (xy 186.920639 -49.012868)
			(xy 186.979087 -49.074166) (xy 187.031443 -49.140742) (xy 187.077233 -49.211994) (xy 187.116044 -49.287275)
			(xy 187.147523 -49.365905) (xy 187.171384 -49.447172) (xy 187.187413 -49.530338) (xy 187.195464 -49.614652)
			(xy 187.195968 -49.657) (xy 187.195524 -49.695288) (xy 187.188906 -49.771578) (xy 187.175761 -49.847018)
			(xy 187.156187 -49.92105) (xy 187.143644 -49.957228) (xy 187.141001 -49.965666) (xy 187.141001 -49.983334)
			(xy 187.143644 -49.991772) (xy 187.156203 -50.027946) (xy 187.175798 -50.101975) (xy 187.188949 -50.177417)
			(xy 187.195557 -50.25371) (xy 187.195968 -50.292) (xy 187.195545 -50.332032) (xy 187.188349 -50.411772)
			(xy 187.174016 -50.490542) (xy 187.152662 -50.567705) (xy 187.124459 -50.642637) (xy 187.089635 -50.714731)
			(xy 187.048474 -50.783404) (xy 187.001307 -50.848099) (xy 186.975242 -50.878486) (xy 186.968892 -50.885598)
			(xy 186.962542 -50.902616) (xy 186.962542 -50.951384) (xy 186.968892 -50.968402) (xy 186.975242 -50.975514)
			(xy 187.001311 -51.005897) (xy 187.048474 -51.070594) (xy 187.089631 -51.139269) (xy 187.124451 -51.211364)
			(xy 187.15265 -51.286296) (xy 187.174003 -51.363459) (xy 187.188334 -51.442229) (xy 187.195529 -51.521968)
			(xy 187.195968 -51.562) (xy 187.195524 -51.600288) (xy 187.188906 -51.676578) (xy 187.175761 -51.752018)
			(xy 187.156187 -51.82605) (xy 187.143644 -51.862228) (xy 187.141001 -51.870666) (xy 187.141001 -51.888334)
			(xy 187.143644 -51.896772) (xy 187.156203 -51.932946) (xy 187.175798 -52.006975) (xy 187.188949 -52.082417)
			(xy 187.195557 -52.15871) (xy 187.195968 -52.197) (xy 187.195464 -52.239348) (xy 187.187413 -52.323662)
			(xy 187.171384 -52.406828) (xy 187.147523 -52.488095) (xy 187.116044 -52.566725) (xy 187.077233 -52.642006)
			(xy 187.031443 -52.713258) (xy 186.979087 -52.779834) (xy 186.920639 -52.841132) (xy 186.856629 -52.896597)
			(xy 186.787637 -52.945726) (xy 186.714287 -52.988075) (xy 186.637244 -53.023259) (xy 186.557205 -53.050961)
			(xy 186.474896 -53.070929) (xy 186.391061 -53.082982) (xy 186.30646 -53.087013) (xy 186.221859 -53.082982)
			(xy 186.138024 -53.070929) (xy 186.055715 -53.050961) (xy 185.975676 -53.023259) (xy 185.898633 -52.988075)
			(xy 185.825283 -52.945726) (xy 185.756291 -52.896597) (xy 185.692281 -52.841132) (xy 185.633833 -52.779834)
			(xy 185.581477 -52.713258) (xy 185.535687 -52.642006) (xy 185.496876 -52.566725) (xy 185.465397 -52.488095)
			(xy 185.441536 -52.406828) (xy 185.425507 -52.323662) (xy 185.417456 -52.239348) (xy 185.416952 -52.197)
			(xy 181.734968 -52.197) (xy 181.734464 -52.239348) (xy 181.726413 -52.323662) (xy 181.710384 -52.406828)
			(xy 181.686523 -52.488095) (xy 181.655044 -52.566725) (xy 181.616233 -52.642006) (xy 181.570443 -52.713258)
			(xy 181.518087 -52.779834) (xy 181.459639 -52.841132) (xy 181.395629 -52.896597) (xy 181.326637 -52.945726)
			(xy 181.253287 -52.988075) (xy 181.176244 -53.023259) (xy 181.096205 -53.050961) (xy 181.013896 -53.070929)
			(xy 180.930061 -53.082982) (xy 180.84546 -53.087013) (xy 180.760859 -53.082982) (xy 180.677024 -53.070929)
			(xy 180.594715 -53.050961) (xy 180.514676 -53.023259) (xy 180.437633 -52.988075) (xy 180.364283 -52.945726)
			(xy 180.295291 -52.896597) (xy 180.231281 -52.841132) (xy 180.172833 -52.779834) (xy 180.120477 -52.713258)
			(xy 180.074687 -52.642006) (xy 180.035876 -52.566725) (xy 180.004397 -52.488095) (xy 179.980536 -52.406828)
			(xy 179.964507 -52.323662) (xy 179.956456 -52.239348) (xy 179.955952 -52.197) (xy 176.276508 -52.197)
			(xy 176.276004 -52.239348) (xy 176.267953 -52.323662) (xy 176.251924 -52.406828) (xy 176.228063 -52.488095)
			(xy 176.196584 -52.566725) (xy 176.157773 -52.642006) (xy 176.111983 -52.713258) (xy 176.059627 -52.779834)
			(xy 176.001179 -52.841132) (xy 175.937169 -52.896597) (xy 175.868177 -52.945726) (xy 175.794827 -52.988075)
			(xy 175.717784 -53.023259) (xy 175.637745 -53.050961) (xy 175.555436 -53.070929) (xy 175.471601 -53.082982)
			(xy 175.387 -53.087013) (xy 175.302399 -53.082982) (xy 175.218564 -53.070929) (xy 175.136255 -53.050961)
			(xy 175.056216 -53.023259) (xy 174.979173 -52.988075) (xy 174.905823 -52.945726) (xy 174.836831 -52.896597)
			(xy 174.772821 -52.841132) (xy 174.714373 -52.779834) (xy 174.662017 -52.713258) (xy 174.616227 -52.642006)
			(xy 174.577416 -52.566725) (xy 174.545937 -52.488095) (xy 174.522076 -52.406828) (xy 174.506047 -52.323662)
			(xy 174.497996 -52.239348) (xy 174.497492 -52.197) (xy 170.815508 -52.197) (xy 170.815004 -52.239348)
			(xy 170.806953 -52.323662) (xy 170.790924 -52.406828) (xy 170.767063 -52.488095) (xy 170.735584 -52.566725)
			(xy 170.696773 -52.642006) (xy 170.650983 -52.713258) (xy 170.598627 -52.779834) (xy 170.540179 -52.841132)
			(xy 170.476169 -52.896597) (xy 170.407177 -52.945726) (xy 170.333827 -52.988075) (xy 170.256784 -53.023259)
			(xy 170.176745 -53.050961) (xy 170.094436 -53.070929) (xy 170.010601 -53.082982) (xy 169.926 -53.087013)
			(xy 169.841399 -53.082982) (xy 169.757564 -53.070929) (xy 169.675255 -53.050961) (xy 169.595216 -53.023259)
			(xy 169.518173 -52.988075) (xy 169.444823 -52.945726) (xy 169.375831 -52.896597) (xy 169.311821 -52.841132)
			(xy 169.253373 -52.779834) (xy 169.201017 -52.713258) (xy 169.155227 -52.642006) (xy 169.116416 -52.566725)
			(xy 169.084937 -52.488095) (xy 169.061076 -52.406828) (xy 169.045047 -52.323662) (xy 169.036996 -52.239348)
			(xy 169.036492 -52.197) (xy 165.354508 -52.197) (xy 165.354004 -52.239348) (xy 165.345953 -52.323662)
			(xy 165.329924 -52.406828) (xy 165.306063 -52.488095) (xy 165.274584 -52.566725) (xy 165.235773 -52.642006)
			(xy 165.189983 -52.713258) (xy 165.137627 -52.779834) (xy 165.079179 -52.841132) (xy 165.015169 -52.896597)
			(xy 164.946177 -52.945726) (xy 164.872827 -52.988075) (xy 164.795784 -53.023259) (xy 164.715745 -53.050961)
			(xy 164.633436 -53.070929) (xy 164.549601 -53.082982) (xy 164.465 -53.087013) (xy 164.380399 -53.082982)
			(xy 164.296564 -53.070929) (xy 164.214255 -53.050961) (xy 164.134216 -53.023259) (xy 164.057173 -52.988075)
			(xy 163.983823 -52.945726) (xy 163.914831 -52.896597) (xy 163.850821 -52.841132) (xy 163.792373 -52.779834)
			(xy 163.740017 -52.713258) (xy 163.694227 -52.642006) (xy 163.655416 -52.566725) (xy 163.623937 -52.488095)
			(xy 163.600076 -52.406828) (xy 163.584047 -52.323662) (xy 163.575996 -52.239348) (xy 163.575492 -52.197)
			(xy 159.893508 -52.197) (xy 159.893033 -52.238102) (xy 159.885448 -52.319957) (xy 159.870343 -52.400762)
			(xy 159.847847 -52.479829) (xy 159.818151 -52.556483) (xy 159.781509 -52.63007) (xy 159.738234 -52.699962)
			(xy 159.688694 -52.765563) (xy 159.633313 -52.826313) (xy 159.572563 -52.881694) (xy 159.506962 -52.931234)
			(xy 159.43707 -52.974509) (xy 159.363483 -53.011151) (xy 159.286829 -53.040847) (xy 159.207762 -53.063343)
			(xy 159.126957 -53.078448) (xy 159.045102 -53.086033) (xy 159.004 -53.086508) (xy 158.962898 -53.086033)
			(xy 158.881043 -53.078448) (xy 158.800238 -53.063343) (xy 158.721171 -53.040847) (xy 158.644517 -53.011151)
			(xy 158.57093 -52.974509) (xy 158.501038 -52.931234) (xy 158.435437 -52.881694) (xy 158.374687 -52.826313)
			(xy 158.319306 -52.765563) (xy 158.269766 -52.699962) (xy 158.226491 -52.63007) (xy 158.189849 -52.556483)
			(xy 158.160153 -52.479829) (xy 158.137657 -52.400762) (xy 158.122552 -52.319957) (xy 158.114967 -52.238102)
			(xy 158.114492 -52.197) (xy 154.432508 -52.197) (xy 154.432033 -52.238102) (xy 154.424448 -52.319957)
			(xy 154.409343 -52.400762) (xy 154.386847 -52.479829) (xy 154.357151 -52.556483) (xy 154.320509 -52.63007)
			(xy 154.277234 -52.699962) (xy 154.227694 -52.765563) (xy 154.172313 -52.826313) (xy 154.111563 -52.881694)
			(xy 154.045962 -52.931234) (xy 153.97607 -52.974509) (xy 153.902483 -53.011151) (xy 153.825829 -53.040847)
			(xy 153.746762 -53.063343) (xy 153.665957 -53.078448) (xy 153.584102 -53.086033) (xy 153.543 -53.086508)
			(xy 153.501898 -53.086033) (xy 153.420043 -53.078448) (xy 153.339238 -53.063343) (xy 153.260171 -53.040847)
			(xy 153.183517 -53.011151) (xy 153.10993 -52.974509) (xy 153.040038 -52.931234) (xy 152.974437 -52.881694)
			(xy 152.913687 -52.826313) (xy 152.858306 -52.765563) (xy 152.808766 -52.699962) (xy 152.765491 -52.63007)
			(xy 152.728849 -52.556483) (xy 152.699153 -52.479829) (xy 152.676657 -52.400762) (xy 152.661552 -52.319957)
			(xy 152.653967 -52.238102) (xy 152.653492 -52.197) (xy 109.084323 -52.197) (xy 109.086488 -52.209417)
			(xy 109.093097 -52.285711) (xy 109.093508 -52.324) (xy 109.093033 -52.365102) (xy 109.085448 -52.446957)
			(xy 109.070343 -52.527762) (xy 109.047847 -52.606829) (xy 109.018151 -52.683483) (xy 108.981509 -52.75707)
			(xy 108.938234 -52.826962) (xy 108.888694 -52.892563) (xy 108.833313 -52.953313) (xy 108.772563 -53.008694)
			(xy 108.706962 -53.058234) (xy 108.63707 -53.101509) (xy 108.563483 -53.138151) (xy 108.486829 -53.167847)
			(xy 108.407762 -53.190343) (xy 108.326957 -53.205448) (xy 108.245102 -53.213033) (xy 108.204 -53.213508)
			(xy 108.162898 -53.213033) (xy 108.081043 -53.205448) (xy 108.000238 -53.190343) (xy 107.921171 -53.167847)
			(xy 107.844517 -53.138151) (xy 107.77093 -53.101509) (xy 107.701038 -53.058234) (xy 107.635437 -53.008694)
			(xy 107.574687 -52.953313) (xy 107.519306 -52.892563) (xy 107.469766 -52.826962) (xy 107.426491 -52.75707)
			(xy 107.389849 -52.683483) (xy 107.360153 -52.606829) (xy 107.337657 -52.527762) (xy 107.322552 -52.446957)
			(xy 107.314967 -52.365102) (xy 107.314492 -52.324) (xy 103.632508 -52.324) (xy 103.632033 -52.365102)
			(xy 103.624448 -52.446957) (xy 103.609343 -52.527762) (xy 103.586847 -52.606829) (xy 103.557151 -52.683483)
			(xy 103.520509 -52.75707) (xy 103.477234 -52.826962) (xy 103.427694 -52.892563) (xy 103.372313 -52.953313)
			(xy 103.311563 -53.008694) (xy 103.245962 -53.058234) (xy 103.17607 -53.101509) (xy 103.102483 -53.138151)
			(xy 103.025829 -53.167847) (xy 102.946762 -53.190343) (xy 102.865957 -53.205448) (xy 102.784102 -53.213033)
			(xy 102.743 -53.213508) (xy 102.701898 -53.213033) (xy 102.620043 -53.205448) (xy 102.539238 -53.190343)
			(xy 102.460171 -53.167847) (xy 102.383517 -53.138151) (xy 102.30993 -53.101509) (xy 102.240038 -53.058234)
			(xy 102.174437 -53.008694) (xy 102.113687 -52.953313) (xy 102.058306 -52.892563) (xy 102.008766 -52.826962)
			(xy 101.965491 -52.75707) (xy 101.928849 -52.683483) (xy 101.899153 -52.606829) (xy 101.876657 -52.527762)
			(xy 101.861552 -52.446957) (xy 101.853967 -52.365102) (xy 101.853492 -52.324) (xy 98.171508 -52.324)
			(xy 98.171033 -52.365102) (xy 98.163448 -52.446957) (xy 98.148343 -52.527762) (xy 98.125847 -52.606829)
			(xy 98.096151 -52.683483) (xy 98.059509 -52.75707) (xy 98.016234 -52.826962) (xy 97.966694 -52.892563)
			(xy 97.911313 -52.953313) (xy 97.850563 -53.008694) (xy 97.784962 -53.058234) (xy 97.71507 -53.101509)
			(xy 97.641483 -53.138151) (xy 97.564829 -53.167847) (xy 97.485762 -53.190343) (xy 97.404957 -53.205448)
			(xy 97.323102 -53.213033) (xy 97.282 -53.213508) (xy 97.240898 -53.213033) (xy 97.159043 -53.205448)
			(xy 97.078238 -53.190343) (xy 96.999171 -53.167847) (xy 96.922517 -53.138151) (xy 96.84893 -53.101509)
			(xy 96.779038 -53.058234) (xy 96.713437 -53.008694) (xy 96.652687 -52.953313) (xy 96.597306 -52.892563)
			(xy 96.547766 -52.826962) (xy 96.504491 -52.75707) (xy 96.467849 -52.683483) (xy 96.438153 -52.606829)
			(xy 96.415657 -52.527762) (xy 96.400552 -52.446957) (xy 96.392967 -52.365102) (xy 96.392492 -52.324)
			(xy 92.710508 -52.324) (xy 92.710033 -52.365102) (xy 92.702448 -52.446957) (xy 92.687343 -52.527762)
			(xy 92.664847 -52.606829) (xy 92.635151 -52.683483) (xy 92.598509 -52.75707) (xy 92.555234 -52.826962)
			(xy 92.505694 -52.892563) (xy 92.450313 -52.953313) (xy 92.389563 -53.008694) (xy 92.323962 -53.058234)
			(xy 92.25407 -53.101509) (xy 92.180483 -53.138151) (xy 92.103829 -53.167847) (xy 92.024762 -53.190343)
			(xy 91.943957 -53.205448) (xy 91.862102 -53.213033) (xy 91.821 -53.213508) (xy 91.779898 -53.213033)
			(xy 91.698043 -53.205448) (xy 91.617238 -53.190343) (xy 91.538171 -53.167847) (xy 91.461517 -53.138151)
			(xy 91.38793 -53.101509) (xy 91.318038 -53.058234) (xy 91.252437 -53.008694) (xy 91.191687 -52.953313)
			(xy 91.136306 -52.892563) (xy 91.086766 -52.826962) (xy 91.043491 -52.75707) (xy 91.006849 -52.683483)
			(xy 90.977153 -52.606829) (xy 90.954657 -52.527762) (xy 90.939552 -52.446957) (xy 90.931967 -52.365102)
			(xy 90.931492 -52.324) (xy 87.249508 -52.324) (xy 87.249033 -52.365102) (xy 87.241448 -52.446957)
			(xy 87.226343 -52.527762) (xy 87.203847 -52.606829) (xy 87.174151 -52.683483) (xy 87.137509 -52.75707)
			(xy 87.094234 -52.826962) (xy 87.044694 -52.892563) (xy 86.989313 -52.953313) (xy 86.928563 -53.008694)
			(xy 86.862962 -53.058234) (xy 86.79307 -53.101509) (xy 86.719483 -53.138151) (xy 86.642829 -53.167847)
			(xy 86.563762 -53.190343) (xy 86.482957 -53.205448) (xy 86.401102 -53.213033) (xy 86.36 -53.213508)
			(xy 86.318898 -53.213033) (xy 86.237043 -53.205448) (xy 86.156238 -53.190343) (xy 86.077171 -53.167847)
			(xy 86.000517 -53.138151) (xy 85.92693 -53.101509) (xy 85.857038 -53.058234) (xy 85.791437 -53.008694)
			(xy 85.730687 -52.953313) (xy 85.675306 -52.892563) (xy 85.625766 -52.826962) (xy 85.582491 -52.75707)
			(xy 85.545849 -52.683483) (xy 85.516153 -52.606829) (xy 85.493657 -52.527762) (xy 85.478552 -52.446957)
			(xy 85.470967 -52.365102) (xy 85.470492 -52.324) (xy 81.788508 -52.324) (xy 81.788033 -52.365102)
			(xy 81.780448 -52.446957) (xy 81.765343 -52.527762) (xy 81.742847 -52.606829) (xy 81.713151 -52.683483)
			(xy 81.676509 -52.75707) (xy 81.633234 -52.826962) (xy 81.583694 -52.892563) (xy 81.528313 -52.953313)
			(xy 81.467563 -53.008694) (xy 81.401962 -53.058234) (xy 81.33207 -53.101509) (xy 81.258483 -53.138151)
			(xy 81.181829 -53.167847) (xy 81.102762 -53.190343) (xy 81.021957 -53.205448) (xy 80.940102 -53.213033)
			(xy 80.899 -53.213508) (xy 80.857898 -53.213033) (xy 80.776043 -53.205448) (xy 80.695238 -53.190343)
			(xy 80.616171 -53.167847) (xy 80.539517 -53.138151) (xy 80.46593 -53.101509) (xy 80.396038 -53.058234)
			(xy 80.330437 -53.008694) (xy 80.269687 -52.953313) (xy 80.214306 -52.892563) (xy 80.164766 -52.826962)
			(xy 80.121491 -52.75707) (xy 80.084849 -52.683483) (xy 80.055153 -52.606829) (xy 80.032657 -52.527762)
			(xy 80.017552 -52.446957) (xy 80.009967 -52.365102) (xy 80.009492 -52.324) (xy 76.327508 -52.324)
			(xy 76.327033 -52.365102) (xy 76.319448 -52.446957) (xy 76.304343 -52.527762) (xy 76.281847 -52.606829)
			(xy 76.252151 -52.683483) (xy 76.215509 -52.75707) (xy 76.172234 -52.826962) (xy 76.122694 -52.892563)
			(xy 76.067313 -52.953313) (xy 76.006563 -53.008694) (xy 75.940962 -53.058234) (xy 75.87107 -53.101509)
			(xy 75.797483 -53.138151) (xy 75.720829 -53.167847) (xy 75.641762 -53.190343) (xy 75.560957 -53.205448)
			(xy 75.479102 -53.213033) (xy 75.438 -53.213508) (xy 75.396898 -53.213033) (xy 75.315043 -53.205448)
			(xy 75.234238 -53.190343) (xy 75.155171 -53.167847) (xy 75.078517 -53.138151) (xy 75.00493 -53.101509)
			(xy 74.935038 -53.058234) (xy 74.869437 -53.008694) (xy 74.808687 -52.953313) (xy 74.753306 -52.892563)
			(xy 74.703766 -52.826962) (xy 74.660491 -52.75707) (xy 74.623849 -52.683483) (xy 74.594153 -52.606829)
			(xy 74.571657 -52.527762) (xy 74.556552 -52.446957) (xy 74.548967 -52.365102) (xy 74.548492 -52.324)
			(xy 40.513 -52.324) (xy 40.513 -58.017918) (xy 42.9514 -58.017918) (xy 42.9514 -55.164482) (xy 42.95179 -55.154408)
			(xy 42.959532 -55.135809) (xy 42.966386 -55.128414) (xy 44.905676 -53.189124) (xy 44.913093 -53.182305)
			(xy 44.931679 -53.174572) (xy 44.941744 -53.174138) (xy 46.529752 -53.174138) (xy 46.537626 -53.171344)
			(xy 46.583952 -53.156248) (xy 46.679068 -53.135103) (xy 46.775927 -53.124486) (xy 46.824646 -53.123846)
			(xy 46.867058 -53.124403) (xy 46.951492 -53.132543) (xy 47.034771 -53.148668) (xy 47.075598 -53.160168)
			(xy 47.08271 -53.1622) (xy 47.349918 -53.1622) (xy 47.359992 -53.16259) (xy 47.378591 -53.170332)
			(xy 47.385986 -53.177186) (xy 47.762414 -53.553614) (xy 47.769254 -53.561014) (xy 47.776973 -53.579613)
			(xy 47.7774 -53.589682) (xy 47.7774 -55.96001) (xy 66.673991 -55.96001) (xy 66.677995 -55.85428)
			(xy 66.689983 -55.749156) (xy 66.709888 -55.64524) (xy 66.737595 -55.543127) (xy 66.772945 -55.443401)
			(xy 66.815736 -55.346635) (xy 66.865722 -55.253382) (xy 66.922618 -55.164176) (xy 66.986098 -55.079529)
			(xy 67.055798 -54.999925) (xy 67.131318 -54.925821) (xy 67.212227 -54.85764) (xy 67.29806 -54.795774)
			(xy 67.388326 -54.740576) (xy 67.482508 -54.692363) (xy 67.580067 -54.651411) (xy 67.680444 -54.617955)
			(xy 67.783063 -54.592185) (xy 67.887337 -54.574251) (xy 67.99267 -54.564254) (xy 68.098456 -54.562251)
			(xy 68.204091 -54.568255) (xy 68.308969 -54.582231) (xy 68.41249 -54.604099) (xy 68.514061 -54.633733)
			(xy 68.6131 -54.670964) (xy 68.709039 -54.715578) (xy 68.801329 -54.767321) (xy 68.889442 -54.825895)
			(xy 68.972873 -54.890965) (xy 69.051143 -54.962159) (xy 69.123805 -55.039068) (xy 69.190443 -55.121252)
			(xy 69.250674 -55.208241) (xy 69.304153 -55.299535) (xy 69.350576 -55.394613) (xy 69.389674 -55.492929)
			(xy 69.421225 -55.593921) (xy 69.445048 -55.69701) (xy 69.461006 -55.801605) (xy 69.469008 -55.907107)
			(xy 69.469508 -55.96001) (xy 77.976991 -55.96001) (xy 77.980995 -55.85428) (xy 77.992983 -55.749156)
			(xy 78.012888 -55.64524) (xy 78.040595 -55.543127) (xy 78.075945 -55.443401) (xy 78.118736 -55.346635)
			(xy 78.168722 -55.253382) (xy 78.225618 -55.164176) (xy 78.289098 -55.079529) (xy 78.358798 -54.999925)
			(xy 78.434318 -54.925821) (xy 78.515227 -54.85764) (xy 78.60106 -54.795774) (xy 78.691326 -54.740576)
			(xy 78.785508 -54.692363) (xy 78.883067 -54.651411) (xy 78.983444 -54.617955) (xy 79.086063 -54.592185)
			(xy 79.190337 -54.574251) (xy 79.29567 -54.564254) (xy 79.401456 -54.562251) (xy 79.507091 -54.568255)
			(xy 79.611969 -54.582231) (xy 79.71549 -54.604099) (xy 79.817061 -54.633733) (xy 79.9161 -54.670964)
			(xy 80.012039 -54.715578) (xy 80.104329 -54.767321) (xy 80.192442 -54.825895) (xy 80.275873 -54.890965)
			(xy 80.354143 -54.962159) (xy 80.426805 -55.039068) (xy 80.493443 -55.121252) (xy 80.553674 -55.208241)
			(xy 80.607153 -55.299535) (xy 80.653576 -55.394613) (xy 80.692674 -55.492929) (xy 80.724225 -55.593921)
			(xy 80.748048 -55.69701) (xy 80.764006 -55.801605) (xy 80.772008 -55.907107) (xy 80.772508 -55.96001)
			(xy 89.279991 -55.96001) (xy 89.283995 -55.85428) (xy 89.295983 -55.749156) (xy 89.315888 -55.64524)
			(xy 89.343595 -55.543127) (xy 89.378945 -55.443401) (xy 89.421736 -55.346635) (xy 89.471722 -55.253382)
			(xy 89.528618 -55.164176) (xy 89.592098 -55.079529) (xy 89.661798 -54.999925) (xy 89.737318 -54.925821)
			(xy 89.818227 -54.85764) (xy 89.90406 -54.795774) (xy 89.994326 -54.740576) (xy 90.088508 -54.692363)
			(xy 90.186067 -54.651411) (xy 90.286444 -54.617955) (xy 90.389063 -54.592185) (xy 90.493337 -54.574251)
			(xy 90.59867 -54.564254) (xy 90.704456 -54.562251) (xy 90.810091 -54.568255) (xy 90.914969 -54.582231)
			(xy 91.01849 -54.604099) (xy 91.120061 -54.633733) (xy 91.2191 -54.670964) (xy 91.315039 -54.715578)
			(xy 91.407329 -54.767321) (xy 91.495442 -54.825895) (xy 91.578873 -54.890965) (xy 91.657143 -54.962159)
			(xy 91.729805 -55.039068) (xy 91.796443 -55.121252) (xy 91.856674 -55.208241) (xy 91.910153 -55.299535)
			(xy 91.956576 -55.394613) (xy 91.995674 -55.492929) (xy 92.027225 -55.593921) (xy 92.051048 -55.69701)
			(xy 92.067006 -55.801605) (xy 92.075008 -55.907107) (xy 92.075508 -55.96001) (xy 107.440991 -55.96001)
			(xy 107.444995 -55.85428) (xy 107.456983 -55.749156) (xy 107.476888 -55.64524) (xy 107.504595 -55.543127)
			(xy 107.539945 -55.443401) (xy 107.582736 -55.346635) (xy 107.632722 -55.253382) (xy 107.689618 -55.164176)
			(xy 107.753098 -55.079529) (xy 107.822798 -54.999925) (xy 107.898318 -54.925821) (xy 107.979227 -54.85764)
			(xy 108.06506 -54.795774) (xy 108.155326 -54.740576) (xy 108.249508 -54.692363) (xy 108.347067 -54.651411)
			(xy 108.447444 -54.617955) (xy 108.550063 -54.592185) (xy 108.654337 -54.574251) (xy 108.75967 -54.564254)
			(xy 108.865456 -54.562251) (xy 108.971091 -54.568255) (xy 109.075969 -54.582231) (xy 109.17949 -54.604099)
			(xy 109.281061 -54.633733) (xy 109.3801 -54.670964) (xy 109.476039 -54.715578) (xy 109.568329 -54.767321)
			(xy 109.656442 -54.825895) (xy 109.739873 -54.890965) (xy 109.818143 -54.962159) (xy 109.890805 -55.039068)
			(xy 109.957443 -55.121252) (xy 110.017674 -55.208241) (xy 110.071153 -55.299535) (xy 110.117576 -55.394613)
			(xy 110.156674 -55.492929) (xy 110.188225 -55.593921) (xy 110.212048 -55.69701) (xy 110.228006 -55.801605)
			(xy 110.236008 -55.907107) (xy 110.236508 -55.96001) (xy 118.616991 -55.96001) (xy 118.620995 -55.85428)
			(xy 118.632983 -55.749156) (xy 118.652888 -55.64524) (xy 118.680595 -55.543127) (xy 118.715945 -55.443401)
			(xy 118.758736 -55.346635) (xy 118.808722 -55.253382) (xy 118.865618 -55.164176) (xy 118.929098 -55.079529)
			(xy 118.998798 -54.999925) (xy 119.074318 -54.925821) (xy 119.155227 -54.85764) (xy 119.24106 -54.795774)
			(xy 119.331326 -54.740576) (xy 119.425508 -54.692363) (xy 119.523067 -54.651411) (xy 119.623444 -54.617955)
			(xy 119.726063 -54.592185) (xy 119.830337 -54.574251) (xy 119.93567 -54.564254) (xy 120.041456 -54.562251)
			(xy 120.147091 -54.568255) (xy 120.251969 -54.582231) (xy 120.35549 -54.604099) (xy 120.457061 -54.633733)
			(xy 120.5561 -54.670964) (xy 120.652039 -54.715578) (xy 120.744329 -54.767321) (xy 120.832442 -54.825895)
			(xy 120.915873 -54.890965) (xy 120.994143 -54.962159) (xy 121.066805 -55.039068) (xy 121.133443 -55.121252)
			(xy 121.193674 -55.208241) (xy 121.247153 -55.299535) (xy 121.293576 -55.394613) (xy 121.332674 -55.492929)
			(xy 121.364225 -55.593921) (xy 121.388048 -55.69701) (xy 121.404006 -55.801605) (xy 121.412008 -55.907107)
			(xy 121.412508 -55.96001) (xy 129.792991 -55.96001) (xy 129.796995 -55.85428) (xy 129.808983 -55.749156)
			(xy 129.828888 -55.64524) (xy 129.856595 -55.543127) (xy 129.891945 -55.443401) (xy 129.934736 -55.346635)
			(xy 129.984722 -55.253382) (xy 130.041618 -55.164176) (xy 130.105098 -55.079529) (xy 130.174798 -54.999925)
			(xy 130.250318 -54.925821) (xy 130.331227 -54.85764) (xy 130.41706 -54.795774) (xy 130.507326 -54.740576)
			(xy 130.601508 -54.692363) (xy 130.699067 -54.651411) (xy 130.799444 -54.617955) (xy 130.902063 -54.592185)
			(xy 131.006337 -54.574251) (xy 131.11167 -54.564254) (xy 131.217456 -54.562251) (xy 131.323091 -54.568255)
			(xy 131.427969 -54.582231) (xy 131.53149 -54.604099) (xy 131.633061 -54.633733) (xy 131.7321 -54.670964)
			(xy 131.828039 -54.715578) (xy 131.920329 -54.767321) (xy 132.008442 -54.825895) (xy 132.091873 -54.890965)
			(xy 132.170143 -54.962159) (xy 132.242805 -55.039068) (xy 132.309443 -55.121252) (xy 132.369674 -55.208241)
			(xy 132.423153 -55.299535) (xy 132.469576 -55.394613) (xy 132.508674 -55.492929) (xy 132.540225 -55.593921)
			(xy 132.564048 -55.69701) (xy 132.580006 -55.801605) (xy 132.588008 -55.907107) (xy 132.588508 -55.96001)
			(xy 145.540991 -55.96001) (xy 145.544995 -55.85428) (xy 145.556983 -55.749156) (xy 145.576888 -55.64524)
			(xy 145.604595 -55.543127) (xy 145.639945 -55.443401) (xy 145.682736 -55.346635) (xy 145.732722 -55.253382)
			(xy 145.789618 -55.164176) (xy 145.853098 -55.079529) (xy 145.922798 -54.999925) (xy 145.998318 -54.925821)
			(xy 146.079227 -54.85764) (xy 146.16506 -54.795774) (xy 146.255326 -54.740576) (xy 146.349508 -54.692363)
			(xy 146.447067 -54.651411) (xy 146.547444 -54.617955) (xy 146.650063 -54.592185) (xy 146.754337 -54.574251)
			(xy 146.85967 -54.564254) (xy 146.965456 -54.562251) (xy 147.071091 -54.568255) (xy 147.175969 -54.582231)
			(xy 147.27949 -54.604099) (xy 147.381061 -54.633733) (xy 147.4801 -54.670964) (xy 147.576039 -54.715578)
			(xy 147.668329 -54.767321) (xy 147.756442 -54.825895) (xy 147.839873 -54.890965) (xy 147.918143 -54.962159)
			(xy 147.990805 -55.039068) (xy 148.057443 -55.121252) (xy 148.117674 -55.208241) (xy 148.171153 -55.299535)
			(xy 148.217576 -55.394613) (xy 148.256674 -55.492929) (xy 148.288225 -55.593921) (xy 148.312048 -55.69701)
			(xy 148.328006 -55.801605) (xy 148.336008 -55.907107) (xy 148.336508 -55.96001) (xy 156.716991 -55.96001)
			(xy 156.720995 -55.85428) (xy 156.732983 -55.749156) (xy 156.752888 -55.64524) (xy 156.780595 -55.543127)
			(xy 156.815945 -55.443401) (xy 156.858736 -55.346635) (xy 156.908722 -55.253382) (xy 156.965618 -55.164176)
			(xy 157.029098 -55.079529) (xy 157.098798 -54.999925) (xy 157.174318 -54.925821) (xy 157.255227 -54.85764)
			(xy 157.34106 -54.795774) (xy 157.431326 -54.740576) (xy 157.525508 -54.692363) (xy 157.623067 -54.651411)
			(xy 157.723444 -54.617955) (xy 157.826063 -54.592185) (xy 157.930337 -54.574251) (xy 158.03567 -54.564254)
			(xy 158.141456 -54.562251) (xy 158.247091 -54.568255) (xy 158.351969 -54.582231) (xy 158.45549 -54.604099)
			(xy 158.557061 -54.633733) (xy 158.6561 -54.670964) (xy 158.752039 -54.715578) (xy 158.844329 -54.767321)
			(xy 158.932442 -54.825895) (xy 159.015873 -54.890965) (xy 159.094143 -54.962159) (xy 159.166805 -55.039068)
			(xy 159.233443 -55.121252) (xy 159.293674 -55.208241) (xy 159.347153 -55.299535) (xy 159.393576 -55.394613)
			(xy 159.432674 -55.492929) (xy 159.464225 -55.593921) (xy 159.488048 -55.69701) (xy 159.504006 -55.801605)
			(xy 159.512008 -55.907107) (xy 159.512508 -55.96001) (xy 167.892991 -55.96001) (xy 167.896995 -55.85428)
			(xy 167.908983 -55.749156) (xy 167.928888 -55.64524) (xy 167.956595 -55.543127) (xy 167.991945 -55.443401)
			(xy 168.034736 -55.346635) (xy 168.084722 -55.253382) (xy 168.141618 -55.164176) (xy 168.205098 -55.079529)
			(xy 168.274798 -54.999925) (xy 168.350318 -54.925821) (xy 168.431227 -54.85764) (xy 168.51706 -54.795774)
			(xy 168.607326 -54.740576) (xy 168.701508 -54.692363) (xy 168.799067 -54.651411) (xy 168.899444 -54.617955)
			(xy 169.002063 -54.592185) (xy 169.106337 -54.574251) (xy 169.21167 -54.564254) (xy 169.317456 -54.562251)
			(xy 169.423091 -54.568255) (xy 169.527969 -54.582231) (xy 169.63149 -54.604099) (xy 169.733061 -54.633733)
			(xy 169.8321 -54.670964) (xy 169.928039 -54.715578) (xy 170.020329 -54.767321) (xy 170.108442 -54.825895)
			(xy 170.191873 -54.890965) (xy 170.270143 -54.962159) (xy 170.342805 -55.039068) (xy 170.409443 -55.121252)
			(xy 170.469674 -55.208241) (xy 170.523153 -55.299535) (xy 170.569576 -55.394613) (xy 170.608674 -55.492929)
			(xy 170.640225 -55.593921) (xy 170.664048 -55.69701) (xy 170.680006 -55.801605) (xy 170.688008 -55.907107)
			(xy 170.688508 -55.96001) (xy 185.541165 -55.96001) (xy 185.545169 -55.85428) (xy 185.557157 -55.749156)
			(xy 185.577062 -55.64524) (xy 185.604769 -55.543127) (xy 185.640119 -55.443401) (xy 185.68291 -55.346635)
			(xy 185.732896 -55.253382) (xy 185.789792 -55.164176) (xy 185.853272 -55.079529) (xy 185.922972 -54.999925)
			(xy 185.998492 -54.925821) (xy 186.079401 -54.85764) (xy 186.165234 -54.795774) (xy 186.2555 -54.740576)
			(xy 186.349682 -54.692363) (xy 186.447241 -54.651411) (xy 186.547618 -54.617955) (xy 186.650237 -54.592185)
			(xy 186.754511 -54.574251) (xy 186.859844 -54.564254) (xy 186.96563 -54.562251) (xy 187.071265 -54.568255)
			(xy 187.176143 -54.582231) (xy 187.279664 -54.604099) (xy 187.381235 -54.633733) (xy 187.480274 -54.670964)
			(xy 187.576213 -54.715578) (xy 187.668503 -54.767321) (xy 187.756616 -54.825895) (xy 187.840047 -54.890965)
			(xy 187.918317 -54.962159) (xy 187.990979 -55.039068) (xy 188.057617 -55.121252) (xy 188.117848 -55.208241)
			(xy 188.171327 -55.299535) (xy 188.21775 -55.394613) (xy 188.256848 -55.492929) (xy 188.288399 -55.593921)
			(xy 188.312222 -55.69701) (xy 188.32818 -55.801605) (xy 188.336182 -55.907107) (xy 188.336682 -55.96001)
			(xy 196.717165 -55.96001) (xy 196.721169 -55.85428) (xy 196.733157 -55.749156) (xy 196.753062 -55.64524)
			(xy 196.780769 -55.543127) (xy 196.816119 -55.443401) (xy 196.85891 -55.346635) (xy 196.908896 -55.253382)
			(xy 196.965792 -55.164176) (xy 197.029272 -55.079529) (xy 197.098972 -54.999925) (xy 197.174492 -54.925821)
			(xy 197.255401 -54.85764) (xy 197.341234 -54.795774) (xy 197.4315 -54.740576) (xy 197.525682 -54.692363)
			(xy 197.623241 -54.651411) (xy 197.723618 -54.617955) (xy 197.826237 -54.592185) (xy 197.930511 -54.574251)
			(xy 198.035844 -54.564254) (xy 198.14163 -54.562251) (xy 198.247265 -54.568255) (xy 198.352143 -54.582231)
			(xy 198.455664 -54.604099) (xy 198.557235 -54.633733) (xy 198.656274 -54.670964) (xy 198.752213 -54.715578)
			(xy 198.844503 -54.767321) (xy 198.932616 -54.825895) (xy 199.016047 -54.890965) (xy 199.094317 -54.962159)
			(xy 199.166979 -55.039068) (xy 199.233617 -55.121252) (xy 199.293848 -55.208241) (xy 199.347327 -55.299535)
			(xy 199.39375 -55.394613) (xy 199.432848 -55.492929) (xy 199.464399 -55.593921) (xy 199.488222 -55.69701)
			(xy 199.50418 -55.801605) (xy 199.512182 -55.907107) (xy 199.512682 -55.96001) (xy 207.893165 -55.96001)
			(xy 207.897169 -55.85428) (xy 207.909157 -55.749156) (xy 207.929062 -55.64524) (xy 207.956769 -55.543127)
			(xy 207.992119 -55.443401) (xy 208.03491 -55.346635) (xy 208.084896 -55.253382) (xy 208.141792 -55.164176)
			(xy 208.205272 -55.079529) (xy 208.274972 -54.999925) (xy 208.350492 -54.925821) (xy 208.431401 -54.85764)
			(xy 208.517234 -54.795774) (xy 208.6075 -54.740576) (xy 208.701682 -54.692363) (xy 208.799241 -54.651411)
			(xy 208.899618 -54.617955) (xy 209.002237 -54.592185) (xy 209.106511 -54.574251) (xy 209.211844 -54.564254)
			(xy 209.31763 -54.562251) (xy 209.423265 -54.568255) (xy 209.528143 -54.582231) (xy 209.631664 -54.604099)
			(xy 209.733235 -54.633733) (xy 209.832274 -54.670964) (xy 209.928213 -54.715578) (xy 210.020503 -54.767321)
			(xy 210.108616 -54.825895) (xy 210.192047 -54.890965) (xy 210.270317 -54.962159) (xy 210.342979 -55.039068)
			(xy 210.409617 -55.121252) (xy 210.469848 -55.208241) (xy 210.523327 -55.299535) (xy 210.56975 -55.394613)
			(xy 210.608848 -55.492929) (xy 210.640399 -55.593921) (xy 210.664222 -55.69701) (xy 210.68018 -55.801605)
			(xy 210.688182 -55.907107) (xy 210.688682 -55.96001) (xy 210.688182 -56.012913) (xy 210.68018 -56.118415)
			(xy 210.664222 -56.22301) (xy 210.640399 -56.326099) (xy 210.608848 -56.427091) (xy 210.56975 -56.525407)
			(xy 210.523327 -56.620485) (xy 210.469848 -56.711779) (xy 210.409617 -56.798768) (xy 210.342979 -56.880952)
			(xy 210.270317 -56.957861) (xy 210.192047 -57.029055) (xy 210.108616 -57.094125) (xy 210.020503 -57.152699)
			(xy 209.928213 -57.204442) (xy 209.832274 -57.249056) (xy 209.733235 -57.286287) (xy 209.631664 -57.315921)
			(xy 209.528143 -57.337789) (xy 209.423265 -57.351765) (xy 209.31763 -57.357769) (xy 209.211844 -57.355766)
			(xy 209.106511 -57.345769) (xy 209.002237 -57.327835) (xy 208.899618 -57.302065) (xy 208.799241 -57.268609)
			(xy 208.701682 -57.227657) (xy 208.6075 -57.179444) (xy 208.517234 -57.124246) (xy 208.431401 -57.06238)
			(xy 208.350492 -56.994199) (xy 208.274972 -56.920095) (xy 208.205272 -56.840491) (xy 208.141792 -56.755844)
			(xy 208.084896 -56.666638) (xy 208.03491 -56.573385) (xy 207.992119 -56.476619) (xy 207.956769 -56.376893)
			(xy 207.929062 -56.27478) (xy 207.909157 -56.170864) (xy 207.897169 -56.06574) (xy 207.893165 -55.96001)
			(xy 199.512682 -55.96001) (xy 199.512182 -56.012913) (xy 199.50418 -56.118415) (xy 199.488222 -56.22301)
			(xy 199.464399 -56.326099) (xy 199.432848 -56.427091) (xy 199.39375 -56.525407) (xy 199.347327 -56.620485)
			(xy 199.293848 -56.711779) (xy 199.233617 -56.798768) (xy 199.166979 -56.880952) (xy 199.094317 -56.957861)
			(xy 199.016047 -57.029055) (xy 198.932616 -57.094125) (xy 198.844503 -57.152699) (xy 198.752213 -57.204442)
			(xy 198.656274 -57.249056) (xy 198.557235 -57.286287) (xy 198.455664 -57.315921) (xy 198.352143 -57.337789)
			(xy 198.247265 -57.351765) (xy 198.14163 -57.357769) (xy 198.035844 -57.355766) (xy 197.930511 -57.345769)
			(xy 197.826237 -57.327835) (xy 197.723618 -57.302065) (xy 197.623241 -57.268609) (xy 197.525682 -57.227657)
			(xy 197.4315 -57.179444) (xy 197.341234 -57.124246) (xy 197.255401 -57.06238) (xy 197.174492 -56.994199)
			(xy 197.098972 -56.920095) (xy 197.029272 -56.840491) (xy 196.965792 -56.755844) (xy 196.908896 -56.666638)
			(xy 196.85891 -56.573385) (xy 196.816119 -56.476619) (xy 196.780769 -56.376893) (xy 196.753062 -56.27478)
			(xy 196.733157 -56.170864) (xy 196.721169 -56.06574) (xy 196.717165 -55.96001) (xy 188.336682 -55.96001)
			(xy 188.336182 -56.012913) (xy 188.32818 -56.118415) (xy 188.312222 -56.22301) (xy 188.288399 -56.326099)
			(xy 188.256848 -56.427091) (xy 188.21775 -56.525407) (xy 188.171327 -56.620485) (xy 188.117848 -56.711779)
			(xy 188.057617 -56.798768) (xy 187.990979 -56.880952) (xy 187.918317 -56.957861) (xy 187.840047 -57.029055)
			(xy 187.756616 -57.094125) (xy 187.668503 -57.152699) (xy 187.576213 -57.204442) (xy 187.480274 -57.249056)
			(xy 187.381235 -57.286287) (xy 187.279664 -57.315921) (xy 187.176143 -57.337789) (xy 187.071265 -57.351765)
			(xy 186.96563 -57.357769) (xy 186.859844 -57.355766) (xy 186.754511 -57.345769) (xy 186.650237 -57.327835)
			(xy 186.547618 -57.302065) (xy 186.447241 -57.268609) (xy 186.349682 -57.227657) (xy 186.2555 -57.179444)
			(xy 186.165234 -57.124246) (xy 186.079401 -57.06238) (xy 185.998492 -56.994199) (xy 185.922972 -56.920095)
			(xy 185.853272 -56.840491) (xy 185.789792 -56.755844) (xy 185.732896 -56.666638) (xy 185.68291 -56.573385)
			(xy 185.640119 -56.476619) (xy 185.604769 -56.376893) (xy 185.577062 -56.27478) (xy 185.557157 -56.170864)
			(xy 185.545169 -56.06574) (xy 185.541165 -55.96001) (xy 170.688508 -55.96001) (xy 170.688008 -56.012913)
			(xy 170.680006 -56.118415) (xy 170.664048 -56.22301) (xy 170.640225 -56.326099) (xy 170.608674 -56.427091)
			(xy 170.569576 -56.525407) (xy 170.523153 -56.620485) (xy 170.469674 -56.711779) (xy 170.409443 -56.798768)
			(xy 170.342805 -56.880952) (xy 170.270143 -56.957861) (xy 170.191873 -57.029055) (xy 170.108442 -57.094125)
			(xy 170.020329 -57.152699) (xy 169.928039 -57.204442) (xy 169.8321 -57.249056) (xy 169.733061 -57.286287)
			(xy 169.63149 -57.315921) (xy 169.527969 -57.337789) (xy 169.423091 -57.351765) (xy 169.317456 -57.357769)
			(xy 169.21167 -57.355766) (xy 169.106337 -57.345769) (xy 169.002063 -57.327835) (xy 168.899444 -57.302065)
			(xy 168.799067 -57.268609) (xy 168.701508 -57.227657) (xy 168.607326 -57.179444) (xy 168.51706 -57.124246)
			(xy 168.431227 -57.06238) (xy 168.350318 -56.994199) (xy 168.274798 -56.920095) (xy 168.205098 -56.840491)
			(xy 168.141618 -56.755844) (xy 168.084722 -56.666638) (xy 168.034736 -56.573385) (xy 167.991945 -56.476619)
			(xy 167.956595 -56.376893) (xy 167.928888 -56.27478) (xy 167.908983 -56.170864) (xy 167.896995 -56.06574)
			(xy 167.892991 -55.96001) (xy 159.512508 -55.96001) (xy 159.512008 -56.012913) (xy 159.504006 -56.118415)
			(xy 159.488048 -56.22301) (xy 159.464225 -56.326099) (xy 159.432674 -56.427091) (xy 159.393576 -56.525407)
			(xy 159.347153 -56.620485) (xy 159.293674 -56.711779) (xy 159.233443 -56.798768) (xy 159.166805 -56.880952)
			(xy 159.094143 -56.957861) (xy 159.015873 -57.029055) (xy 158.932442 -57.094125) (xy 158.844329 -57.152699)
			(xy 158.752039 -57.204442) (xy 158.6561 -57.249056) (xy 158.557061 -57.286287) (xy 158.45549 -57.315921)
			(xy 158.351969 -57.337789) (xy 158.247091 -57.351765) (xy 158.141456 -57.357769) (xy 158.03567 -57.355766)
			(xy 157.930337 -57.345769) (xy 157.826063 -57.327835) (xy 157.723444 -57.302065) (xy 157.623067 -57.268609)
			(xy 157.525508 -57.227657) (xy 157.431326 -57.179444) (xy 157.34106 -57.124246) (xy 157.255227 -57.06238)
			(xy 157.174318 -56.994199) (xy 157.098798 -56.920095) (xy 157.029098 -56.840491) (xy 156.965618 -56.755844)
			(xy 156.908722 -56.666638) (xy 156.858736 -56.573385) (xy 156.815945 -56.476619) (xy 156.780595 -56.376893)
			(xy 156.752888 -56.27478) (xy 156.732983 -56.170864) (xy 156.720995 -56.06574) (xy 156.716991 -55.96001)
			(xy 148.336508 -55.96001) (xy 148.336008 -56.012913) (xy 148.328006 -56.118415) (xy 148.312048 -56.22301)
			(xy 148.288225 -56.326099) (xy 148.256674 -56.427091) (xy 148.217576 -56.525407) (xy 148.171153 -56.620485)
			(xy 148.117674 -56.711779) (xy 148.057443 -56.798768) (xy 147.990805 -56.880952) (xy 147.918143 -56.957861)
			(xy 147.839873 -57.029055) (xy 147.756442 -57.094125) (xy 147.668329 -57.152699) (xy 147.576039 -57.204442)
			(xy 147.4801 -57.249056) (xy 147.381061 -57.286287) (xy 147.27949 -57.315921) (xy 147.175969 -57.337789)
			(xy 147.071091 -57.351765) (xy 146.965456 -57.357769) (xy 146.85967 -57.355766) (xy 146.754337 -57.345769)
			(xy 146.650063 -57.327835) (xy 146.547444 -57.302065) (xy 146.447067 -57.268609) (xy 146.349508 -57.227657)
			(xy 146.255326 -57.179444) (xy 146.16506 -57.124246) (xy 146.079227 -57.06238) (xy 145.998318 -56.994199)
			(xy 145.922798 -56.920095) (xy 145.853098 -56.840491) (xy 145.789618 -56.755844) (xy 145.732722 -56.666638)
			(xy 145.682736 -56.573385) (xy 145.639945 -56.476619) (xy 145.604595 -56.376893) (xy 145.576888 -56.27478)
			(xy 145.556983 -56.170864) (xy 145.544995 -56.06574) (xy 145.540991 -55.96001) (xy 132.588508 -55.96001)
			(xy 132.588008 -56.012913) (xy 132.580006 -56.118415) (xy 132.564048 -56.22301) (xy 132.540225 -56.326099)
			(xy 132.508674 -56.427091) (xy 132.469576 -56.525407) (xy 132.423153 -56.620485) (xy 132.369674 -56.711779)
			(xy 132.309443 -56.798768) (xy 132.242805 -56.880952) (xy 132.170143 -56.957861) (xy 132.091873 -57.029055)
			(xy 132.008442 -57.094125) (xy 131.920329 -57.152699) (xy 131.828039 -57.204442) (xy 131.7321 -57.249056)
			(xy 131.633061 -57.286287) (xy 131.53149 -57.315921) (xy 131.427969 -57.337789) (xy 131.323091 -57.351765)
			(xy 131.217456 -57.357769) (xy 131.11167 -57.355766) (xy 131.006337 -57.345769) (xy 130.902063 -57.327835)
			(xy 130.799444 -57.302065) (xy 130.699067 -57.268609) (xy 130.601508 -57.227657) (xy 130.507326 -57.179444)
			(xy 130.41706 -57.124246) (xy 130.331227 -57.06238) (xy 130.250318 -56.994199) (xy 130.174798 -56.920095)
			(xy 130.105098 -56.840491) (xy 130.041618 -56.755844) (xy 129.984722 -56.666638) (xy 129.934736 -56.573385)
			(xy 129.891945 -56.476619) (xy 129.856595 -56.376893) (xy 129.828888 -56.27478) (xy 129.808983 -56.170864)
			(xy 129.796995 -56.06574) (xy 129.792991 -55.96001) (xy 121.412508 -55.96001) (xy 121.412008 -56.012913)
			(xy 121.404006 -56.118415) (xy 121.388048 -56.22301) (xy 121.364225 -56.326099) (xy 121.332674 -56.427091)
			(xy 121.293576 -56.525407) (xy 121.247153 -56.620485) (xy 121.193674 -56.711779) (xy 121.133443 -56.798768)
			(xy 121.066805 -56.880952) (xy 120.994143 -56.957861) (xy 120.915873 -57.029055) (xy 120.832442 -57.094125)
			(xy 120.744329 -57.152699) (xy 120.652039 -57.204442) (xy 120.5561 -57.249056) (xy 120.457061 -57.286287)
			(xy 120.35549 -57.315921) (xy 120.251969 -57.337789) (xy 120.147091 -57.351765) (xy 120.041456 -57.357769)
			(xy 119.93567 -57.355766) (xy 119.830337 -57.345769) (xy 119.726063 -57.327835) (xy 119.623444 -57.302065)
			(xy 119.523067 -57.268609) (xy 119.425508 -57.227657) (xy 119.331326 -57.179444) (xy 119.24106 -57.124246)
			(xy 119.155227 -57.06238) (xy 119.074318 -56.994199) (xy 118.998798 -56.920095) (xy 118.929098 -56.840491)
			(xy 118.865618 -56.755844) (xy 118.808722 -56.666638) (xy 118.758736 -56.573385) (xy 118.715945 -56.476619)
			(xy 118.680595 -56.376893) (xy 118.652888 -56.27478) (xy 118.632983 -56.170864) (xy 118.620995 -56.06574)
			(xy 118.616991 -55.96001) (xy 110.236508 -55.96001) (xy 110.236008 -56.012913) (xy 110.228006 -56.118415)
			(xy 110.212048 -56.22301) (xy 110.188225 -56.326099) (xy 110.156674 -56.427091) (xy 110.117576 -56.525407)
			(xy 110.071153 -56.620485) (xy 110.017674 -56.711779) (xy 109.957443 -56.798768) (xy 109.890805 -56.880952)
			(xy 109.818143 -56.957861) (xy 109.739873 -57.029055) (xy 109.656442 -57.094125) (xy 109.568329 -57.152699)
			(xy 109.476039 -57.204442) (xy 109.3801 -57.249056) (xy 109.281061 -57.286287) (xy 109.17949 -57.315921)
			(xy 109.075969 -57.337789) (xy 108.971091 -57.351765) (xy 108.865456 -57.357769) (xy 108.75967 -57.355766)
			(xy 108.654337 -57.345769) (xy 108.550063 -57.327835) (xy 108.447444 -57.302065) (xy 108.347067 -57.268609)
			(xy 108.249508 -57.227657) (xy 108.155326 -57.179444) (xy 108.06506 -57.124246) (xy 107.979227 -57.06238)
			(xy 107.898318 -56.994199) (xy 107.822798 -56.920095) (xy 107.753098 -56.840491) (xy 107.689618 -56.755844)
			(xy 107.632722 -56.666638) (xy 107.582736 -56.573385) (xy 107.539945 -56.476619) (xy 107.504595 -56.376893)
			(xy 107.476888 -56.27478) (xy 107.456983 -56.170864) (xy 107.444995 -56.06574) (xy 107.440991 -55.96001)
			(xy 92.075508 -55.96001) (xy 92.075008 -56.012913) (xy 92.067006 -56.118415) (xy 92.051048 -56.22301)
			(xy 92.027225 -56.326099) (xy 91.995674 -56.427091) (xy 91.956576 -56.525407) (xy 91.910153 -56.620485)
			(xy 91.856674 -56.711779) (xy 91.796443 -56.798768) (xy 91.729805 -56.880952) (xy 91.657143 -56.957861)
			(xy 91.578873 -57.029055) (xy 91.495442 -57.094125) (xy 91.407329 -57.152699) (xy 91.315039 -57.204442)
			(xy 91.2191 -57.249056) (xy 91.120061 -57.286287) (xy 91.01849 -57.315921) (xy 90.914969 -57.337789)
			(xy 90.810091 -57.351765) (xy 90.704456 -57.357769) (xy 90.59867 -57.355766) (xy 90.493337 -57.345769)
			(xy 90.389063 -57.327835) (xy 90.286444 -57.302065) (xy 90.186067 -57.268609) (xy 90.088508 -57.227657)
			(xy 89.994326 -57.179444) (xy 89.90406 -57.124246) (xy 89.818227 -57.06238) (xy 89.737318 -56.994199)
			(xy 89.661798 -56.920095) (xy 89.592098 -56.840491) (xy 89.528618 -56.755844) (xy 89.471722 -56.666638)
			(xy 89.421736 -56.573385) (xy 89.378945 -56.476619) (xy 89.343595 -56.376893) (xy 89.315888 -56.27478)
			(xy 89.295983 -56.170864) (xy 89.283995 -56.06574) (xy 89.279991 -55.96001) (xy 80.772508 -55.96001)
			(xy 80.772008 -56.012913) (xy 80.764006 -56.118415) (xy 80.748048 -56.22301) (xy 80.724225 -56.326099)
			(xy 80.692674 -56.427091) (xy 80.653576 -56.525407) (xy 80.607153 -56.620485) (xy 80.553674 -56.711779)
			(xy 80.493443 -56.798768) (xy 80.426805 -56.880952) (xy 80.354143 -56.957861) (xy 80.275873 -57.029055)
			(xy 80.192442 -57.094125) (xy 80.104329 -57.152699) (xy 80.012039 -57.204442) (xy 79.9161 -57.249056)
			(xy 79.817061 -57.286287) (xy 79.71549 -57.315921) (xy 79.611969 -57.337789) (xy 79.507091 -57.351765)
			(xy 79.401456 -57.357769) (xy 79.29567 -57.355766) (xy 79.190337 -57.345769) (xy 79.086063 -57.327835)
			(xy 78.983444 -57.302065) (xy 78.883067 -57.268609) (xy 78.785508 -57.227657) (xy 78.691326 -57.179444)
			(xy 78.60106 -57.124246) (xy 78.515227 -57.06238) (xy 78.434318 -56.994199) (xy 78.358798 -56.920095)
			(xy 78.289098 -56.840491) (xy 78.225618 -56.755844) (xy 78.168722 -56.666638) (xy 78.118736 -56.573385)
			(xy 78.075945 -56.476619) (xy 78.040595 -56.376893) (xy 78.012888 -56.27478) (xy 77.992983 -56.170864)
			(xy 77.980995 -56.06574) (xy 77.976991 -55.96001) (xy 69.469508 -55.96001) (xy 69.469008 -56.012913)
			(xy 69.461006 -56.118415) (xy 69.445048 -56.22301) (xy 69.421225 -56.326099) (xy 69.389674 -56.427091)
			(xy 69.350576 -56.525407) (xy 69.304153 -56.620485) (xy 69.250674 -56.711779) (xy 69.190443 -56.798768)
			(xy 69.123805 -56.880952) (xy 69.051143 -56.957861) (xy 68.972873 -57.029055) (xy 68.889442 -57.094125)
			(xy 68.801329 -57.152699) (xy 68.709039 -57.204442) (xy 68.6131 -57.249056) (xy 68.514061 -57.286287)
			(xy 68.41249 -57.315921) (xy 68.308969 -57.337789) (xy 68.204091 -57.351765) (xy 68.098456 -57.357769)
			(xy 67.99267 -57.355766) (xy 67.887337 -57.345769) (xy 67.783063 -57.327835) (xy 67.680444 -57.302065)
			(xy 67.580067 -57.268609) (xy 67.482508 -57.227657) (xy 67.388326 -57.179444) (xy 67.29806 -57.124246)
			(xy 67.212227 -57.06238) (xy 67.131318 -56.994199) (xy 67.055798 -56.920095) (xy 66.986098 -56.840491)
			(xy 66.922618 -56.755844) (xy 66.865722 -56.666638) (xy 66.815736 -56.573385) (xy 66.772945 -56.476619)
			(xy 66.737595 -56.376893) (xy 66.709888 -56.27478) (xy 66.689983 -56.170864) (xy 66.677995 -56.06574)
			(xy 66.673991 -55.96001) (xy 47.7774 -55.96001) (xy 47.7774 -56.341518) (xy 47.77701 -56.351592)
			(xy 47.769268 -56.370191) (xy 47.762414 -56.377586) (xy 45.303186 -58.836814) (xy 45.295786 -58.843654)
			(xy 45.277187 -58.851373) (xy 45.267118 -58.8518) (xy 43.785282 -58.8518) (xy 43.775208 -58.85141)
			(xy 43.756609 -58.843668) (xy 43.749214 -58.836814) (xy 42.966386 -58.053986) (xy 42.959546 -58.046586)
			(xy 42.951827 -58.027987) (xy 42.9514 -58.017918) (xy 40.513 -58.017918) (xy 40.513 -58.856118) (xy 40.512573 -58.866187)
			(xy 40.504854 -58.884786) (xy 40.498014 -58.892186) (xy 40.179244 -59.210956) (xy 40.1701 -59.223656)
			(xy 40.151662 -59.258605) (xy 40.109459 -59.325415) (xy 40.061497 -59.388219) (xy 40.008156 -59.446523)
			(xy 39.949854 -59.499868) (xy 39.887052 -59.547833) (xy 39.820244 -59.590039) (xy 39.78529 -59.608466)
			(xy 39.77259 -59.61761) (xy 39.7002 -59.69) (xy 39.550594 -59.69) (xy 39.50804 -59.697857) (xy 39.421907 -59.706254)
			(xy 39.378636 -59.706764) (xy 39.335366 -59.706247) (xy 39.249234 -59.697848) (xy 39.206678 -59.69)
			(xy 38.2778 -59.69) (xy 37.9349 -60.0329) (xy 37.9349 -61.4045) (xy 39.0144 -62.484) (xy 39.497 -62.484)
			(xy 39.6748 -62.3062) (xy 39.6748 -61.866526) (xy 39.631162 -61.879758) (xy 39.541873 -61.898294)
			(xy 39.451157 -61.907608) (xy 39.40556 -61.908182) (xy 39.363199 -61.907678) (xy 39.278862 -61.899625)
			(xy 39.195672 -61.883591) (xy 39.114382 -61.859723) (xy 39.03573 -61.828235) (xy 38.960427 -61.789413)
			(xy 38.889155 -61.74361) (xy 38.822559 -61.691239) (xy 38.761244 -61.632774) (xy 38.705763 -61.568746)
			(xy 38.65662 -61.499734) (xy 38.61426 -61.426364) (xy 38.579065 -61.349299) (xy 38.551356 -61.269237)
			(xy 38.531382 -61.186904) (xy 38.519325 -61.103045) (xy 38.515294 -61.01842) (xy 38.519325 -60.933795)
			(xy 38.531382 -60.849936) (xy 38.551356 -60.767603) (xy 38.579065 -60.687541) (xy 38.61426 -60.610476)
			(xy 38.65662 -60.537106) (xy 38.705763 -60.468094) (xy 38.761244 -60.404066) (xy 38.822559 -60.345601)
			(xy 38.889155 -60.29323) (xy 38.960427 -60.247427) (xy 39.03573 -60.208605) (xy 39.114382 -60.177117)
			(xy 39.195672 -60.153249) (xy 39.278862 -60.137215) (xy 39.363199 -60.129162) (xy 39.40556 -60.128658)
			(xy 39.453004 -60.129287) (xy 39.547349 -60.139411) (xy 39.640085 -60.159507) (xy 39.730158 -60.189346)
			(xy 39.773606 -60.208414) (xy 39.783066 -60.166137) (xy 39.809126 -60.083511) (xy 39.84309 -60.003807)
			(xy 39.884637 -59.92778) (xy 39.933375 -59.85615) (xy 39.988842 -59.789594) (xy 40.050513 -59.728742)
			(xy 40.117804 -59.67417) (xy 40.190079 -59.626395) (xy 40.266654 -59.585867) (xy 40.346805 -59.552971)
			(xy 40.429773 -59.528019) (xy 40.514772 -59.511246) (xy 40.600999 -59.50281) (xy 40.644318 -59.502294)
			(xy 40.68739 -59.502801) (xy 40.773129 -59.511127) (xy 40.857663 -59.527701) (xy 40.9402 -59.552366)
			(xy 41.019967 -59.584892) (xy 41.096216 -59.624975) (xy 41.168236 -59.672238) (xy 41.235351 -59.726241)
			(xy 41.296933 -59.786476) (xy 41.352405 -59.852381) (xy 41.401249 -59.923338) (xy 41.422574 -59.960764)
			(xy 41.430457 -59.973924) (xy 41.452598 -59.995137) (xy 41.480036 -60.008823) (xy 41.5103 -60.013751)
			(xy 41.540664 -60.009476) (xy 41.56839 -59.996383) (xy 41.580054 -59.986418) (xy 41.611216 -59.958489)
			(xy 41.67793 -59.907967) (xy 41.749094 -59.863932) (xy 41.824079 -59.826775) (xy 41.902221 -59.796823)
			(xy 41.982831 -59.774342) (xy 42.065195 -59.75953) (xy 42.10685 -59.755532) (xy 42.115994 -59.75477)
			(xy 42.131996 -59.747404) (xy 42.276014 -59.603386) (xy 42.283409 -59.596532) (xy 42.302008 -59.58879)
			(xy 42.312082 -59.5884) (xy 42.904918 -59.5884) (xy 42.914987 -59.588827) (xy 42.933586 -59.596546)
			(xy 42.940986 -59.603386) (xy 44.536614 -61.199014) (xy 44.543468 -61.206409) (xy 44.55121 -61.225008)
			(xy 44.5516 -61.235082) (xy 44.5516 -62.2554) (xy 47.309532 -62.2554) (xy 47.309532 -62.254892) (xy 47.310135 -62.20856)
			(xy 47.319807 -62.116402) (xy 47.339003 -62.025748) (xy 47.367516 -61.937579) (xy 47.385732 -61.894974)
			(xy 47.389541 -61.885032) (xy 47.389541 -61.863768) (xy 47.385732 -61.853826) (xy 47.367506 -61.811225)
			(xy 47.33899 -61.723056) (xy 47.319799 -61.632401) (xy 47.31014 -61.54024) (xy 47.309532 -61.493908)
			(xy 47.309532 -61.4934) (xy 47.309952 -61.452296) (xy 47.317538 -61.370438) (xy 47.332644 -61.289629)
			(xy 47.355142 -61.210559) (xy 47.38484 -61.133902) (xy 47.421485 -61.060312) (xy 47.464763 -60.990417)
			(xy 47.514306 -60.924814) (xy 47.569691 -60.864063) (xy 47.630445 -60.80868) (xy 47.69605 -60.75914)
			(xy 47.765947 -60.715865) (xy 47.839538 -60.679224) (xy 47.916197 -60.649529) (xy 47.995268 -60.627035)
			(xy 48.076077 -60.611932) (xy 48.157936 -60.60435) (xy 48.19904 -60.603892) (xy 48.199548 -60.603892)
			(xy 48.245879 -60.604519) (xy 48.338037 -60.614184) (xy 48.428691 -60.633374) (xy 48.51686 -60.66188)
			(xy 48.559466 -60.680092) (xy 48.569408 -60.683898) (xy 48.590672 -60.683898) (xy 48.600614 -60.680092)
			(xy 48.643241 -60.661845) (xy 48.731473 -60.633318) (xy 48.822195 -60.614129) (xy 48.914421 -60.604486)
			(xy 48.960786 -60.603892) (xy 48.96104 -60.603892) (xy 48.961294 -60.603892) (xy 49.007657 -60.604508)
			(xy 49.09988 -60.61416) (xy 49.190599 -60.633349) (xy 49.27883 -60.661868) (xy 49.321466 -60.680092)
			(xy 49.331408 -60.683898) (xy 49.352672 -60.683898) (xy 49.362614 -60.680092) (xy 49.405241 -60.661845)
			(xy 49.493473 -60.633318) (xy 49.584195 -60.614129) (xy 49.676421 -60.604486) (xy 49.722786 -60.603892)
			(xy 49.72304 -60.603892) (xy 49.723294 -60.603892) (xy 49.769657 -60.604508) (xy 49.86188 -60.61416)
			(xy 49.952599 -60.633349) (xy 50.04083 -60.661868) (xy 50.083466 -60.680092) (xy 50.093408 -60.683898)
			(xy 50.114672 -60.683898) (xy 50.124614 -60.680092) (xy 50.167241 -60.661845) (xy 50.255473 -60.633318)
			(xy 50.346195 -60.614129) (xy 50.438421 -60.604486) (xy 50.484786 -60.603892) (xy 50.48504 -60.603892)
			(xy 50.485294 -60.603892) (xy 50.531657 -60.604508) (xy 50.62388 -60.61416) (xy 50.714599 -60.633349)
			(xy 50.80283 -60.661868) (xy 50.845466 -60.680092) (xy 50.855408 -60.683898) (xy 50.876672 -60.683898)
			(xy 50.886614 -60.680092) (xy 50.929211 -60.661857) (xy 51.017381 -60.633343) (xy 51.108038 -60.614154)
			(xy 51.200199 -60.604498) (xy 51.246532 -60.603892) (xy 51.24704 -60.603892) (xy 51.288143 -60.604328)
			(xy 51.369998 -60.611917) (xy 51.450804 -60.627026) (xy 51.529872 -60.649525) (xy 51.606526 -60.679224)
			(xy 51.680113 -60.715869) (xy 51.750005 -60.759147) (xy 51.815606 -60.808689) (xy 51.876355 -60.864073)
			(xy 51.931736 -60.924825) (xy 51.981275 -60.990428) (xy 52.02455 -61.060322) (xy 52.061192 -61.133911)
			(xy 52.090887 -61.210566) (xy 52.113384 -61.289634) (xy 52.128489 -61.370441) (xy 52.136073 -61.452297)
			(xy 52.136548 -61.4934) (xy 52.136548 -61.493908) (xy 52.135939 -61.54024) (xy 52.126268 -61.632397)
			(xy 52.107073 -61.723052) (xy 52.078562 -61.81122) (xy 52.060348 -61.853826) (xy 52.05654 -61.863768)
			(xy 52.05654 -61.885032) (xy 52.060348 -61.894974) (xy 52.078573 -61.937576) (xy 52.107089 -62.025744)
			(xy 52.126281 -62.1164) (xy 52.13594 -62.20856) (xy 52.136548 -62.254892) (xy 52.136548 -62.2554)
			(xy 52.136033 -62.296501) (xy 52.128449 -62.378353) (xy 52.113345 -62.459156) (xy 52.090849 -62.538221)
			(xy 52.061155 -62.614873) (xy 52.024515 -62.688458) (xy 51.981242 -62.758349) (xy 51.931705 -62.823949)
			(xy 51.894284 -62.865) (xy 60.705492 -62.865) (xy 60.70599 -62.823495) (xy 60.713726 -62.740846)
			(xy 60.72913 -62.659277) (xy 60.752069 -62.579499) (xy 60.782343 -62.502206) (xy 60.819688 -62.428071)
			(xy 60.863779 -62.357738) (xy 60.888626 -62.324488) (xy 60.894965 -62.315288) (xy 60.899791 -62.2935)
			(xy 60.894965 -62.271712) (xy 60.888626 -62.262512) (xy 60.863779 -62.229262) (xy 60.819683 -62.158931)
			(xy 60.782333 -62.084796) (xy 60.752056 -62.007504) (xy 60.729115 -61.927725) (xy 60.713708 -61.846156)
			(xy 60.705972 -61.763506) (xy 60.705492 -61.722) (xy 60.705958 -61.680844) (xy 60.713545 -61.598883)
			(xy 60.728673 -61.517973) (xy 60.751212 -61.438808) (xy 60.780969 -61.362063) (xy 60.81769 -61.288397)
			(xy 60.86106 -61.218438) (xy 60.910709 -61.152786) (xy 60.966211 -61.092002) (xy 61.027093 -61.036607)
			(xy 61.092832 -60.987074) (xy 61.162867 -60.943827) (xy 61.236598 -60.907236) (xy 61.313395 -60.877614)
			(xy 61.392601 -60.855215) (xy 61.473537 -60.84023) (xy 61.514482 -60.836048) (xy 61.52515 -60.835032)
			(xy 61.543438 -60.825126) (xy 61.595508 -60.75807) (xy 61.598612 -60.753813) (xy 61.603228 -60.744346)
			(xy 61.604652 -60.739274) (xy 61.607192 -60.729368) (xy 61.605668 -60.718954) (xy 61.605668 -60.7187)
			(xy 61.600449 -60.684011) (xy 61.594858 -60.614078) (xy 61.594492 -60.579) (xy 61.594492 -60.578492)
			(xy 61.595098 -60.53216) (xy 61.604769 -60.440002) (xy 61.623965 -60.349348) (xy 61.652477 -60.261179)
			(xy 61.670692 -60.218574) (xy 61.674498 -60.208632) (xy 61.674498 -60.187368) (xy 61.670692 -60.177426)
			(xy 61.65247 -60.134823) (xy 61.623952 -60.046656) (xy 61.60476 -59.956) (xy 61.5951 -59.86384) (xy 61.594492 -59.817508)
			(xy 61.594492 -59.817) (xy 61.594996 -59.774652) (xy 61.603047 -59.690338) (xy 61.619076 -59.607172)
			(xy 61.642937 -59.525905) (xy 61.674416 -59.447275) (xy 61.713227 -59.371994) (xy 61.759017 -59.300742)
			(xy 61.811373 -59.234166) (xy 61.869821 -59.172868) (xy 61.933831 -59.117403) (xy 62.002823 -59.068274)
			(xy 62.076173 -59.025925) (xy 62.153216 -58.990741) (xy 62.233255 -58.963039) (xy 62.315564 -58.943071)
			(xy 62.399399 -58.931018) (xy 62.484 -58.926988) (xy 62.568601 -58.931018) (xy 62.652436 -58.943071)
			(xy 62.734745 -58.963039) (xy 62.814784 -58.990741) (xy 62.891827 -59.025925) (xy 62.965177 -59.068274)
			(xy 63.034169 -59.117403) (xy 63.098179 -59.172868) (xy 63.156627 -59.234166) (xy 63.208983 -59.300742)
			(xy 63.254773 -59.371994) (xy 63.293584 -59.447275) (xy 63.325063 -59.525905) (xy 63.348924 -59.607172)
			(xy 63.364953 -59.690338) (xy 63.373004 -59.774652) (xy 63.373508 -59.817) (xy 63.373508 -59.817508)
			(xy 63.372902 -59.86384) (xy 63.363231 -59.955998) (xy 63.344035 -60.046652) (xy 63.315523 -60.134821)
			(xy 63.297308 -60.177426) (xy 63.293502 -60.187368) (xy 63.293502 -60.208632) (xy 63.297308 -60.218574)
			(xy 63.31553 -60.261177) (xy 63.344048 -60.349344) (xy 63.36324 -60.44) (xy 63.3729 -60.53216) (xy 63.373508 -60.578492)
			(xy 63.373508 -60.579) (xy 63.373042 -60.620156) (xy 63.365455 -60.702117) (xy 63.350327 -60.783027)
			(xy 63.327788 -60.862192) (xy 63.298031 -60.938937) (xy 63.266422 -61.002348) (xy 67.182996 -61.002348)
			(xy 67.182996 -60.917652) (xy 67.191047 -60.833338) (xy 67.207076 -60.750172) (xy 67.230937 -60.668905)
			(xy 67.262416 -60.590275) (xy 67.301227 -60.514994) (xy 67.347017 -60.443742) (xy 67.399373 -60.377166)
			(xy 67.457821 -60.315868) (xy 67.521831 -60.260403) (xy 67.590823 -60.211274) (xy 67.664173 -60.168925)
			(xy 67.741216 -60.133741) (xy 67.821255 -60.106039) (xy 67.903564 -60.086071) (xy 67.987399 -60.074018)
			(xy 68.072 -60.069988) (xy 68.156601 -60.074018) (xy 68.240436 -60.086071) (xy 68.322745 -60.106039)
			(xy 68.402784 -60.133741) (xy 68.479827 -60.168925) (xy 68.553177 -60.211274) (xy 68.622169 -60.260403)
			(xy 68.686179 -60.315868) (xy 68.744627 -60.377166) (xy 68.796983 -60.443742) (xy 68.842773 -60.514994)
			(xy 68.881584 -60.590275) (xy 68.913063 -60.668905) (xy 68.936924 -60.750172) (xy 68.952953 -60.833338)
			(xy 68.961004 -60.917652) (xy 68.961508 -60.96) (xy 68.961004 -61.002348) (xy 78.485996 -61.002348)
			(xy 78.485996 -60.917652) (xy 78.494047 -60.833338) (xy 78.510076 -60.750172) (xy 78.533937 -60.668905)
			(xy 78.565416 -60.590275) (xy 78.604227 -60.514994) (xy 78.650017 -60.443742) (xy 78.702373 -60.377166)
			(xy 78.760821 -60.315868) (xy 78.824831 -60.260403) (xy 78.893823 -60.211274) (xy 78.967173 -60.168925)
			(xy 79.044216 -60.133741) (xy 79.124255 -60.106039) (xy 79.206564 -60.086071) (xy 79.290399 -60.074018)
			(xy 79.375 -60.069988) (xy 79.459601 -60.074018) (xy 79.543436 -60.086071) (xy 79.625745 -60.106039)
			(xy 79.705784 -60.133741) (xy 79.782827 -60.168925) (xy 79.856177 -60.211274) (xy 79.925169 -60.260403)
			(xy 79.989179 -60.315868) (xy 80.047627 -60.377166) (xy 80.099983 -60.443742) (xy 80.145773 -60.514994)
			(xy 80.184584 -60.590275) (xy 80.216063 -60.668905) (xy 80.239924 -60.750172) (xy 80.255953 -60.833338)
			(xy 80.264004 -60.917652) (xy 80.264508 -60.96) (xy 80.264004 -61.002348) (xy 89.788996 -61.002348)
			(xy 89.788996 -60.917652) (xy 89.797047 -60.833338) (xy 89.813076 -60.750172) (xy 89.836937 -60.668905)
			(xy 89.868416 -60.590275) (xy 89.907227 -60.514994) (xy 89.953017 -60.443742) (xy 90.005373 -60.377166)
			(xy 90.063821 -60.315868) (xy 90.127831 -60.260403) (xy 90.196823 -60.211274) (xy 90.270173 -60.168925)
			(xy 90.347216 -60.133741) (xy 90.427255 -60.106039) (xy 90.509564 -60.086071) (xy 90.593399 -60.074018)
			(xy 90.678 -60.069988) (xy 90.762601 -60.074018) (xy 90.846436 -60.086071) (xy 90.928745 -60.106039)
			(xy 91.008784 -60.133741) (xy 91.085827 -60.168925) (xy 91.159177 -60.211274) (xy 91.228169 -60.260403)
			(xy 91.292179 -60.315868) (xy 91.350627 -60.377166) (xy 91.402983 -60.443742) (xy 91.448773 -60.514994)
			(xy 91.487584 -60.590275) (xy 91.519063 -60.668905) (xy 91.542924 -60.750172) (xy 91.558953 -60.833338)
			(xy 91.567004 -60.917652) (xy 91.567508 -60.96) (xy 91.567004 -61.002348) (xy 91.558953 -61.086662)
			(xy 91.542924 -61.169828) (xy 91.519063 -61.251095) (xy 91.487584 -61.329725) (xy 91.448773 -61.405006)
			(xy 91.402983 -61.476258) (xy 91.350627 -61.542834) (xy 91.292179 -61.604132) (xy 91.228169 -61.659597)
			(xy 91.159177 -61.708726) (xy 91.085827 -61.751075) (xy 91.008784 -61.786259) (xy 90.928745 -61.813961)
			(xy 90.846436 -61.833929) (xy 90.762601 -61.845982) (xy 90.678 -61.850013) (xy 90.593399 -61.845982)
			(xy 90.509564 -61.833929) (xy 90.427255 -61.813961) (xy 90.347216 -61.786259) (xy 90.270173 -61.751075)
			(xy 90.196823 -61.708726) (xy 90.127831 -61.659597) (xy 90.063821 -61.604132) (xy 90.005373 -61.542834)
			(xy 89.953017 -61.476258) (xy 89.907227 -61.405006) (xy 89.868416 -61.329725) (xy 89.836937 -61.251095)
			(xy 89.813076 -61.169828) (xy 89.797047 -61.086662) (xy 89.788996 -61.002348) (xy 80.264004 -61.002348)
			(xy 80.255953 -61.086662) (xy 80.239924 -61.169828) (xy 80.216063 -61.251095) (xy 80.184584 -61.329725)
			(xy 80.145773 -61.405006) (xy 80.099983 -61.476258) (xy 80.047627 -61.542834) (xy 79.989179 -61.604132)
			(xy 79.925169 -61.659597) (xy 79.856177 -61.708726) (xy 79.782827 -61.751075) (xy 79.705784 -61.786259)
			(xy 79.625745 -61.813961) (xy 79.543436 -61.833929) (xy 79.459601 -61.845982) (xy 79.375 -61.850013)
			(xy 79.290399 -61.845982) (xy 79.206564 -61.833929) (xy 79.124255 -61.813961) (xy 79.044216 -61.786259)
			(xy 78.967173 -61.751075) (xy 78.893823 -61.708726) (xy 78.824831 -61.659597) (xy 78.760821 -61.604132)
			(xy 78.702373 -61.542834) (xy 78.650017 -61.476258) (xy 78.604227 -61.405006) (xy 78.565416 -61.329725)
			(xy 78.533937 -61.251095) (xy 78.510076 -61.169828) (xy 78.494047 -61.086662) (xy 78.485996 -61.002348)
			(xy 68.961004 -61.002348) (xy 68.952953 -61.086662) (xy 68.936924 -61.169828) (xy 68.913063 -61.251095)
			(xy 68.881584 -61.329725) (xy 68.842773 -61.405006) (xy 68.796983 -61.476258) (xy 68.744627 -61.542834)
			(xy 68.686179 -61.604132) (xy 68.622169 -61.659597) (xy 68.553177 -61.708726) (xy 68.479827 -61.751075)
			(xy 68.402784 -61.786259) (xy 68.322745 -61.813961) (xy 68.240436 -61.833929) (xy 68.156601 -61.845982)
			(xy 68.072 -61.850013) (xy 67.987399 -61.845982) (xy 67.903564 -61.833929) (xy 67.821255 -61.813961)
			(xy 67.741216 -61.786259) (xy 67.664173 -61.751075) (xy 67.590823 -61.708726) (xy 67.521831 -61.659597)
			(xy 67.457821 -61.604132) (xy 67.399373 -61.542834) (xy 67.347017 -61.476258) (xy 67.301227 -61.405006)
			(xy 67.262416 -61.329725) (xy 67.230937 -61.251095) (xy 67.207076 -61.169828) (xy 67.191047 -61.086662)
			(xy 67.182996 -61.002348) (xy 63.266422 -61.002348) (xy 63.26131 -61.012603) (xy 63.21794 -61.082562)
			(xy 63.168291 -61.148214) (xy 63.112789 -61.208998) (xy 63.051907 -61.264393) (xy 62.986168 -61.313926)
			(xy 62.916133 -61.357173) (xy 62.842402 -61.393764) (xy 62.765605 -61.423386) (xy 62.686399 -61.445785)
			(xy 62.605463 -61.46077) (xy 62.564518 -61.464952) (xy 62.55385 -61.465968) (xy 62.535562 -61.475874)
			(xy 62.483492 -61.54293) (xy 62.480388 -61.547187) (xy 62.475772 -61.556654) (xy 62.474348 -61.561726)
			(xy 62.471808 -61.571632) (xy 62.473332 -61.582046) (xy 62.473332 -61.5823) (xy 62.478551 -61.616989)
			(xy 62.484142 -61.686922) (xy 62.484508 -61.722) (xy 62.48401 -61.763505) (xy 62.476274 -61.846154)
			(xy 62.46087 -61.927723) (xy 62.437931 -62.007501) (xy 62.407657 -62.084794) (xy 62.370312 -62.158929)
			(xy 62.326221 -62.229262) (xy 62.301374 -62.262512) (xy 62.295035 -62.271712) (xy 62.290209 -62.2935)
			(xy 62.295035 -62.315288) (xy 62.301374 -62.324488) (xy 62.326221 -62.357738) (xy 62.370317 -62.428069)
			(xy 62.407667 -62.502204) (xy 62.437944 -62.579496) (xy 62.460885 -62.659275) (xy 62.475755 -62.738)
			(xy 100.329492 -62.738) (xy 100.32999 -62.696495) (xy 100.337726 -62.613846) (xy 100.35313 -62.532277)
			(xy 100.376069 -62.452499) (xy 100.406343 -62.375206) (xy 100.443688 -62.301071) (xy 100.487779 -62.230738)
			(xy 100.512626 -62.197488) (xy 100.518965 -62.188288) (xy 100.523791 -62.1665) (xy 100.518965 -62.144712)
			(xy 100.512626 -62.135512) (xy 100.487779 -62.102262) (xy 100.443683 -62.031931) (xy 100.406333 -61.957796)
			(xy 100.376056 -61.880504) (xy 100.353115 -61.800725) (xy 100.337708 -61.719156) (xy 100.329972 -61.636506)
			(xy 100.329492 -61.595) (xy 100.329958 -61.553844) (xy 100.337545 -61.471883) (xy 100.352673 -61.390973)
			(xy 100.375212 -61.311808) (xy 100.404969 -61.235063) (xy 100.44169 -61.161397) (xy 100.48506 -61.091438)
			(xy 100.534709 -61.025786) (xy 100.590211 -60.965002) (xy 100.651093 -60.909607) (xy 100.716832 -60.860074)
			(xy 100.786867 -60.816827) (xy 100.860598 -60.780236) (xy 100.937395 -60.750614) (xy 101.016601 -60.728215)
			(xy 101.097537 -60.71323) (xy 101.138482 -60.709048) (xy 101.14915 -60.708032) (xy 101.167438 -60.698126)
			(xy 101.219508 -60.63107) (xy 101.222612 -60.626813) (xy 101.227228 -60.617346) (xy 101.228652 -60.612274)
			(xy 101.231192 -60.602368) (xy 101.229668 -60.591954) (xy 101.229668 -60.5917) (xy 101.224449 -60.557011)
			(xy 101.218858 -60.487078) (xy 101.218492 -60.452) (xy 101.218492 -60.451492) (xy 101.219098 -60.40516)
			(xy 101.228769 -60.313002) (xy 101.247965 -60.222348) (xy 101.276477 -60.134179) (xy 101.294692 -60.091574)
			(xy 101.298498 -60.081632) (xy 101.298498 -60.060368) (xy 101.294692 -60.050426) (xy 101.27647 -60.007823)
			(xy 101.247952 -59.919656) (xy 101.22876 -59.829) (xy 101.2191 -59.73684) (xy 101.218492 -59.690508)
			(xy 101.218492 -59.69) (xy 101.218996 -59.647652) (xy 101.227047 -59.563338) (xy 101.243076 -59.480172)
			(xy 101.266937 -59.398905) (xy 101.298416 -59.320275) (xy 101.337227 -59.244994) (xy 101.383017 -59.173742)
			(xy 101.435373 -59.107166) (xy 101.493821 -59.045868) (xy 101.557831 -58.990403) (xy 101.626823 -58.941274)
			(xy 101.700173 -58.898925) (xy 101.777216 -58.863741) (xy 101.857255 -58.836039) (xy 101.939564 -58.816071)
			(xy 102.023399 -58.804018) (xy 102.108 -58.799988) (xy 102.192601 -58.804018) (xy 102.276436 -58.816071)
			(xy 102.358745 -58.836039) (xy 102.438784 -58.863741) (xy 102.515827 -58.898925) (xy 102.589177 -58.941274)
			(xy 102.658169 -58.990403) (xy 102.722179 -59.045868) (xy 102.780627 -59.107166) (xy 102.832983 -59.173742)
			(xy 102.878773 -59.244994) (xy 102.917584 -59.320275) (xy 102.949063 -59.398905) (xy 102.972924 -59.480172)
			(xy 102.988953 -59.563338) (xy 102.997004 -59.647652) (xy 102.997508 -59.69) (xy 102.997508 -59.690508)
			(xy 102.996902 -59.73684) (xy 102.987231 -59.828998) (xy 102.968035 -59.919652) (xy 102.939523 -60.007821)
			(xy 102.921308 -60.050426) (xy 102.917502 -60.060368) (xy 102.917502 -60.081632) (xy 102.921308 -60.091574)
			(xy 102.93953 -60.134177) (xy 102.968048 -60.222344) (xy 102.98724 -60.313) (xy 102.9969 -60.40516)
			(xy 102.997508 -60.451492) (xy 102.997508 -60.452) (xy 102.997042 -60.493156) (xy 102.989455 -60.575117)
			(xy 102.974327 -60.656027) (xy 102.951788 -60.735192) (xy 102.922031 -60.811937) (xy 102.88531 -60.885603)
			(xy 102.84194 -60.955562) (xy 102.806558 -61.002348) (xy 107.949996 -61.002348) (xy 107.949996 -60.917652)
			(xy 107.958047 -60.833338) (xy 107.974076 -60.750172) (xy 107.997937 -60.668905) (xy 108.029416 -60.590275)
			(xy 108.068227 -60.514994) (xy 108.114017 -60.443742) (xy 108.166373 -60.377166) (xy 108.224821 -60.315868)
			(xy 108.288831 -60.260403) (xy 108.357823 -60.211274) (xy 108.431173 -60.168925) (xy 108.508216 -60.133741)
			(xy 108.588255 -60.106039) (xy 108.670564 -60.086071) (xy 108.754399 -60.074018) (xy 108.839 -60.069988)
			(xy 108.923601 -60.074018) (xy 109.007436 -60.086071) (xy 109.089745 -60.106039) (xy 109.169784 -60.133741)
			(xy 109.246827 -60.168925) (xy 109.320177 -60.211274) (xy 109.389169 -60.260403) (xy 109.453179 -60.315868)
			(xy 109.511627 -60.377166) (xy 109.563983 -60.443742) (xy 109.609773 -60.514994) (xy 109.648584 -60.590275)
			(xy 109.680063 -60.668905) (xy 109.703924 -60.750172) (xy 109.719953 -60.833338) (xy 109.728004 -60.917652)
			(xy 109.728508 -60.96) (xy 109.728004 -61.002348) (xy 119.125996 -61.002348) (xy 119.125996 -60.917652)
			(xy 119.134047 -60.833338) (xy 119.150076 -60.750172) (xy 119.173937 -60.668905) (xy 119.205416 -60.590275)
			(xy 119.244227 -60.514994) (xy 119.290017 -60.443742) (xy 119.342373 -60.377166) (xy 119.400821 -60.315868)
			(xy 119.464831 -60.260403) (xy 119.533823 -60.211274) (xy 119.607173 -60.168925) (xy 119.684216 -60.133741)
			(xy 119.764255 -60.106039) (xy 119.846564 -60.086071) (xy 119.930399 -60.074018) (xy 120.015 -60.069988)
			(xy 120.099601 -60.074018) (xy 120.183436 -60.086071) (xy 120.265745 -60.106039) (xy 120.345784 -60.133741)
			(xy 120.422827 -60.168925) (xy 120.496177 -60.211274) (xy 120.565169 -60.260403) (xy 120.629179 -60.315868)
			(xy 120.687627 -60.377166) (xy 120.739983 -60.443742) (xy 120.785773 -60.514994) (xy 120.824584 -60.590275)
			(xy 120.856063 -60.668905) (xy 120.879924 -60.750172) (xy 120.895953 -60.833338) (xy 120.904004 -60.917652)
			(xy 120.904508 -60.96) (xy 120.904004 -61.002348) (xy 130.301996 -61.002348) (xy 130.301996 -60.917652)
			(xy 130.310047 -60.833338) (xy 130.326076 -60.750172) (xy 130.349937 -60.668905) (xy 130.381416 -60.590275)
			(xy 130.420227 -60.514994) (xy 130.466017 -60.443742) (xy 130.518373 -60.377166) (xy 130.576821 -60.315868)
			(xy 130.640831 -60.260403) (xy 130.709823 -60.211274) (xy 130.783173 -60.168925) (xy 130.860216 -60.133741)
			(xy 130.940255 -60.106039) (xy 131.022564 -60.086071) (xy 131.106399 -60.074018) (xy 131.191 -60.069988)
			(xy 131.275601 -60.074018) (xy 131.359436 -60.086071) (xy 131.441745 -60.106039) (xy 131.521784 -60.133741)
			(xy 131.598827 -60.168925) (xy 131.672177 -60.211274) (xy 131.741169 -60.260403) (xy 131.805179 -60.315868)
			(xy 131.863627 -60.377166) (xy 131.915983 -60.443742) (xy 131.961773 -60.514994) (xy 132.000584 -60.590275)
			(xy 132.032063 -60.668905) (xy 132.055924 -60.750172) (xy 132.071953 -60.833338) (xy 132.080004 -60.917652)
			(xy 132.080508 -60.96) (xy 132.080004 -61.002348) (xy 132.071953 -61.086662) (xy 132.055924 -61.169828)
			(xy 132.032063 -61.251095) (xy 132.000584 -61.329725) (xy 131.961773 -61.405006) (xy 131.915983 -61.476258)
			(xy 131.863627 -61.542834) (xy 131.805179 -61.604132) (xy 131.741169 -61.659597) (xy 131.672177 -61.708726)
			(xy 131.598827 -61.751075) (xy 131.521784 -61.786259) (xy 131.441745 -61.813961) (xy 131.359436 -61.833929)
			(xy 131.275601 -61.845982) (xy 131.191 -61.850013) (xy 131.106399 -61.845982) (xy 131.022564 -61.833929)
			(xy 130.940255 -61.813961) (xy 130.860216 -61.786259) (xy 130.783173 -61.751075) (xy 130.709823 -61.708726)
			(xy 130.640831 -61.659597) (xy 130.576821 -61.604132) (xy 130.518373 -61.542834) (xy 130.466017 -61.476258)
			(xy 130.420227 -61.405006) (xy 130.381416 -61.329725) (xy 130.349937 -61.251095) (xy 130.326076 -61.169828)
			(xy 130.310047 -61.086662) (xy 130.301996 -61.002348) (xy 120.904004 -61.002348) (xy 120.895953 -61.086662)
			(xy 120.879924 -61.169828) (xy 120.856063 -61.251095) (xy 120.824584 -61.329725) (xy 120.785773 -61.405006)
			(xy 120.739983 -61.476258) (xy 120.687627 -61.542834) (xy 120.629179 -61.604132) (xy 120.565169 -61.659597)
			(xy 120.496177 -61.708726) (xy 120.422827 -61.751075) (xy 120.345784 -61.786259) (xy 120.265745 -61.813961)
			(xy 120.183436 -61.833929) (xy 120.099601 -61.845982) (xy 120.015 -61.850013) (xy 119.930399 -61.845982)
			(xy 119.846564 -61.833929) (xy 119.764255 -61.813961) (xy 119.684216 -61.786259) (xy 119.607173 -61.751075)
			(xy 119.533823 -61.708726) (xy 119.464831 -61.659597) (xy 119.400821 -61.604132) (xy 119.342373 -61.542834)
			(xy 119.290017 -61.476258) (xy 119.244227 -61.405006) (xy 119.205416 -61.329725) (xy 119.173937 -61.251095)
			(xy 119.150076 -61.169828) (xy 119.134047 -61.086662) (xy 119.125996 -61.002348) (xy 109.728004 -61.002348)
			(xy 109.719953 -61.086662) (xy 109.703924 -61.169828) (xy 109.680063 -61.251095) (xy 109.648584 -61.329725)
			(xy 109.609773 -61.405006) (xy 109.563983 -61.476258) (xy 109.511627 -61.542834) (xy 109.453179 -61.604132)
			(xy 109.389169 -61.659597) (xy 109.320177 -61.708726) (xy 109.246827 -61.751075) (xy 109.169784 -61.786259)
			(xy 109.089745 -61.813961) (xy 109.007436 -61.833929) (xy 108.923601 -61.845982) (xy 108.839 -61.850013)
			(xy 108.754399 -61.845982) (xy 108.670564 -61.833929) (xy 108.588255 -61.813961) (xy 108.508216 -61.786259)
			(xy 108.431173 -61.751075) (xy 108.357823 -61.708726) (xy 108.288831 -61.659597) (xy 108.224821 -61.604132)
			(xy 108.166373 -61.542834) (xy 108.114017 -61.476258) (xy 108.068227 -61.405006) (xy 108.029416 -61.329725)
			(xy 107.997937 -61.251095) (xy 107.974076 -61.169828) (xy 107.958047 -61.086662) (xy 107.949996 -61.002348)
			(xy 102.806558 -61.002348) (xy 102.792291 -61.021214) (xy 102.736789 -61.081998) (xy 102.675907 -61.137393)
			(xy 102.610168 -61.186926) (xy 102.540133 -61.230173) (xy 102.466402 -61.266764) (xy 102.389605 -61.296386)
			(xy 102.310399 -61.318785) (xy 102.229463 -61.33377) (xy 102.188518 -61.337952) (xy 102.17785 -61.338968)
			(xy 102.159562 -61.348874) (xy 102.107492 -61.41593) (xy 102.104388 -61.420187) (xy 102.099772 -61.429654)
			(xy 102.098348 -61.434726) (xy 102.095808 -61.444632) (xy 102.097332 -61.455046) (xy 102.097332 -61.4553)
			(xy 102.102551 -61.489989) (xy 102.108142 -61.559922) (xy 102.108508 -61.595) (xy 102.10801 -61.636505)
			(xy 102.100274 -61.719154) (xy 102.08487 -61.800723) (xy 102.061931 -61.880501) (xy 102.031657 -61.957794)
			(xy 101.994312 -62.031929) (xy 101.950221 -62.102262) (xy 101.925374 -62.135512) (xy 101.919035 -62.144712)
			(xy 101.914209 -62.1665) (xy 101.919035 -62.188288) (xy 101.925374 -62.197488) (xy 101.950221 -62.230738)
			(xy 101.994317 -62.301069) (xy 102.031667 -62.375204) (xy 102.061944 -62.452496) (xy 102.084885 -62.532275)
			(xy 102.100292 -62.613844) (xy 102.108028 -62.696494) (xy 102.108508 -62.738) (xy 139.318492 -62.738)
			(xy 139.319052 -62.694207) (xy 139.327682 -62.607046) (xy 139.344828 -62.521154) (xy 139.370325 -62.43736)
			(xy 139.403926 -62.356475) (xy 139.424156 -62.31763) (xy 139.429577 -62.306164) (xy 139.429577 -62.280836)
			(xy 139.424156 -62.26937) (xy 139.403917 -62.230528) (xy 139.370281 -62.149652) (xy 139.344768 -62.065859)
			(xy 139.327623 -61.979963) (xy 139.319013 -61.892796) (xy 139.318492 -61.849) (xy 139.318958 -61.807844)
			(xy 139.326545 -61.725883) (xy 139.341673 -61.644973) (xy 139.364212 -61.565808) (xy 139.393969 -61.489063)
			(xy 139.43069 -61.415397) (xy 139.47406 -61.345438) (xy 139.523709 -61.279786) (xy 139.579211 -61.219002)
			(xy 139.640093 -61.163607) (xy 139.705832 -61.114074) (xy 139.775867 -61.070827) (xy 139.849598 -61.034236)
			(xy 139.926395 -61.004614) (xy 140.005601 -60.982215) (xy 140.086537 -60.96723) (xy 140.127482 -60.963048)
			(xy 140.13815 -60.962032) (xy 140.156438 -60.952126) (xy 140.208508 -60.88507) (xy 140.211612 -60.880813)
			(xy 140.216228 -60.871346) (xy 140.217652 -60.866274) (xy 140.220192 -60.856368) (xy 140.218668 -60.845954)
			(xy 140.218668 -60.8457) (xy 140.213449 -60.811011) (xy 140.207858 -60.741078) (xy 140.207492 -60.706)
			(xy 140.207492 -60.705492) (xy 140.208098 -60.65916) (xy 140.217769 -60.567002) (xy 140.236965 -60.476348)
			(xy 140.265477 -60.388179) (xy 140.283692 -60.345574) (xy 140.287498 -60.335632) (xy 140.287498 -60.314368)
			(xy 140.283692 -60.304426) (xy 140.26547 -60.261823) (xy 140.236952 -60.173656) (xy 140.21776 -60.083)
			(xy 140.2081 -59.99084) (xy 140.207492 -59.944508) (xy 140.207492 -59.944) (xy 140.207996 -59.901652)
			(xy 140.216047 -59.817338) (xy 140.232076 -59.734172) (xy 140.255937 -59.652905) (xy 140.287416 -59.574275)
			(xy 140.326227 -59.498994) (xy 140.372017 -59.427742) (xy 140.424373 -59.361166) (xy 140.482821 -59.299868)
			(xy 140.546831 -59.244403) (xy 140.615823 -59.195274) (xy 140.689173 -59.152925) (xy 140.766216 -59.117741)
			(xy 140.846255 -59.090039) (xy 140.928564 -59.070071) (xy 141.012399 -59.058018) (xy 141.097 -59.053988)
			(xy 141.181601 -59.058018) (xy 141.265436 -59.070071) (xy 141.347745 -59.090039) (xy 141.427784 -59.117741)
			(xy 141.504827 -59.152925) (xy 141.578177 -59.195274) (xy 141.647169 -59.244403) (xy 141.711179 -59.299868)
			(xy 141.769627 -59.361166) (xy 141.821983 -59.427742) (xy 141.867773 -59.498994) (xy 141.906584 -59.574275)
			(xy 141.938063 -59.652905) (xy 141.961924 -59.734172) (xy 141.977953 -59.817338) (xy 141.986004 -59.901652)
			(xy 141.986508 -59.944) (xy 141.986508 -59.944508) (xy 141.985902 -59.99084) (xy 141.976231 -60.082998)
			(xy 141.957035 -60.173652) (xy 141.928523 -60.261821) (xy 141.910308 -60.304426) (xy 141.906502 -60.314368)
			(xy 141.906502 -60.335632) (xy 141.910308 -60.345574) (xy 141.92853 -60.388177) (xy 141.957048 -60.476344)
			(xy 141.97624 -60.567) (xy 141.9859 -60.65916) (xy 141.986508 -60.705492) (xy 141.986508 -60.706)
			(xy 141.986042 -60.747156) (xy 141.978455 -60.829117) (xy 141.963327 -60.910027) (xy 141.940788 -60.989192)
			(xy 141.935687 -61.002348) (xy 146.049996 -61.002348) (xy 146.049996 -60.917652) (xy 146.058047 -60.833338)
			(xy 146.074076 -60.750172) (xy 146.097937 -60.668905) (xy 146.129416 -60.590275) (xy 146.168227 -60.514994)
			(xy 146.214017 -60.443742) (xy 146.266373 -60.377166) (xy 146.324821 -60.315868) (xy 146.388831 -60.260403)
			(xy 146.457823 -60.211274) (xy 146.531173 -60.168925) (xy 146.608216 -60.133741) (xy 146.688255 -60.106039)
			(xy 146.770564 -60.086071) (xy 146.854399 -60.074018) (xy 146.939 -60.069988) (xy 147.023601 -60.074018)
			(xy 147.107436 -60.086071) (xy 147.189745 -60.106039) (xy 147.269784 -60.133741) (xy 147.346827 -60.168925)
			(xy 147.420177 -60.211274) (xy 147.489169 -60.260403) (xy 147.553179 -60.315868) (xy 147.611627 -60.377166)
			(xy 147.663983 -60.443742) (xy 147.709773 -60.514994) (xy 147.748584 -60.590275) (xy 147.780063 -60.668905)
			(xy 147.803924 -60.750172) (xy 147.819953 -60.833338) (xy 147.828004 -60.917652) (xy 147.828508 -60.96)
			(xy 147.828004 -61.002348) (xy 157.225996 -61.002348) (xy 157.225996 -60.917652) (xy 157.234047 -60.833338)
			(xy 157.250076 -60.750172) (xy 157.273937 -60.668905) (xy 157.305416 -60.590275) (xy 157.344227 -60.514994)
			(xy 157.390017 -60.443742) (xy 157.442373 -60.377166) (xy 157.500821 -60.315868) (xy 157.564831 -60.260403)
			(xy 157.633823 -60.211274) (xy 157.707173 -60.168925) (xy 157.784216 -60.133741) (xy 157.864255 -60.106039)
			(xy 157.946564 -60.086071) (xy 158.030399 -60.074018) (xy 158.115 -60.069988) (xy 158.199601 -60.074018)
			(xy 158.283436 -60.086071) (xy 158.365745 -60.106039) (xy 158.445784 -60.133741) (xy 158.522827 -60.168925)
			(xy 158.596177 -60.211274) (xy 158.665169 -60.260403) (xy 158.729179 -60.315868) (xy 158.787627 -60.377166)
			(xy 158.839983 -60.443742) (xy 158.885773 -60.514994) (xy 158.924584 -60.590275) (xy 158.956063 -60.668905)
			(xy 158.979924 -60.750172) (xy 158.995953 -60.833338) (xy 159.004004 -60.917652) (xy 159.004508 -60.96)
			(xy 159.004004 -61.002348) (xy 168.401996 -61.002348) (xy 168.401996 -60.917652) (xy 168.410047 -60.833338)
			(xy 168.426076 -60.750172) (xy 168.449937 -60.668905) (xy 168.481416 -60.590275) (xy 168.520227 -60.514994)
			(xy 168.566017 -60.443742) (xy 168.618373 -60.377166) (xy 168.676821 -60.315868) (xy 168.740831 -60.260403)
			(xy 168.809823 -60.211274) (xy 168.883173 -60.168925) (xy 168.960216 -60.133741) (xy 169.040255 -60.106039)
			(xy 169.122564 -60.086071) (xy 169.206399 -60.074018) (xy 169.291 -60.069988) (xy 169.375601 -60.074018)
			(xy 169.459436 -60.086071) (xy 169.541745 -60.106039) (xy 169.621784 -60.133741) (xy 169.698827 -60.168925)
			(xy 169.772177 -60.211274) (xy 169.841169 -60.260403) (xy 169.905179 -60.315868) (xy 169.963627 -60.377166)
			(xy 170.015983 -60.443742) (xy 170.061773 -60.514994) (xy 170.100584 -60.590275) (xy 170.132063 -60.668905)
			(xy 170.155924 -60.750172) (xy 170.171953 -60.833338) (xy 170.180004 -60.917652) (xy 170.180508 -60.96)
			(xy 170.180004 -61.002348) (xy 170.171953 -61.086662) (xy 170.155924 -61.169828) (xy 170.132063 -61.251095)
			(xy 170.100584 -61.329725) (xy 170.061773 -61.405006) (xy 170.015983 -61.476258) (xy 169.963627 -61.542834)
			(xy 169.905179 -61.604132) (xy 169.841169 -61.659597) (xy 169.772177 -61.708726) (xy 169.698827 -61.751075)
			(xy 169.621784 -61.786259) (xy 169.541745 -61.813961) (xy 169.459436 -61.833929) (xy 169.375601 -61.845982)
			(xy 169.31226 -61.849) (xy 179.318666 -61.849) (xy 179.319156 -61.807845) (xy 179.326743 -61.725885)
			(xy 179.34187 -61.644977) (xy 179.364408 -61.565812) (xy 179.394164 -61.489069) (xy 179.430883 -61.415403)
			(xy 179.474252 -61.345445) (xy 179.523899 -61.279794) (xy 179.5794 -61.21901) (xy 179.640279 -61.163615)
			(xy 179.706017 -61.114081) (xy 179.77605 -61.070834) (xy 179.849779 -61.034242) (xy 179.926574 -61.004619)
			(xy 180.005777 -60.982218) (xy 180.086711 -60.967231) (xy 180.127656 -60.963048) (xy 180.138324 -60.962032)
			(xy 180.156612 -60.952126) (xy 180.208682 -60.88507) (xy 180.211783 -60.880811) (xy 180.216401 -60.871345)
			(xy 180.217826 -60.866274) (xy 180.220366 -60.856368) (xy 180.218842 -60.845954) (xy 180.218842 -60.8457)
			(xy 180.213623 -60.811011) (xy 180.208032 -60.741078) (xy 180.207666 -60.706) (xy 180.207666 -60.705492)
			(xy 180.208274 -60.65916) (xy 180.217945 -60.567002) (xy 180.23714 -60.476348) (xy 180.265651 -60.38818)
			(xy 180.283866 -60.345574) (xy 180.287673 -60.335632) (xy 180.287673 -60.314368) (xy 180.283866 -60.304426)
			(xy 180.265642 -60.261824) (xy 180.237125 -60.173656) (xy 180.217933 -60.083) (xy 180.208274 -59.99084)
			(xy 180.207666 -59.944508) (xy 180.207666 -59.944) (xy 180.20817 -59.901652) (xy 180.216221 -59.817338)
			(xy 180.23225 -59.734172) (xy 180.256111 -59.652905) (xy 180.28759 -59.574275) (xy 180.326401 -59.498994)
			(xy 180.372191 -59.427742) (xy 180.424547 -59.361166) (xy 180.482995 -59.299868) (xy 180.547005 -59.244403)
			(xy 180.615997 -59.195274) (xy 180.689347 -59.152925) (xy 180.76639 -59.117741) (xy 180.846429 -59.090039)
			(xy 180.928738 -59.070071) (xy 181.012573 -59.058018) (xy 181.097174 -59.053988) (xy 181.181775 -59.058018)
			(xy 181.26561 -59.070071) (xy 181.347919 -59.090039) (xy 181.427958 -59.117741) (xy 181.505001 -59.152925)
			(xy 181.578351 -59.195274) (xy 181.647343 -59.244403) (xy 181.711353 -59.299868) (xy 181.769801 -59.361166)
			(xy 181.822157 -59.427742) (xy 181.867947 -59.498994) (xy 181.906758 -59.574275) (xy 181.938237 -59.652905)
			(xy 181.962098 -59.734172) (xy 181.978127 -59.817338) (xy 181.986178 -59.901652) (xy 181.986682 -59.944)
			(xy 181.986682 -59.944508) (xy 181.986078 -59.99084) (xy 181.976406 -60.082998) (xy 181.95721 -60.173652)
			(xy 181.928698 -60.261821) (xy 181.910482 -60.304426) (xy 181.906678 -60.314369) (xy 181.906678 -60.335631)
			(xy 181.910482 -60.345574) (xy 181.928702 -60.388178) (xy 181.957221 -60.476345) (xy 181.976414 -60.567)
			(xy 181.986074 -60.65916) (xy 181.986682 -60.705492) (xy 181.986682 -60.706) (xy 181.986239 -60.747157)
			(xy 181.978652 -60.829119) (xy 181.963524 -60.91003) (xy 181.940984 -60.989197) (xy 181.935885 -61.002348)
			(xy 186.05017 -61.002348) (xy 186.05017 -60.917652) (xy 186.058221 -60.833338) (xy 186.07425 -60.750172)
			(xy 186.098111 -60.668905) (xy 186.12959 -60.590275) (xy 186.168401 -60.514994) (xy 186.214191 -60.443742)
			(xy 186.266547 -60.377166) (xy 186.324995 -60.315868) (xy 186.389005 -60.260403) (xy 186.457997 -60.211274)
			(xy 186.531347 -60.168925) (xy 186.60839 -60.133741) (xy 186.688429 -60.106039) (xy 186.770738 -60.086071)
			(xy 186.854573 -60.074018) (xy 186.939174 -60.069988) (xy 187.023775 -60.074018) (xy 187.10761 -60.086071)
			(xy 187.189919 -60.106039) (xy 187.269958 -60.133741) (xy 187.347001 -60.168925) (xy 187.420351 -60.211274)
			(xy 187.489343 -60.260403) (xy 187.553353 -60.315868) (xy 187.611801 -60.377166) (xy 187.664157 -60.443742)
			(xy 187.709947 -60.514994) (xy 187.748758 -60.590275) (xy 187.780237 -60.668905) (xy 187.804098 -60.750172)
			(xy 187.820127 -60.833338) (xy 187.828178 -60.917652) (xy 187.828682 -60.96) (xy 187.828178 -61.002348)
			(xy 197.22617 -61.002348) (xy 197.22617 -60.917652) (xy 197.234221 -60.833338) (xy 197.25025 -60.750172)
			(xy 197.274111 -60.668905) (xy 197.30559 -60.590275) (xy 197.344401 -60.514994) (xy 197.390191 -60.443742)
			(xy 197.442547 -60.377166) (xy 197.500995 -60.315868) (xy 197.565005 -60.260403) (xy 197.633997 -60.211274)
			(xy 197.707347 -60.168925) (xy 197.78439 -60.133741) (xy 197.864429 -60.106039) (xy 197.946738 -60.086071)
			(xy 198.030573 -60.074018) (xy 198.115174 -60.069988) (xy 198.199775 -60.074018) (xy 198.28361 -60.086071)
			(xy 198.365919 -60.106039) (xy 198.445958 -60.133741) (xy 198.523001 -60.168925) (xy 198.596351 -60.211274)
			(xy 198.665343 -60.260403) (xy 198.729353 -60.315868) (xy 198.787801 -60.377166) (xy 198.840157 -60.443742)
			(xy 198.885947 -60.514994) (xy 198.924758 -60.590275) (xy 198.956237 -60.668905) (xy 198.980098 -60.750172)
			(xy 198.996127 -60.833338) (xy 199.004178 -60.917652) (xy 199.004682 -60.96) (xy 199.004178 -61.002348)
			(xy 208.40217 -61.002348) (xy 208.40217 -60.917652) (xy 208.410221 -60.833338) (xy 208.42625 -60.750172)
			(xy 208.450111 -60.668905) (xy 208.48159 -60.590275) (xy 208.520401 -60.514994) (xy 208.566191 -60.443742)
			(xy 208.618547 -60.377166) (xy 208.676995 -60.315868) (xy 208.741005 -60.260403) (xy 208.809997 -60.211274)
			(xy 208.883347 -60.168925) (xy 208.96039 -60.133741) (xy 209.040429 -60.106039) (xy 209.122738 -60.086071)
			(xy 209.206573 -60.074018) (xy 209.291174 -60.069988) (xy 209.375775 -60.074018) (xy 209.45961 -60.086071)
			(xy 209.541919 -60.106039) (xy 209.621958 -60.133741) (xy 209.699001 -60.168925) (xy 209.772351 -60.211274)
			(xy 209.841343 -60.260403) (xy 209.905353 -60.315868) (xy 209.963801 -60.377166) (xy 210.016157 -60.443742)
			(xy 210.061947 -60.514994) (xy 210.100758 -60.590275) (xy 210.132237 -60.668905) (xy 210.156098 -60.750172)
			(xy 210.172127 -60.833338) (xy 210.180178 -60.917652) (xy 210.180682 -60.96) (xy 210.180178 -61.002348)
			(xy 210.172127 -61.086662) (xy 210.156098 -61.169828) (xy 210.132237 -61.251095) (xy 210.100758 -61.329725)
			(xy 210.061947 -61.405006) (xy 210.016157 -61.476258) (xy 209.963801 -61.542834) (xy 209.905353 -61.604132)
			(xy 209.841343 -61.659597) (xy 209.772351 -61.708726) (xy 209.699001 -61.751075) (xy 209.621958 -61.786259)
			(xy 209.541919 -61.813961) (xy 209.45961 -61.833929) (xy 209.375775 -61.845982) (xy 209.291174 -61.850013)
			(xy 209.206573 -61.845982) (xy 209.122738 -61.833929) (xy 209.040429 -61.813961) (xy 208.96039 -61.786259)
			(xy 208.883347 -61.751075) (xy 208.809997 -61.708726) (xy 208.741005 -61.659597) (xy 208.676995 -61.604132)
			(xy 208.618547 -61.542834) (xy 208.566191 -61.476258) (xy 208.520401 -61.405006) (xy 208.48159 -61.329725)
			(xy 208.450111 -61.251095) (xy 208.42625 -61.169828) (xy 208.410221 -61.086662) (xy 208.40217 -61.002348)
			(xy 199.004178 -61.002348) (xy 198.996127 -61.086662) (xy 198.980098 -61.169828) (xy 198.956237 -61.251095)
			(xy 198.924758 -61.329725) (xy 198.885947 -61.405006) (xy 198.840157 -61.476258) (xy 198.787801 -61.542834)
			(xy 198.729353 -61.604132) (xy 198.665343 -61.659597) (xy 198.596351 -61.708726) (xy 198.523001 -61.751075)
			(xy 198.445958 -61.786259) (xy 198.365919 -61.813961) (xy 198.28361 -61.833929) (xy 198.199775 -61.845982)
			(xy 198.115174 -61.850013) (xy 198.030573 -61.845982) (xy 197.946738 -61.833929) (xy 197.864429 -61.813961)
			(xy 197.78439 -61.786259) (xy 197.707347 -61.751075) (xy 197.633997 -61.708726) (xy 197.565005 -61.659597)
			(xy 197.500995 -61.604132) (xy 197.442547 -61.542834) (xy 197.390191 -61.476258) (xy 197.344401 -61.405006)
			(xy 197.30559 -61.329725) (xy 197.274111 -61.251095) (xy 197.25025 -61.169828) (xy 197.234221 -61.086662)
			(xy 197.22617 -61.002348) (xy 187.828178 -61.002348) (xy 187.820127 -61.086662) (xy 187.804098 -61.169828)
			(xy 187.780237 -61.251095) (xy 187.748758 -61.329725) (xy 187.709947 -61.405006) (xy 187.664157 -61.476258)
			(xy 187.611801 -61.542834) (xy 187.553353 -61.604132) (xy 187.489343 -61.659597) (xy 187.420351 -61.708726)
			(xy 187.347001 -61.751075) (xy 187.269958 -61.786259) (xy 187.189919 -61.813961) (xy 187.10761 -61.833929)
			(xy 187.023775 -61.845982) (xy 186.939174 -61.850013) (xy 186.854573 -61.845982) (xy 186.770738 -61.833929)
			(xy 186.688429 -61.813961) (xy 186.60839 -61.786259) (xy 186.531347 -61.751075) (xy 186.457997 -61.708726)
			(xy 186.389005 -61.659597) (xy 186.324995 -61.604132) (xy 186.266547 -61.542834) (xy 186.214191 -61.476258)
			(xy 186.168401 -61.405006) (xy 186.12959 -61.329725) (xy 186.098111 -61.251095) (xy 186.07425 -61.169828)
			(xy 186.058221 -61.086662) (xy 186.05017 -61.002348) (xy 181.935885 -61.002348) (xy 181.911226 -61.065942)
			(xy 181.874504 -61.13961) (xy 181.831132 -61.209569) (xy 181.781482 -61.275222) (xy 181.725977 -61.336006)
			(xy 181.665094 -61.391401) (xy 181.599352 -61.440934) (xy 181.529315 -61.48418) (xy 181.455582 -61.52077)
			(xy 181.378783 -61.550391) (xy 181.299576 -61.572788) (xy 181.218638 -61.587771) (xy 181.177692 -61.591952)
			(xy 181.167024 -61.592968) (xy 181.148736 -61.602874) (xy 181.096666 -61.66993) (xy 181.093559 -61.674185)
			(xy 181.088946 -61.683654) (xy 181.087522 -61.688726) (xy 181.084982 -61.698632) (xy 181.086506 -61.709046)
			(xy 181.086506 -61.7093) (xy 181.091724 -61.743989) (xy 181.097315 -61.813922) (xy 181.097682 -61.849)
			(xy 181.097682 -61.849254) (xy 181.097158 -61.89256) (xy 181.088737 -61.978762) (xy 181.071971 -62.063735)
			(xy 181.047018 -62.146675) (xy 181.014115 -62.226794) (xy 180.994304 -62.265306) (xy 180.989053 -62.276759)
			(xy 180.989173 -62.301923) (xy 180.994558 -62.313312) (xy 181.015235 -62.352477) (xy 181.049579 -62.434116)
			(xy 181.075639 -62.518765) (xy 181.093157 -62.605585) (xy 181.101959 -62.693715) (xy 181.102508 -62.738)
			(xy 181.102004 -62.780348) (xy 181.093953 -62.864662) (xy 181.077924 -62.947828) (xy 181.054063 -63.029095)
			(xy 181.022584 -63.107725) (xy 180.983773 -63.183006) (xy 180.937983 -63.254258) (xy 180.885627 -63.320834)
			(xy 180.827179 -63.382132) (xy 180.763169 -63.437597) (xy 180.694177 -63.486726) (xy 180.620827 -63.529075)
			(xy 180.543784 -63.564259) (xy 180.463745 -63.591961) (xy 180.381436 -63.611929) (xy 180.297601 -63.623982)
			(xy 180.213 -63.628013) (xy 180.128399 -63.623982) (xy 180.044564 -63.611929) (xy 179.962255 -63.591961)
			(xy 179.882216 -63.564259) (xy 179.805173 -63.529075) (xy 179.731823 -63.486726) (xy 179.662831 -63.437597)
			(xy 179.598821 -63.382132) (xy 179.540373 -63.320834) (xy 179.488017 -63.254258) (xy 179.442227 -63.183006)
			(xy 179.403416 -63.107725) (xy 179.371937 -63.029095) (xy 179.348076 -62.947828) (xy 179.332047 -62.864662)
			(xy 179.323996 -62.780348) (xy 179.323492 -62.738) (xy 179.323492 -62.737746) (xy 179.323913 -62.698138)
			(xy 179.330969 -62.619238) (xy 179.34502 -62.541279) (xy 179.365954 -62.46488) (xy 179.379372 -62.427612)
			(xy 179.383944 -62.415674) (xy 179.393463 -62.391644) (xy 179.414943 -62.344625) (xy 179.42687 -62.321694)
			(xy 179.432123 -62.310241) (xy 179.432003 -62.285077) (xy 179.426616 -62.273688) (xy 179.405945 -62.23452)
			(xy 179.371599 -62.152882) (xy 179.345537 -62.068234) (xy 179.328018 -61.981415) (xy 179.319215 -61.893284)
			(xy 179.318666 -61.849) (xy 169.31226 -61.849) (xy 169.291 -61.850013) (xy 169.206399 -61.845982)
			(xy 169.122564 -61.833929) (xy 169.040255 -61.813961) (xy 168.960216 -61.786259) (xy 168.883173 -61.751075)
			(xy 168.809823 -61.708726) (xy 168.740831 -61.659597) (xy 168.676821 -61.604132) (xy 168.618373 -61.542834)
			(xy 168.566017 -61.476258) (xy 168.520227 -61.405006) (xy 168.481416 -61.329725) (xy 168.449937 -61.251095)
			(xy 168.426076 -61.169828) (xy 168.410047 -61.086662) (xy 168.401996 -61.002348) (xy 159.004004 -61.002348)
			(xy 158.995953 -61.086662) (xy 158.979924 -61.169828) (xy 158.956063 -61.251095) (xy 158.924584 -61.329725)
			(xy 158.885773 -61.405006) (xy 158.839983 -61.476258) (xy 158.787627 -61.542834) (xy 158.729179 -61.604132)
			(xy 158.665169 -61.659597) (xy 158.596177 -61.708726) (xy 158.522827 -61.751075) (xy 158.445784 -61.786259)
			(xy 158.365745 -61.813961) (xy 158.283436 -61.833929) (xy 158.199601 -61.845982) (xy 158.115 -61.850013)
			(xy 158.030399 -61.845982) (xy 157.946564 -61.833929) (xy 157.864255 -61.813961) (xy 157.784216 -61.786259)
			(xy 157.707173 -61.751075) (xy 157.633823 -61.708726) (xy 157.564831 -61.659597) (xy 157.500821 -61.604132)
			(xy 157.442373 -61.542834) (xy 157.390017 -61.476258) (xy 157.344227 -61.405006) (xy 157.305416 -61.329725)
			(xy 157.273937 -61.251095) (xy 157.250076 -61.169828) (xy 157.234047 -61.086662) (xy 157.225996 -61.002348)
			(xy 147.828004 -61.002348) (xy 147.819953 -61.086662) (xy 147.803924 -61.169828) (xy 147.780063 -61.251095)
			(xy 147.748584 -61.329725) (xy 147.709773 -61.405006) (xy 147.663983 -61.476258) (xy 147.611627 -61.542834)
			(xy 147.553179 -61.604132) (xy 147.489169 -61.659597) (xy 147.420177 -61.708726) (xy 147.346827 -61.751075)
			(xy 147.269784 -61.786259) (xy 147.189745 -61.813961) (xy 147.107436 -61.833929) (xy 147.023601 -61.845982)
			(xy 146.939 -61.850013) (xy 146.854399 -61.845982) (xy 146.770564 -61.833929) (xy 146.688255 -61.813961)
			(xy 146.608216 -61.786259) (xy 146.531173 -61.751075) (xy 146.457823 -61.708726) (xy 146.388831 -61.659597)
			(xy 146.324821 -61.604132) (xy 146.266373 -61.542834) (xy 146.214017 -61.476258) (xy 146.168227 -61.405006)
			(xy 146.129416 -61.329725) (xy 146.097937 -61.251095) (xy 146.074076 -61.169828) (xy 146.058047 -61.086662)
			(xy 146.049996 -61.002348) (xy 141.935687 -61.002348) (xy 141.911031 -61.065937) (xy 141.87431 -61.139603)
			(xy 141.83094 -61.209562) (xy 141.781291 -61.275214) (xy 141.725789 -61.335998) (xy 141.664907 -61.391393)
			(xy 141.599168 -61.440926) (xy 141.529133 -61.484173) (xy 141.455402 -61.520764) (xy 141.378605 -61.550386)
			(xy 141.299399 -61.572785) (xy 141.218463 -61.58777) (xy 141.177518 -61.591952) (xy 141.16685 -61.592968)
			(xy 141.148562 -61.602874) (xy 141.096492 -61.66993) (xy 141.093388 -61.674187) (xy 141.088772 -61.683654)
			(xy 141.087348 -61.688726) (xy 141.084808 -61.698632) (xy 141.086332 -61.709046) (xy 141.086332 -61.7093)
			(xy 141.091551 -61.743989) (xy 141.097142 -61.813922) (xy 141.097508 -61.849) (xy 141.096948 -61.892793)
			(xy 141.088318 -61.979954) (xy 141.071172 -62.065846) (xy 141.045675 -62.14964) (xy 141.012074 -62.230525)
			(xy 140.991844 -62.26937) (xy 140.986423 -62.280836) (xy 140.986423 -62.306164) (xy 140.991844 -62.31763)
			(xy 141.012083 -62.356472) (xy 141.045719 -62.437348) (xy 141.071232 -62.521141) (xy 141.088377 -62.607037)
			(xy 141.096987 -62.694204) (xy 141.097508 -62.738) (xy 141.097004 -62.780348) (xy 141.088953 -62.864662)
			(xy 141.072924 -62.947828) (xy 141.049063 -63.029095) (xy 141.017584 -63.107725) (xy 140.978773 -63.183006)
			(xy 140.932983 -63.254258) (xy 140.880627 -63.320834) (xy 140.822179 -63.382132) (xy 140.758169 -63.437597)
			(xy 140.689177 -63.486726) (xy 140.615827 -63.529075) (xy 140.538784 -63.564259) (xy 140.458745 -63.591961)
			(xy 140.376436 -63.611929) (xy 140.292601 -63.623982) (xy 140.208 -63.628013) (xy 140.123399 -63.623982)
			(xy 140.039564 -63.611929) (xy 139.957255 -63.591961) (xy 139.877216 -63.564259) (xy 139.800173 -63.529075)
			(xy 139.726823 -63.486726) (xy 139.657831 -63.437597) (xy 139.593821 -63.382132) (xy 139.535373 -63.320834)
			(xy 139.483017 -63.254258) (xy 139.437227 -63.183006) (xy 139.398416 -63.107725) (xy 139.366937 -63.029095)
			(xy 139.343076 -62.947828) (xy 139.327047 -62.864662) (xy 139.318996 -62.780348) (xy 139.318492 -62.738)
			(xy 102.108508 -62.738) (xy 102.108004 -62.780348) (xy 102.099953 -62.864662) (xy 102.083924 -62.947828)
			(xy 102.060063 -63.029095) (xy 102.028584 -63.107725) (xy 101.989773 -63.183006) (xy 101.943983 -63.254258)
			(xy 101.891627 -63.320834) (xy 101.833179 -63.382132) (xy 101.769169 -63.437597) (xy 101.700177 -63.486726)
			(xy 101.626827 -63.529075) (xy 101.549784 -63.564259) (xy 101.469745 -63.591961) (xy 101.387436 -63.611929)
			(xy 101.303601 -63.623982) (xy 101.219 -63.628013) (xy 101.134399 -63.623982) (xy 101.050564 -63.611929)
			(xy 100.968255 -63.591961) (xy 100.888216 -63.564259) (xy 100.811173 -63.529075) (xy 100.737823 -63.486726)
			(xy 100.668831 -63.437597) (xy 100.604821 -63.382132) (xy 100.546373 -63.320834) (xy 100.494017 -63.254258)
			(xy 100.448227 -63.183006) (xy 100.409416 -63.107725) (xy 100.377937 -63.029095) (xy 100.354076 -62.947828)
			(xy 100.338047 -62.864662) (xy 100.329996 -62.780348) (xy 100.329492 -62.738) (xy 62.475755 -62.738)
			(xy 62.476292 -62.740844) (xy 62.484028 -62.823494) (xy 62.484508 -62.865) (xy 62.484004 -62.907348)
			(xy 62.475953 -62.991662) (xy 62.459924 -63.074828) (xy 62.436063 -63.156095) (xy 62.404584 -63.234725)
			(xy 62.365773 -63.310006) (xy 62.319983 -63.381258) (xy 62.267627 -63.447834) (xy 62.209179 -63.509132)
			(xy 62.145169 -63.564597) (xy 62.076177 -63.613726) (xy 62.002827 -63.656075) (xy 61.925784 -63.691259)
			(xy 61.845745 -63.718961) (xy 61.763436 -63.738929) (xy 61.679601 -63.750982) (xy 61.595 -63.755013)
			(xy 61.510399 -63.750982) (xy 61.426564 -63.738929) (xy 61.344255 -63.718961) (xy 61.264216 -63.691259)
			(xy 61.187173 -63.656075) (xy 61.113823 -63.613726) (xy 61.044831 -63.564597) (xy 60.980821 -63.509132)
			(xy 60.922373 -63.447834) (xy 60.870017 -63.381258) (xy 60.824227 -63.310006) (xy 60.785416 -63.234725)
			(xy 60.753937 -63.156095) (xy 60.730076 -63.074828) (xy 60.714047 -62.991662) (xy 60.705996 -62.907348)
			(xy 60.705492 -62.865) (xy 51.894284 -62.865) (xy 51.876327 -62.884699) (xy 51.81558 -62.94008) (xy 51.749982 -62.98962)
			(xy 51.680093 -63.032896) (xy 51.60651 -63.069539) (xy 51.529859 -63.099237) (xy 51.450795 -63.121736)
			(xy 51.369993 -63.136843) (xy 51.288141 -63.144432) (xy 51.24704 -63.144908) (xy 51.246532 -63.144908)
			(xy 51.200201 -63.144288) (xy 51.108043 -63.134621) (xy 51.017389 -63.115429) (xy 50.92922 -63.086921)
			(xy 50.886614 -63.068708) (xy 50.876672 -63.064902) (xy 50.855408 -63.064902) (xy 50.845466 -63.068708)
			(xy 50.802828 -63.086928) (xy 50.7146 -63.115462) (xy 50.623882 -63.134659) (xy 50.531658 -63.144309)
			(xy 50.485294 -63.144908) (xy 50.48504 -63.144908) (xy 50.484786 -63.144908) (xy 50.438423 -63.144299)
			(xy 50.3462 -63.134645) (xy 50.255481 -63.115454) (xy 50.167249 -63.086933) (xy 50.124614 -63.068708)
			(xy 50.114672 -63.064902) (xy 50.093408 -63.064902) (xy 50.083466 -63.068708) (xy 50.040828 -63.086928)
			(xy 49.9526 -63.115462) (xy 49.861882 -63.134659) (xy 49.769658 -63.144309) (xy 49.723294 -63.144908)
			(xy 49.72304 -63.144908) (xy 49.722786 -63.144908) (xy 49.676423 -63.144299) (xy 49.5842 -63.134645)
			(xy 49.493481 -63.115454) (xy 49.405249 -63.086933) (xy 49.362614 -63.068708) (xy 49.352672 -63.064902)
			(xy 49.331408 -63.064902) (xy 49.321466 -63.068708) (xy 49.278828 -63.086928) (xy 49.1906 -63.115462)
			(xy 49.099882 -63.134659) (xy 49.007658 -63.144309) (xy 48.961294 -63.144908) (xy 48.96104 -63.144908)
			(xy 48.960786 -63.144908) (xy 48.914423 -63.144299) (xy 48.8222 -63.134645) (xy 48.731481 -63.115454)
			(xy 48.643249 -63.086933) (xy 48.600614 -63.068708) (xy 48.590672 -63.064902) (xy 48.569408 -63.064902)
			(xy 48.559466 -63.068708) (xy 48.516858 -63.086917) (xy 48.428692 -63.115438) (xy 48.338038 -63.134634)
			(xy 48.24588 -63.144298) (xy 48.199548 -63.144908) (xy 48.19904 -63.144908) (xy 48.157937 -63.14441)
			(xy 48.076083 -63.136828) (xy 47.995277 -63.121726) (xy 47.916209 -63.099233) (xy 47.839554 -63.06954)
			(xy 47.765966 -63.0329) (xy 47.696073 -62.989627) (xy 47.630471 -62.940089) (xy 47.569719 -62.884709)
			(xy 47.514337 -62.82396) (xy 47.464796 -62.75836) (xy 47.42152 -62.688469) (xy 47.384877 -62.614882)
			(xy 47.35518 -62.538229) (xy 47.332683 -62.459162) (xy 47.317577 -62.378357) (xy 47.309992 -62.296502)
			(xy 47.309532 -62.2554) (xy 44.5516 -62.2554) (xy 44.5516 -67.114674) (xy 44.552037 -67.124738) (xy 44.55977 -67.143323)
			(xy 44.566586 -67.150742) (xy 44.943014 -67.52717) (xy 44.950412 -67.534017) (xy 44.96901 -67.541752)
			(xy 44.979082 -67.542156) (xy 49.557686 -67.542156) (xy 49.558448 -67.542156) (xy 49.569266 -67.541496)
			(xy 49.588866 -67.532291) (xy 49.602938 -67.515833) (xy 49.606454 -67.50558) (xy 49.621593 -67.455747)
			(xy 49.658802 -67.358462) (xy 49.703701 -67.264478) (xy 49.755998 -67.174401) (xy 49.815358 -67.088812)
			(xy 49.881396 -67.008265) (xy 49.953687 -66.933278) (xy 50.031763 -66.864336) (xy 50.115122 -66.801884)
			(xy 50.203225 -66.746325) (xy 50.295503 -66.698018) (xy 50.391362 -66.657273) (xy 50.490181 -66.624355)
			(xy 50.591324 -66.599475) (xy 50.694138 -66.582794) (xy 50.797959 -66.57442) (xy 50.850038 -66.573908)
			(xy 50.901717 -66.574414) (xy 51.004747 -66.582649) (xy 51.106794 -66.599063) (xy 51.20721 -66.623553)
			(xy 51.305356 -66.655963) (xy 51.400609 -66.696086) (xy 51.492363 -66.743669) (xy 51.580037 -66.798408)
			(xy 51.663072 -66.859956) (xy 51.740942 -66.927922) (xy 51.777392 -66.96456) (xy 51.784758 -66.971926)
			(xy 51.8033 -66.9798) (xy 51.896772 -66.9798) (xy 51.915314 -66.971926) (xy 51.92268 -66.96456) (xy 51.959141 -66.927931)
			(xy 52.037004 -66.859955) (xy 52.120034 -66.798397) (xy 52.207705 -66.74365) (xy 52.299458 -66.69606)
			(xy 52.39471 -66.655931) (xy 52.492857 -66.623517) (xy 52.593273 -66.599025) (xy 52.695322 -66.582609)
			(xy 52.798354 -66.574376) (xy 52.901714 -66.574376) (xy 53.004746 -66.582609) (xy 53.106795 -66.599025)
			(xy 53.207211 -66.623517) (xy 53.305358 -66.655931) (xy 53.40061 -66.69606) (xy 53.492363 -66.74365)
			(xy 53.580034 -66.798397) (xy 53.663064 -66.859955) (xy 53.740927 -66.927931) (xy 53.777388 -66.96456)
			(xy 53.784754 -66.971926) (xy 53.803296 -66.9798) (xy 53.896768 -66.9798) (xy 53.91531 -66.971926)
			(xy 53.922676 -66.96456) (xy 53.959137 -66.927931) (xy 54.037 -66.859955) (xy 54.12003 -66.798397)
			(xy 54.207701 -66.74365) (xy 54.299454 -66.69606) (xy 54.394706 -66.655931) (xy 54.492853 -66.623517)
			(xy 54.593269 -66.599025) (xy 54.695318 -66.582609) (xy 54.79835 -66.574376) (xy 54.90171 -66.574376)
			(xy 55.004742 -66.582609) (xy 55.106791 -66.599025) (xy 55.207207 -66.623517) (xy 55.305354 -66.655931)
			(xy 55.400606 -66.69606) (xy 55.492359 -66.74365) (xy 55.58003 -66.798397) (xy 55.66306 -66.859955)
			(xy 55.740923 -66.927931) (xy 55.777384 -66.96456) (xy 55.78475 -66.971926) (xy 55.803292 -66.9798)
			(xy 55.896764 -66.9798) (xy 55.915306 -66.971926) (xy 55.922672 -66.96456) (xy 55.959133 -66.927931)
			(xy 56.036996 -66.859955) (xy 56.120026 -66.798397) (xy 56.207697 -66.74365) (xy 56.29945 -66.69606)
			(xy 56.394702 -66.655931) (xy 56.492849 -66.623517) (xy 56.593265 -66.599025) (xy 56.695314 -66.582609)
			(xy 56.798346 -66.574376) (xy 56.901706 -66.574376) (xy 57.004738 -66.582609) (xy 57.106787 -66.599025)
			(xy 57.207203 -66.623517) (xy 57.30535 -66.655931) (xy 57.400602 -66.69606) (xy 57.492355 -66.74365)
			(xy 57.580026 -66.798397) (xy 57.663056 -66.859955) (xy 57.740919 -66.927931) (xy 57.77738 -66.96456)
			(xy 57.784746 -66.971926) (xy 57.803288 -66.9798) (xy 57.89676 -66.9798) (xy 57.915302 -66.971926)
			(xy 57.922668 -66.96456) (xy 57.959129 -66.927931) (xy 58.036992 -66.859955) (xy 58.120022 -66.798397)
			(xy 58.207693 -66.74365) (xy 58.299446 -66.69606) (xy 58.394698 -66.655931) (xy 58.492845 -66.623517)
			(xy 58.593261 -66.599025) (xy 58.69531 -66.582609) (xy 58.798342 -66.574376) (xy 58.901702 -66.574376)
			(xy 59.004734 -66.582609) (xy 59.106783 -66.599025) (xy 59.207199 -66.623517) (xy 59.305346 -66.655931)
			(xy 59.400598 -66.69606) (xy 59.492351 -66.74365) (xy 59.580022 -66.798397) (xy 59.663052 -66.859955)
			(xy 59.740915 -66.927931) (xy 59.777376 -66.96456) (xy 59.784742 -66.971926) (xy 59.803284 -66.9798)
			(xy 59.896756 -66.9798) (xy 59.915298 -66.971926) (xy 59.922664 -66.96456) (xy 59.959125 -66.927931)
			(xy 60.036988 -66.859955) (xy 60.120018 -66.798397) (xy 60.207689 -66.74365) (xy 60.299442 -66.69606)
			(xy 60.394694 -66.655931) (xy 60.492841 -66.623517) (xy 60.593257 -66.599025) (xy 60.695306 -66.582609)
			(xy 60.798338 -66.574376) (xy 60.901698 -66.574376) (xy 61.00473 -66.582609) (xy 61.106779 -66.599025)
			(xy 61.207195 -66.623517) (xy 61.305342 -66.655931) (xy 61.400594 -66.69606) (xy 61.492347 -66.74365)
			(xy 61.580018 -66.798397) (xy 61.663048 -66.859955) (xy 61.740911 -66.927931) (xy 61.777372 -66.96456)
			(xy 61.784738 -66.971926) (xy 61.80328 -66.9798) (xy 61.896752 -66.9798) (xy 61.915294 -66.971926)
			(xy 61.92266 -66.96456) (xy 61.959119 -66.927929) (xy 62.036979 -66.859949) (xy 62.120008 -66.798389)
			(xy 62.207678 -66.74364) (xy 62.299432 -66.69605) (xy 62.394685 -66.655922) (xy 62.492833 -66.623511)
			(xy 62.593251 -66.599023) (xy 62.695301 -66.582614) (xy 62.798334 -66.574387) (xy 62.850014 -66.573908)
			(xy 62.900244 -66.574394) (xy 63.000403 -66.582174) (xy 63.099658 -66.597685) (xy 63.197415 -66.620836)
			(xy 63.293085 -66.651485) (xy 63.386096 -66.689451) (xy 63.475887 -66.734504) (xy 63.56192 -66.786374)
			(xy 63.643679 -66.84475) (xy 63.720673 -66.909281) (xy 63.792438 -66.97958) (xy 63.858545 -67.055225)
			(xy 63.918597 -67.135761) (xy 63.972232 -67.220706) (xy 64.01913 -67.309548) (xy 64.039496 -67.355466)
			(xy 64.052704 -67.3862) (xy 64.057276 -67.3862) (xy 64.057276 -67.693794) (xy 64.056853 -67.703864)
			(xy 64.049138 -67.722468) (xy 64.04229 -67.729862) (xy 63.909702 -67.862196) (xy 63.902082 -67.879976)
			(xy 63.901828 -67.890136) (xy 63.900503 -67.934587) (xy 63.891283 -68.023044) (xy 63.874628 -68.110406)
			(xy 63.850657 -68.196051) (xy 63.819541 -68.279366) (xy 63.781502 -68.359757) (xy 63.736812 -68.43665)
			(xy 63.68579 -68.509495) (xy 63.6288 -68.577772) (xy 63.56625 -68.640994) (xy 63.498585 -68.69871)
			(xy 63.426289 -68.750507) (xy 63.349878 -68.796016) (xy 63.269899 -68.834911) (xy 63.18692 -68.866915)
			(xy 63.101537 -68.8918) (xy 63.05804 -68.901056) (xy 63.0174 -68.909184) (xy 63.0174 -68.9102) (xy 63.006478 -68.9102)
			(xy 63.002922 -68.910708) (xy 62.964912 -68.91594) (xy 62.888381 -68.921535) (xy 62.850014 -68.921884)
			(xy 62.811647 -68.921535) (xy 62.735116 -68.915942) (xy 62.697106 -68.910708) (xy 62.69355 -68.9102)
			(xy 62.327282 -68.9102) (xy 62.317213 -68.910627) (xy 62.298614 -68.918346) (xy 62.291214 -68.925186)
			(xy 61.559186 -69.657214) (xy 61.552332 -69.664609) (xy 61.54459 -69.683208) (xy 61.5442 -69.693282)
			(xy 61.5442 -70.409816) (xy 62.779915 -70.409816) (xy 62.783942 -70.293213) (xy 62.796004 -70.177166)
			(xy 62.816043 -70.062228) (xy 62.843965 -69.948946) (xy 62.879635 -69.83786) (xy 62.922884 -69.7295)
			(xy 62.973507 -69.624382) (xy 63.03126 -69.523007) (xy 63.095871 -69.425858) (xy 63.167029 -69.333398)
			(xy 63.244397 -69.246067) (xy 63.327606 -69.164283) (xy 63.416259 -69.088434) (xy 63.509933 -69.018882)
			(xy 63.608183 -68.955958) (xy 63.71054 -68.899962) (xy 63.816516 -68.851162) (xy 63.925607 -68.80979)
			(xy 64.037291 -68.776042) (xy 64.151038 -68.75008) (xy 64.266306 -68.732027) (xy 64.382544 -68.72197)
			(xy 64.499198 -68.719956) (xy 64.615714 -68.725995) (xy 64.731536 -68.740059) (xy 64.846111 -68.762079)
			(xy 64.958894 -68.791952) (xy 65.069348 -68.829534) (xy 65.176945 -68.874648) (xy 65.281174 -68.927077)
			(xy 65.381537 -68.986572) (xy 65.477556 -69.052849) (xy 65.568774 -69.125593) (xy 65.654756 -69.204457)
			(xy 65.735093 -69.289065) (xy 65.8094 -69.379014) (xy 65.877325 -69.473875) (xy 65.938544 -69.573196)
			(xy 65.992764 -69.676504) (xy 66.039728 -69.783307) (xy 66.079211 -69.893095) (xy 66.111026 -70.005346)
			(xy 66.135021 -70.119524) (xy 66.151081 -70.235086) (xy 66.15913 -70.35148) (xy 66.159634 -70.409816)
			(xy 66.589915 -70.409816) (xy 66.593942 -70.293213) (xy 66.606004 -70.177166) (xy 66.626043 -70.062228)
			(xy 66.653965 -69.948946) (xy 66.689635 -69.83786) (xy 66.732884 -69.7295) (xy 66.783507 -69.624382)
			(xy 66.84126 -69.523007) (xy 66.905871 -69.425858) (xy 66.977029 -69.333398) (xy 67.054397 -69.246067)
			(xy 67.137606 -69.164283) (xy 67.226259 -69.088434) (xy 67.319933 -69.018882) (xy 67.418183 -68.955958)
			(xy 67.52054 -68.899962) (xy 67.626516 -68.851162) (xy 67.735607 -68.80979) (xy 67.847291 -68.776042)
			(xy 67.961038 -68.75008) (xy 68.076306 -68.732027) (xy 68.192544 -68.72197) (xy 68.309198 -68.719956)
			(xy 68.425714 -68.725995) (xy 68.541536 -68.740059) (xy 68.656111 -68.762079) (xy 68.768894 -68.791952)
			(xy 68.879348 -68.829534) (xy 68.986945 -68.874648) (xy 69.091174 -68.927077) (xy 69.191537 -68.986572)
			(xy 69.287556 -69.052849) (xy 69.378774 -69.125593) (xy 69.464756 -69.204457) (xy 69.545093 -69.289065)
			(xy 69.6194 -69.379014) (xy 69.687325 -69.473875) (xy 69.748544 -69.573196) (xy 69.802764 -69.676504)
			(xy 69.849728 -69.783307) (xy 69.889211 -69.893095) (xy 69.921026 -70.005346) (xy 69.945021 -70.119524)
			(xy 69.961081 -70.235086) (xy 69.96913 -70.35148) (xy 69.969634 -70.409816) (xy 69.96913 -70.468152)
			(xy 69.961081 -70.584546) (xy 69.945021 -70.700108) (xy 69.921026 -70.814286) (xy 69.889211 -70.926537)
			(xy 69.849728 -71.036325) (xy 69.802764 -71.143128) (xy 69.748544 -71.246436) (xy 69.687325 -71.345757)
			(xy 69.6194 -71.440618) (xy 69.545093 -71.530567) (xy 69.464756 -71.615175) (xy 69.378774 -71.694039)
			(xy 69.287556 -71.766783) (xy 69.191537 -71.83306) (xy 69.091174 -71.892555) (xy 68.986945 -71.944984)
			(xy 68.879348 -71.990098) (xy 68.768894 -72.02768) (xy 68.656111 -72.057553) (xy 68.541536 -72.079573)
			(xy 68.425714 -72.093637) (xy 68.309198 -72.099676) (xy 68.192544 -72.097662) (xy 68.076306 -72.087605)
			(xy 67.961038 -72.069552) (xy 67.847291 -72.04359) (xy 67.735607 -72.009842) (xy 67.626516 -71.96847)
			(xy 67.52054 -71.91967) (xy 67.418183 -71.863674) (xy 67.319933 -71.80075) (xy 67.226259 -71.731198)
			(xy 67.137606 -71.655349) (xy 67.054397 -71.573565) (xy 66.977029 -71.486234) (xy 66.905871 -71.393774)
			(xy 66.84126 -71.296625) (xy 66.783507 -71.19525) (xy 66.732884 -71.090132) (xy 66.689635 -70.981772)
			(xy 66.653965 -70.870686) (xy 66.626043 -70.757404) (xy 66.606004 -70.642466) (xy 66.593942 -70.526419)
			(xy 66.589915 -70.409816) (xy 66.159634 -70.409816) (xy 66.15913 -70.468152) (xy 66.151081 -70.584546)
			(xy 66.135021 -70.700108) (xy 66.111026 -70.814286) (xy 66.079211 -70.926537) (xy 66.039728 -71.036325)
			(xy 65.992764 -71.143128) (xy 65.938544 -71.246436) (xy 65.877325 -71.345757) (xy 65.8094 -71.440618)
			(xy 65.735093 -71.530567) (xy 65.654756 -71.615175) (xy 65.568774 -71.694039) (xy 65.477556 -71.766783)
			(xy 65.381537 -71.83306) (xy 65.281174 -71.892555) (xy 65.176945 -71.944984) (xy 65.069348 -71.990098)
			(xy 64.958894 -72.02768) (xy 64.846111 -72.057553) (xy 64.731536 -72.079573) (xy 64.615714 -72.093637)
			(xy 64.499198 -72.099676) (xy 64.382544 -72.097662) (xy 64.266306 -72.087605) (xy 64.151038 -72.069552)
			(xy 64.037291 -72.04359) (xy 63.925607 -72.009842) (xy 63.816516 -71.96847) (xy 63.71054 -71.91967)
			(xy 63.608183 -71.863674) (xy 63.509933 -71.80075) (xy 63.416259 -71.731198) (xy 63.327606 -71.655349)
			(xy 63.244397 -71.573565) (xy 63.167029 -71.486234) (xy 63.095871 -71.393774) (xy 63.03126 -71.296625)
			(xy 62.973507 -71.19525) (xy 62.922884 -71.090132) (xy 62.879635 -70.981772) (xy 62.843965 -70.870686)
			(xy 62.816043 -70.757404) (xy 62.796004 -70.642466) (xy 62.783942 -70.526419) (xy 62.779915 -70.409816)
			(xy 61.5442 -70.409816) (xy 61.5442 -72.705722) (xy 61.544627 -72.71579) (xy 61.552347 -72.734389)
			(xy 61.559186 -72.74179) (xy 61.986414 -73.169018) (xy 61.993809 -73.175871) (xy 62.012408 -73.183613)
			(xy 62.022482 -73.184004)
		)
		(stroke
			(width 0)
			(type solid)
		)
		(fill yes)
		(layer "In2.Cu")
		(net "P12V_BRICK")
	)
	(gr_poly
		(pts
			(xy 322.804282 -145.569686) (xy 322.811888 -145.568173) (xy 322.825724 -145.561189) (xy 322.83146 -145.55597)
			(xy 326.502014 -141.885416) (xy 326.508857 -141.878017) (xy 326.516574 -141.859418) (xy 326.517 -141.849348)
			(xy 326.517 -4.836922) (xy 326.50938 -4.818126) (xy 326.502014 -4.811014) (xy 323.232272 -1.541272)
			(xy 323.224875 -1.534422) (xy 323.206277 -1.526687) (xy 323.196204 -1.526286) (xy 166.261796 -1.526286)
			(xy 166.251726 -1.526709) (xy 166.233121 -1.534423) (xy 166.225728 -1.541272) (xy 165.318186 -2.448814)
			(xy 165.31082 -2.455926) (xy 165.3032 -2.474722) (xy 165.3032 -4.36987) (xy 242.877075 -4.36987)
			(xy 242.877075 -4.24073) (xy 242.885025 -4.111835) (xy 242.900895 -3.983675) (xy 242.924624 -3.856734)
			(xy 242.956123 -3.731495) (xy 242.995272 -3.608432) (xy 243.041923 -3.488013) (xy 243.095898 -3.370694)
			(xy 243.156993 -3.25692) (xy 243.224976 -3.147123) (xy 243.29959 -3.04172) (xy 243.380551 -2.94111)
			(xy 243.467551 -2.845675) (xy 243.560262 -2.755776) (xy 243.658332 -2.671755) (xy 243.761387 -2.593931)
			(xy 243.869038 -2.522599) (xy 243.980877 -2.458029) (xy 244.096478 -2.400467) (xy 244.215403 -2.35013)
			(xy 244.337202 -2.30721) (xy 244.461412 -2.271869) (xy 244.587561 -2.244242) (xy 244.715173 -2.224433)
			(xy 244.843762 -2.212517) (xy 244.97284 -2.208541) (xy 245.101918 -2.212517) (xy 245.230507 -2.224433)
			(xy 245.358119 -2.244242) (xy 245.484268 -2.271869) (xy 245.608478 -2.30721) (xy 245.730277 -2.35013)
			(xy 245.849202 -2.400467) (xy 245.964803 -2.458029) (xy 246.076642 -2.522599) (xy 246.184293 -2.593931)
			(xy 246.287348 -2.671755) (xy 246.385418 -2.755776) (xy 246.478129 -2.845675) (xy 246.565129 -2.94111)
			(xy 246.64609 -3.04172) (xy 246.720704 -3.147123) (xy 246.788687 -3.25692) (xy 246.849782 -3.370694)
			(xy 246.903757 -3.488013) (xy 246.950408 -3.608432) (xy 246.989557 -3.731495) (xy 247.021056 -3.856734)
			(xy 247.044785 -3.983675) (xy 247.060655 -4.111835) (xy 247.068605 -4.24073) (xy 247.069102 -4.3053)
			(xy 247.068605 -4.36987) (xy 247.060655 -4.498765) (xy 247.044785 -4.626925) (xy 247.021056 -4.753866)
			(xy 246.989557 -4.879105) (xy 246.950408 -5.002168) (xy 246.903757 -5.122587) (xy 246.849782 -5.239906)
			(xy 246.788687 -5.35368) (xy 246.720704 -5.463477) (xy 246.64609 -5.56888) (xy 246.565129 -5.66949)
			(xy 246.478129 -5.764925) (xy 246.385418 -5.854824) (xy 246.287348 -5.938845) (xy 246.184293 -6.016669)
			(xy 246.076642 -6.088001) (xy 245.964803 -6.152571) (xy 245.849202 -6.210133) (xy 245.730277 -6.26047)
			(xy 245.608478 -6.30339) (xy 245.484268 -6.338731) (xy 245.358119 -6.366358) (xy 245.230507 -6.386167)
			(xy 245.101918 -6.398083) (xy 244.97284 -6.40206) (xy 244.843762 -6.398083) (xy 244.715173 -6.386167)
			(xy 244.587561 -6.366358) (xy 244.461412 -6.338731) (xy 244.337202 -6.30339) (xy 244.215403 -6.26047)
			(xy 244.096478 -6.210133) (xy 243.980877 -6.152571) (xy 243.869038 -6.088001) (xy 243.761387 -6.016669)
			(xy 243.658332 -5.938845) (xy 243.560262 -5.854824) (xy 243.467551 -5.764925) (xy 243.380551 -5.66949)
			(xy 243.29959 -5.56888) (xy 243.224976 -5.463477) (xy 243.156993 -5.35368) (xy 243.095898 -5.239906)
			(xy 243.041923 -5.122587) (xy 242.995272 -5.002168) (xy 242.956123 -4.879105) (xy 242.924624 -4.753866)
			(xy 242.900895 -4.626925) (xy 242.885025 -4.498765) (xy 242.877075 -4.36987) (xy 165.3032 -4.36987)
			(xy 165.3032 -7.493) (xy 176.001932 -7.493) (xy 176.006003 -7.437378) (xy 176.018129 -7.382941) (xy 176.038052 -7.33085)
			(xy 176.065348 -7.282215) (xy 176.099434 -7.238072) (xy 176.139583 -7.199363) (xy 176.184941 -7.166912)
			(xy 176.234541 -7.141411) (xy 176.287325 -7.123404) (xy 176.342168 -7.113274) (xy 176.397902 -7.111237)
			(xy 176.453339 -7.117337) (xy 176.507296 -7.131443) (xy 176.558625 -7.153255) (xy 176.606231 -7.182309)
			(xy 176.649099 -7.217984) (xy 176.686316 -7.259521) (xy 176.717089 -7.306034) (xy 176.740761 -7.356531)
			(xy 176.756829 -7.409938) (xy 176.764949 -7.465114) (xy 176.765458 -7.493) (xy 176.764949 -7.520886)
			(xy 176.756829 -7.576062) (xy 176.74361 -7.62) (xy 188.889132 -7.62) (xy 188.889637 -7.577094) (xy 188.89791 -7.491682)
			(xy 188.914369 -7.407463) (xy 188.938862 -7.32522) (xy 188.97116 -7.245718) (xy 189.010964 -7.169696)
			(xy 189.057903 -7.09786) (xy 189.111542 -7.030878) (xy 189.171381 -6.969372) (xy 189.236865 -6.913915)
			(xy 189.307385 -6.865021) (xy 189.382286 -6.823144) (xy 189.460871 -6.788675) (xy 189.54241 -6.761934)
			(xy 189.626145 -6.743168) (xy 189.668658 -6.73735) (xy 189.668912 -6.73735) (xy 189.676423 -6.736127)
			(xy 189.69025 -6.729783) (xy 189.69609 -6.724904) (xy 189.696344 -6.72465) (xy 189.701861 -6.719381)
			(xy 189.709754 -6.706334) (xy 189.711838 -6.698996) (xy 189.711838 -6.698742) (xy 189.722336 -6.657725)
			(xy 189.750059 -6.577721) (xy 189.785259 -6.500713) (xy 189.827618 -6.427398) (xy 189.876752 -6.358441)
			(xy 189.932217 -6.294465) (xy 189.99351 -6.236049) (xy 190.060077 -6.183721) (xy 190.131315 -6.137957)
			(xy 190.20658 -6.099169) (xy 190.28519 -6.067708) (xy 190.366433 -6.043861) (xy 190.449576 -6.027841)
			(xy 190.533864 -6.019795) (xy 190.5762 -6.019292) (xy 190.618559 -6.019838) (xy 190.702893 -6.027909)
			(xy 190.786078 -6.043958) (xy 190.867361 -6.067841) (xy 190.946006 -6.099341) (xy 191.021301 -6.138173)
			(xy 191.092565 -6.183985) (xy 191.159152 -6.236363) (xy 191.22046 -6.294832) (xy 191.275933 -6.358864)
			(xy 191.325069 -6.427878) (xy 191.367424 -6.501249) (xy 191.402614 -6.578314) (xy 191.43032 -6.658374)
			(xy 191.450291 -6.740705) (xy 191.456818 -6.782562) (xy 191.458444 -6.791251) (xy 191.466704 -6.806863)
			(xy 191.479781 -6.818734) (xy 191.487806 -6.82244) (xy 191.52812 -6.839574) (xy 191.605508 -6.88062)
			(xy 191.678487 -6.929075) (xy 191.746349 -6.98447) (xy 191.808436 -7.046268) (xy 191.864148 -7.11387)
			(xy 191.912944 -7.186622) (xy 191.954351 -7.263818) (xy 191.987969 -7.344711) (xy 192.013471 -7.428517)
			(xy 192.030611 -7.514424) (xy 192.039223 -7.6016) (xy 192.039748 -7.6454) (xy 192.039233 -7.686501)
			(xy 192.031649 -7.768353) (xy 192.016545 -7.849156) (xy 191.994049 -7.928221) (xy 191.964355 -8.004873)
			(xy 191.927715 -8.078458) (xy 191.884442 -8.148349) (xy 191.834905 -8.213949) (xy 191.779527 -8.274699)
			(xy 191.71878 -8.33008) (xy 191.653182 -8.37962) (xy 191.583293 -8.422896) (xy 191.50971 -8.459539)
			(xy 191.433059 -8.489237) (xy 191.353995 -8.511736) (xy 191.273193 -8.526843) (xy 191.191341 -8.534432)
			(xy 191.15024 -8.534908) (xy 191.107122 -8.534391) (xy 191.021289 -8.526046) (xy 190.936668 -8.509431)
			(xy 190.854053 -8.484702) (xy 190.813944 -8.468868) (xy 190.804575 -8.465531) (xy 190.784705 -8.465531)
			(xy 190.775336 -8.468868) (xy 190.735223 -8.484692) (xy 190.652609 -8.509425) (xy 190.56799 -8.526046)
			(xy 190.482158 -8.534397) (xy 190.43904 -8.534908) (xy 190.438786 -8.534908) (xy 190.394696 -8.534335)
			(xy 190.306956 -8.525529) (xy 190.220519 -8.508075) (xy 190.136237 -8.482144) (xy 190.095378 -8.465566)
			(xy 190.09233 -8.464296) (xy 190.084317 -8.461859) (xy 190.067577 -8.461859) (xy 190.059564 -8.464296)
			(xy 190.014317 -8.478669) (xy 189.92153 -8.498789) (xy 189.827127 -8.5089) (xy 189.779656 -8.509508)
			(xy 189.77864 -8.509508) (xy 189.737537 -8.50901) (xy 189.655683 -8.501428) (xy 189.574877 -8.486326)
			(xy 189.495809 -8.463833) (xy 189.419154 -8.43414) (xy 189.345566 -8.3975) (xy 189.275673 -8.354227)
			(xy 189.210071 -8.304689) (xy 189.149319 -8.249309) (xy 189.093937 -8.18856) (xy 189.044396 -8.12296)
			(xy 189.00112 -8.053069) (xy 188.964477 -7.979482) (xy 188.93478 -7.902829) (xy 188.912283 -7.823762)
			(xy 188.897177 -7.742957) (xy 188.889592 -7.661102) (xy 188.889132 -7.62) (xy 176.74361 -7.62) (xy 176.740761 -7.629469)
			(xy 176.717089 -7.679966) (xy 176.686316 -7.726479) (xy 176.649099 -7.768016) (xy 176.606231 -7.803691)
			(xy 176.558625 -7.832745) (xy 176.507296 -7.854557) (xy 176.453339 -7.868663) (xy 176.397902 -7.874763)
			(xy 176.342168 -7.872726) (xy 176.287325 -7.862596) (xy 176.234541 -7.844589) (xy 176.184941 -7.819088)
			(xy 176.139583 -7.786637) (xy 176.099434 -7.747928) (xy 176.065348 -7.703785) (xy 176.038052 -7.65515)
			(xy 176.018129 -7.603059) (xy 176.006003 -7.548622) (xy 176.001932 -7.493) (xy 165.3032 -7.493) (xy 165.3032 -8.128)
			(xy 179.195982 -8.128) (xy 179.200053 -8.072378) (xy 179.212179 -8.017941) (xy 179.232102 -7.96585)
			(xy 179.259398 -7.917215) (xy 179.293484 -7.873072) (xy 179.333633 -7.834363) (xy 179.378991 -7.801912)
			(xy 179.428591 -7.776411) (xy 179.481375 -7.758404) (xy 179.536218 -7.748274) (xy 179.591952 -7.746237)
			(xy 179.647389 -7.752337) (xy 179.701346 -7.766443) (xy 179.752675 -7.788255) (xy 179.800281 -7.817309)
			(xy 179.843149 -7.852984) (xy 179.880366 -7.894521) (xy 179.911139 -7.941034) (xy 179.934811 -7.991531)
			(xy 179.950879 -8.044938) (xy 179.958999 -8.100114) (xy 179.959508 -8.128) (xy 179.958999 -8.155886)
			(xy 179.950879 -8.211062) (xy 179.934811 -8.264469) (xy 179.911139 -8.314966) (xy 179.880366 -8.361479)
			(xy 179.843149 -8.403016) (xy 179.800281 -8.438691) (xy 179.752675 -8.467745) (xy 179.701346 -8.489557)
			(xy 179.647389 -8.503663) (xy 179.591952 -8.509763) (xy 179.536218 -8.507726) (xy 179.481375 -8.497596)
			(xy 179.428591 -8.479589) (xy 179.378991 -8.454088) (xy 179.333633 -8.421637) (xy 179.293484 -8.382928)
			(xy 179.259398 -8.338785) (xy 179.232102 -8.29015) (xy 179.212179 -8.238059) (xy 179.200053 -8.183622)
			(xy 179.195982 -8.128) (xy 165.3032 -8.128) (xy 165.3032 -10.033) (xy 174.897032 -10.033) (xy 174.901103 -9.977378)
			(xy 174.913229 -9.922941) (xy 174.933152 -9.87085) (xy 174.960448 -9.822215) (xy 174.994534 -9.778072)
			(xy 175.034683 -9.739363) (xy 175.080041 -9.706912) (xy 175.129641 -9.681411) (xy 175.182425 -9.663404)
			(xy 175.237268 -9.653274) (xy 175.293002 -9.651237) (xy 175.348439 -9.657337) (xy 175.402396 -9.671443)
			(xy 175.453725 -9.693255) (xy 175.501331 -9.722309) (xy 175.544199 -9.757984) (xy 175.563029 -9.779)
			(xy 188.888572 -9.779) (xy 188.892602 -9.694395) (xy 188.904657 -9.610556) (xy 188.924626 -9.528243)
			(xy 188.95233 -9.448201) (xy 188.987517 -9.371155) (xy 189.029869 -9.297802) (xy 189.079001 -9.228808)
			(xy 189.13447 -9.164796) (xy 189.195772 -9.106347) (xy 189.262353 -9.053991) (xy 189.333609 -9.0082)
			(xy 189.408895 -8.96939) (xy 189.48753 -8.937912) (xy 189.568801 -8.914052) (xy 189.651972 -8.898026)
			(xy 189.73629 -8.889978) (xy 189.77864 -8.889492) (xy 189.778894 -8.889492) (xy 189.822984 -8.890072)
			(xy 189.910724 -8.898876) (xy 189.997161 -8.916328) (xy 190.081443 -8.942257) (xy 190.122302 -8.958834)
			(xy 190.12535 -8.960104) (xy 190.133377 -8.962451) (xy 190.150089 -8.962451) (xy 190.158116 -8.960104)
			(xy 190.203365 -8.945736) (xy 190.29615 -8.925614) (xy 190.390553 -8.915501) (xy 190.438024 -8.914892)
			(xy 190.43904 -8.914892) (xy 190.482158 -8.915416) (xy 190.56799 -8.923759) (xy 190.652611 -8.940372)
			(xy 190.735227 -8.965099) (xy 190.775336 -8.980932) (xy 190.784705 -8.984269) (xy 190.804575 -8.984269)
			(xy 190.813944 -8.980932) (xy 190.854048 -8.965083) (xy 190.936665 -8.940356) (xy 191.021287 -8.923743)
			(xy 191.107121 -8.915399) (xy 191.15024 -8.914892) (xy 191.192587 -8.915397) (xy 191.276898 -8.923452)
			(xy 191.360061 -8.939484) (xy 191.441324 -8.963348) (xy 191.519951 -8.994828) (xy 191.595229 -9.03364)
			(xy 191.666478 -9.079431) (xy 191.733051 -9.131788) (xy 191.794346 -9.190235) (xy 191.849808 -9.254244)
			(xy 191.898934 -9.323235) (xy 191.94128 -9.396583) (xy 191.976463 -9.473625) (xy 192.004163 -9.553661)
			(xy 192.02413 -9.635969) (xy 192.036183 -9.719801) (xy 192.040213 -9.8044) (xy 192.036183 -9.888999)
			(xy 192.02413 -9.972831) (xy 192.004163 -10.055139) (xy 191.976463 -10.135175) (xy 191.94128 -10.212217)
			(xy 191.898934 -10.285565) (xy 191.849808 -10.354556) (xy 191.794346 -10.418565) (xy 191.733051 -10.477012)
			(xy 191.666478 -10.529369) (xy 191.595229 -10.57516) (xy 191.519951 -10.613972) (xy 191.441324 -10.645452)
			(xy 191.360061 -10.669316) (xy 191.276898 -10.685348) (xy 191.192587 -10.693403) (xy 191.15024 -10.693908)
			(xy 191.107122 -10.693391) (xy 191.021289 -10.685046) (xy 190.936668 -10.668431) (xy 190.854053 -10.643702)
			(xy 190.813944 -10.627868) (xy 190.804575 -10.624531) (xy 190.784705 -10.624531) (xy 190.775336 -10.627868)
			(xy 190.735223 -10.643692) (xy 190.652609 -10.668425) (xy 190.56799 -10.685046) (xy 190.482158 -10.693397)
			(xy 190.43904 -10.693908) (xy 190.438786 -10.693908) (xy 190.394696 -10.693335) (xy 190.306956 -10.684529)
			(xy 190.220519 -10.667075) (xy 190.136237 -10.641144) (xy 190.095378 -10.624566) (xy 190.09233 -10.623296)
			(xy 190.084317 -10.620859) (xy 190.067577 -10.620859) (xy 190.059564 -10.623296) (xy 190.014317 -10.637669)
			(xy 189.92153 -10.657789) (xy 189.827127 -10.6679) (xy 189.779656 -10.668508) (xy 189.77864 -10.668508)
			(xy 189.73629 -10.668022) (xy 189.651972 -10.659974) (xy 189.568801 -10.643948) (xy 189.48753 -10.620088)
			(xy 189.408895 -10.58861) (xy 189.333609 -10.5498) (xy 189.262353 -10.504009) (xy 189.195772 -10.451653)
			(xy 189.13447 -10.393204) (xy 189.079001 -10.329192) (xy 189.029869 -10.260198) (xy 188.987517 -10.186845)
			(xy 188.95233 -10.109799) (xy 188.924626 -10.029757) (xy 188.904657 -9.947444) (xy 188.892602 -9.863605)
			(xy 188.888572 -9.779) (xy 175.563029 -9.779) (xy 175.581416 -9.799521) (xy 175.612189 -9.846034)
			(xy 175.635861 -9.896531) (xy 175.651929 -9.949938) (xy 175.660049 -10.005114) (xy 175.660558 -10.033)
			(xy 175.660049 -10.060886) (xy 175.651929 -10.116062) (xy 175.635861 -10.169469) (xy 175.612189 -10.219966)
			(xy 175.581416 -10.266479) (xy 175.544199 -10.308016) (xy 175.501331 -10.343691) (xy 175.453725 -10.372745)
			(xy 175.402396 -10.394557) (xy 175.348439 -10.408663) (xy 175.299936 -10.414) (xy 178.367942 -10.414)
			(xy 178.372013 -10.358378) (xy 178.384139 -10.303941) (xy 178.404062 -10.25185) (xy 178.431358 -10.203215)
			(xy 178.465444 -10.159072) (xy 178.505593 -10.120363) (xy 178.550951 -10.087912) (xy 178.600551 -10.062411)
			(xy 178.653335 -10.044404) (xy 178.708178 -10.034274) (xy 178.763912 -10.032237) (xy 178.819349 -10.038337)
			(xy 178.873306 -10.052443) (xy 178.924635 -10.074255) (xy 178.972241 -10.103309) (xy 179.015109 -10.138984)
			(xy 179.052326 -10.180521) (xy 179.083099 -10.227034) (xy 179.106771 -10.277531) (xy 179.122839 -10.330938)
			(xy 179.130959 -10.386114) (xy 179.131468 -10.414) (xy 179.130959 -10.441886) (xy 179.122839 -10.497062)
			(xy 179.106771 -10.550469) (xy 179.083099 -10.600966) (xy 179.052326 -10.647479) (xy 179.015109 -10.689016)
			(xy 178.972241 -10.724691) (xy 178.924635 -10.753745) (xy 178.873306 -10.775557) (xy 178.819349 -10.789663)
			(xy 178.763912 -10.795763) (xy 178.708178 -10.793726) (xy 178.653335 -10.783596) (xy 178.600551 -10.765589)
			(xy 178.550951 -10.740088) (xy 178.505593 -10.707637) (xy 178.465444 -10.668928) (xy 178.431358 -10.624785)
			(xy 178.404062 -10.57615) (xy 178.384139 -10.524059) (xy 178.372013 -10.469622) (xy 178.367942 -10.414)
			(xy 175.299936 -10.414) (xy 175.293002 -10.414763) (xy 175.237268 -10.412726) (xy 175.182425 -10.402596)
			(xy 175.129641 -10.384589) (xy 175.080041 -10.359088) (xy 175.034683 -10.326637) (xy 174.994534 -10.287928)
			(xy 174.960448 -10.243785) (xy 174.933152 -10.19515) (xy 174.913229 -10.143059) (xy 174.901103 -10.088622)
			(xy 174.897032 -10.033) (xy 165.3032 -10.033) (xy 165.3032 -11.938) (xy 188.888572 -11.938) (xy 188.892602 -11.853395)
			(xy 188.904657 -11.769556) (xy 188.924626 -11.687243) (xy 188.95233 -11.607201) (xy 188.987517 -11.530155)
			(xy 189.029869 -11.456802) (xy 189.079001 -11.387808) (xy 189.13447 -11.323796) (xy 189.195772 -11.265347)
			(xy 189.262353 -11.212991) (xy 189.333609 -11.1672) (xy 189.408895 -11.12839) (xy 189.48753 -11.096912)
			(xy 189.568801 -11.073052) (xy 189.651972 -11.057026) (xy 189.73629 -11.048978) (xy 189.77864 -11.048492)
			(xy 189.778894 -11.048492) (xy 189.822984 -11.049072) (xy 189.910724 -11.057876) (xy 189.997161 -11.075328)
			(xy 190.081443 -11.101257) (xy 190.122302 -11.117834) (xy 190.12535 -11.119104) (xy 190.133377 -11.121451)
			(xy 190.150089 -11.121451) (xy 190.158116 -11.119104) (xy 190.203365 -11.104736) (xy 190.29615 -11.084614)
			(xy 190.390553 -11.074501) (xy 190.438024 -11.073892) (xy 190.43904 -11.073892) (xy 190.482158 -11.074416)
			(xy 190.56799 -11.082759) (xy 190.652611 -11.099372) (xy 190.735227 -11.124099) (xy 190.775336 -11.139932)
			(xy 190.784705 -11.143269) (xy 190.804575 -11.143269) (xy 190.813944 -11.139932) (xy 190.854048 -11.124083)
			(xy 190.936665 -11.099356) (xy 191.021287 -11.082743) (xy 191.107121 -11.074399) (xy 191.15024 -11.073892)
			(xy 191.192587 -11.074397) (xy 191.276898 -11.082452) (xy 191.360061 -11.098484) (xy 191.441324 -11.122348)
			(xy 191.519951 -11.153828) (xy 191.595229 -11.19264) (xy 191.666478 -11.238431) (xy 191.733051 -11.290788)
			(xy 191.794346 -11.349235) (xy 191.849808 -11.413244) (xy 191.898934 -11.482235) (xy 191.94128 -11.555583)
			(xy 191.976463 -11.632625) (xy 192.004163 -11.712661) (xy 192.02413 -11.794969) (xy 192.036183 -11.878801)
			(xy 192.040213 -11.9634) (xy 192.036183 -12.047999) (xy 192.02413 -12.131831) (xy 192.004163 -12.214139)
			(xy 191.976463 -12.294175) (xy 191.94128 -12.371217) (xy 191.898934 -12.444565) (xy 191.849808 -12.513556)
			(xy 191.794346 -12.577565) (xy 191.733051 -12.636012) (xy 191.666478 -12.688369) (xy 191.595229 -12.73416)
			(xy 191.519951 -12.772972) (xy 191.441324 -12.804452) (xy 191.360061 -12.828316) (xy 191.276898 -12.844348)
			(xy 191.192587 -12.852403) (xy 191.15024 -12.852908) (xy 191.107122 -12.852391) (xy 191.021289 -12.844046)
			(xy 190.936668 -12.827431) (xy 190.854053 -12.802702) (xy 190.813944 -12.786868) (xy 190.804575 -12.783531)
			(xy 190.784705 -12.783531) (xy 190.775336 -12.786868) (xy 190.735223 -12.802692) (xy 190.652609 -12.827425)
			(xy 190.56799 -12.844046) (xy 190.482158 -12.852397) (xy 190.43904 -12.852908) (xy 190.438786 -12.852908)
			(xy 190.394696 -12.852335) (xy 190.306956 -12.843529) (xy 190.220519 -12.826075) (xy 190.136237 -12.800144)
			(xy 190.095378 -12.783566) (xy 190.09233 -12.782296) (xy 190.084317 -12.779859) (xy 190.067577 -12.779859)
			(xy 190.059564 -12.782296) (xy 190.014317 -12.796669) (xy 189.92153 -12.816789) (xy 189.827127 -12.8269)
			(xy 189.779656 -12.827508) (xy 189.77864 -12.827508) (xy 189.73629 -12.827022) (xy 189.651972 -12.818974)
			(xy 189.568801 -12.802948) (xy 189.48753 -12.779088) (xy 189.408895 -12.74761) (xy 189.333609 -12.7088)
			(xy 189.262353 -12.663009) (xy 189.195772 -12.610653) (xy 189.13447 -12.552204) (xy 189.079001 -12.488192)
			(xy 189.029869 -12.419198) (xy 188.987517 -12.345845) (xy 188.95233 -12.268799) (xy 188.924626 -12.188757)
			(xy 188.904657 -12.106444) (xy 188.892602 -12.022605) (xy 188.888572 -11.938) (xy 165.3032 -11.938)
			(xy 165.3032 -13.745972) (xy 178.367942 -13.745972) (xy 178.372013 -13.69035) (xy 178.384139 -13.635913)
			(xy 178.404062 -13.583822) (xy 178.431358 -13.535187) (xy 178.465444 -13.491044) (xy 178.505593 -13.452335)
			(xy 178.550951 -13.419884) (xy 178.600551 -13.394383) (xy 178.653335 -13.376376) (xy 178.708178 -13.366246)
			(xy 178.763912 -13.364209) (xy 178.819349 -13.370309) (xy 178.873306 -13.384415) (xy 178.924635 -13.406227)
			(xy 178.972241 -13.435281) (xy 179.015109 -13.470956) (xy 179.052326 -13.512493) (xy 179.083099 -13.559006)
			(xy 179.106771 -13.609503) (xy 179.122839 -13.66291) (xy 179.130959 -13.718086) (xy 179.131468 -13.745972)
			(xy 179.130959 -13.773858) (xy 179.122839 -13.829034) (xy 179.106771 -13.882441) (xy 179.083099 -13.932938)
			(xy 179.052326 -13.979451) (xy 179.015109 -14.020988) (xy 178.972241 -14.056663) (xy 178.924635 -14.085717)
			(xy 178.898083 -14.097) (xy 188.888572 -14.097) (xy 188.892602 -14.012395) (xy 188.904657 -13.928556)
			(xy 188.924626 -13.846243) (xy 188.95233 -13.766201) (xy 188.987517 -13.689155) (xy 189.029869 -13.615802)
			(xy 189.079001 -13.546808) (xy 189.13447 -13.482796) (xy 189.195772 -13.424347) (xy 189.262353 -13.371991)
			(xy 189.333609 -13.3262) (xy 189.408895 -13.28739) (xy 189.48753 -13.255912) (xy 189.568801 -13.232052)
			(xy 189.651972 -13.216026) (xy 189.73629 -13.207978) (xy 189.77864 -13.207492) (xy 189.778894 -13.207492)
			(xy 189.822984 -13.208072) (xy 189.910724 -13.216876) (xy 189.997161 -13.234328) (xy 190.081443 -13.260257)
			(xy 190.122302 -13.276834) (xy 190.12535 -13.278104) (xy 190.133377 -13.280451) (xy 190.150089 -13.280451)
			(xy 190.158116 -13.278104) (xy 190.203365 -13.263736) (xy 190.29615 -13.243614) (xy 190.390553 -13.233501)
			(xy 190.438024 -13.232892) (xy 190.43904 -13.232892) (xy 190.482158 -13.233416) (xy 190.56799 -13.241759)
			(xy 190.652611 -13.258372) (xy 190.735227 -13.283099) (xy 190.775336 -13.298932) (xy 190.784705 -13.302269)
			(xy 190.804575 -13.302269) (xy 190.813944 -13.298932) (xy 190.854048 -13.283083) (xy 190.936665 -13.258356)
			(xy 191.021287 -13.241743) (xy 191.107121 -13.233399) (xy 191.15024 -13.232892) (xy 191.192587 -13.233397)
			(xy 191.276898 -13.241452) (xy 191.360061 -13.257484) (xy 191.441324 -13.281348) (xy 191.519951 -13.312828)
			(xy 191.595229 -13.35164) (xy 191.666478 -13.397431) (xy 191.733051 -13.449788) (xy 191.794346 -13.508235)
			(xy 191.849808 -13.572244) (xy 191.898934 -13.641235) (xy 191.94128 -13.714583) (xy 191.976463 -13.791625)
			(xy 192.004163 -13.871661) (xy 192.02413 -13.953969) (xy 192.036183 -14.037801) (xy 192.040213 -14.1224)
			(xy 192.036183 -14.206999) (xy 192.02413 -14.290831) (xy 192.004163 -14.373139) (xy 191.976463 -14.453175)
			(xy 191.94128 -14.530217) (xy 191.898934 -14.603565) (xy 191.849808 -14.672556) (xy 191.794346 -14.736565)
			(xy 191.733051 -14.795012) (xy 191.666478 -14.847369) (xy 191.595229 -14.89316) (xy 191.519951 -14.931972)
			(xy 191.441324 -14.963452) (xy 191.360061 -14.987316) (xy 191.276898 -15.003348) (xy 191.192587 -15.011403)
			(xy 191.15024 -15.011908) (xy 191.107122 -15.011391) (xy 191.021289 -15.003046) (xy 190.936668 -14.986431)
			(xy 190.854053 -14.961702) (xy 190.813944 -14.945868) (xy 190.804575 -14.942531) (xy 190.784705 -14.942531)
			(xy 190.775336 -14.945868) (xy 190.735223 -14.961692) (xy 190.652609 -14.986425) (xy 190.56799 -15.003046)
			(xy 190.482158 -15.011397) (xy 190.43904 -15.011908) (xy 190.438786 -15.011908) (xy 190.394696 -15.011335)
			(xy 190.306956 -15.002529) (xy 190.220519 -14.985075) (xy 190.136237 -14.959144) (xy 190.095378 -14.942566)
			(xy 190.09233 -14.941296) (xy 190.084317 -14.938859) (xy 190.067577 -14.938859) (xy 190.059564 -14.941296)
			(xy 190.014317 -14.955669) (xy 189.92153 -14.975789) (xy 189.827127 -14.9859) (xy 189.779656 -14.986508)
			(xy 189.77864 -14.986508) (xy 189.73629 -14.986022) (xy 189.651972 -14.977974) (xy 189.568801 -14.961948)
			(xy 189.48753 -14.938088) (xy 189.408895 -14.90661) (xy 189.333609 -14.8678) (xy 189.262353 -14.822009)
			(xy 189.195772 -14.769653) (xy 189.13447 -14.711204) (xy 189.079001 -14.647192) (xy 189.029869 -14.578198)
			(xy 188.987517 -14.504845) (xy 188.95233 -14.427799) (xy 188.924626 -14.347757) (xy 188.904657 -14.265444)
			(xy 188.892602 -14.181605) (xy 188.888572 -14.097) (xy 178.898083 -14.097) (xy 178.873306 -14.107529)
			(xy 178.819349 -14.121635) (xy 178.763912 -14.127735) (xy 178.708178 -14.125698) (xy 178.653335 -14.115568)
			(xy 178.600551 -14.097561) (xy 178.550951 -14.07206) (xy 178.505593 -14.039609) (xy 178.465444 -14.0009)
			(xy 178.431358 -13.956757) (xy 178.404062 -13.908122) (xy 178.384139 -13.856031) (xy 178.372013 -13.801594)
			(xy 178.367942 -13.745972) (xy 165.3032 -13.745972) (xy 165.3032 -16.256) (xy 188.888572 -16.256)
			(xy 188.892602 -16.171395) (xy 188.904657 -16.087556) (xy 188.924626 -16.005243) (xy 188.95233 -15.925201)
			(xy 188.987517 -15.848155) (xy 189.029869 -15.774802) (xy 189.079001 -15.705808) (xy 189.13447 -15.641796)
			(xy 189.195772 -15.583347) (xy 189.262353 -15.530991) (xy 189.333609 -15.4852) (xy 189.408895 -15.44639)
			(xy 189.48753 -15.414912) (xy 189.568801 -15.391052) (xy 189.651972 -15.375026) (xy 189.73629 -15.366978)
			(xy 189.77864 -15.366492) (xy 189.778894 -15.366492) (xy 189.822984 -15.367072) (xy 189.910724 -15.375876)
			(xy 189.997161 -15.393328) (xy 190.081443 -15.419257) (xy 190.122302 -15.435834) (xy 190.12535 -15.437104)
			(xy 190.133377 -15.439451) (xy 190.150089 -15.439451) (xy 190.158116 -15.437104) (xy 190.203365 -15.422736)
			(xy 190.29615 -15.402614) (xy 190.390553 -15.392501) (xy 190.438024 -15.391892) (xy 190.43904 -15.391892)
			(xy 190.482158 -15.392416) (xy 190.56799 -15.400759) (xy 190.652611 -15.417372) (xy 190.735227 -15.442099)
			(xy 190.775336 -15.457932) (xy 190.784705 -15.461269) (xy 190.804575 -15.461269) (xy 190.813944 -15.457932)
			(xy 190.854048 -15.442083) (xy 190.936665 -15.417356) (xy 191.021287 -15.400743) (xy 191.107121 -15.392399)
			(xy 191.15024 -15.391892) (xy 191.192587 -15.392397) (xy 191.276898 -15.400452) (xy 191.360061 -15.416484)
			(xy 191.441324 -15.440348) (xy 191.519951 -15.471828) (xy 191.595229 -15.51064) (xy 191.666478 -15.556431)
			(xy 191.733051 -15.608788) (xy 191.794346 -15.667235) (xy 191.849808 -15.731244) (xy 191.898934 -15.800235)
			(xy 191.94128 -15.873583) (xy 191.976463 -15.950625) (xy 192.004163 -16.030661) (xy 192.02413 -16.112969)
			(xy 192.036183 -16.196801) (xy 192.040213 -16.2814) (xy 192.036183 -16.365999) (xy 192.02413 -16.449831)
			(xy 192.004163 -16.532139) (xy 191.976463 -16.612175) (xy 191.94128 -16.689217) (xy 191.898934 -16.762565)
			(xy 191.849808 -16.831556) (xy 191.794346 -16.895565) (xy 191.733051 -16.954012) (xy 191.666478 -17.006369)
			(xy 191.595229 -17.05216) (xy 191.519951 -17.090972) (xy 191.441324 -17.122452) (xy 191.360061 -17.146316)
			(xy 191.276898 -17.162348) (xy 191.192587 -17.170403) (xy 191.15024 -17.170908) (xy 191.107122 -17.170391)
			(xy 191.021289 -17.162046) (xy 190.936668 -17.145431) (xy 190.854053 -17.120702) (xy 190.813944 -17.104868)
			(xy 190.804575 -17.101531) (xy 190.784705 -17.101531) (xy 190.775336 -17.104868) (xy 190.735223 -17.120692)
			(xy 190.652609 -17.145425) (xy 190.56799 -17.162046) (xy 190.482158 -17.170397) (xy 190.43904 -17.170908)
			(xy 190.438786 -17.170908) (xy 190.394696 -17.170335) (xy 190.306956 -17.161529) (xy 190.220519 -17.144075)
			(xy 190.136237 -17.118144) (xy 190.095378 -17.101566) (xy 190.09233 -17.100296) (xy 190.084317 -17.097859)
			(xy 190.067577 -17.097859) (xy 190.059564 -17.100296) (xy 190.014317 -17.114669) (xy 189.92153 -17.134789)
			(xy 189.827127 -17.1449) (xy 189.779656 -17.145508) (xy 189.77864 -17.145508) (xy 189.73629 -17.145022)
			(xy 189.651972 -17.136974) (xy 189.568801 -17.120948) (xy 189.48753 -17.097088) (xy 189.408895 -17.06561)
			(xy 189.333609 -17.0268) (xy 189.262353 -16.981009) (xy 189.195772 -16.928653) (xy 189.13447 -16.870204)
			(xy 189.079001 -16.806192) (xy 189.029869 -16.737198) (xy 188.987517 -16.663845) (xy 188.95233 -16.586799)
			(xy 188.924626 -16.506757) (xy 188.904657 -16.424444) (xy 188.892602 -16.340605) (xy 188.888572 -16.256)
			(xy 165.3032 -16.256) (xy 165.3032 -17.504918) (xy 165.30366 -17.514795) (xy 165.311103 -17.533094)
			(xy 165.317678 -17.540478) (xy 166.532052 -18.754852) (xy 166.53256 -18.75536) (xy 166.539942 -18.761941)
			(xy 166.558241 -18.769387) (xy 166.56812 -18.769838) (xy 172.398944 -18.769838) (xy 172.403898 -18.769961)
			(xy 172.413617 -18.771885) (xy 172.418248 -18.773648) (xy 172.444664 -18.784824) (xy 201.020934 -18.784824)
			(xy 201.031001 -18.785254) (xy 201.049594 -18.79298) (xy 201.057002 -18.79981) (xy 203.254553 -20.997361)
			(xy 276.478742 -20.997361) (xy 276.478742 -20.912639) (xy 276.486795 -20.828302) (xy 276.502829 -20.745112)
			(xy 276.526697 -20.663822) (xy 276.558185 -20.58517) (xy 276.597007 -20.509867) (xy 276.64281 -20.438595)
			(xy 276.695181 -20.371999) (xy 276.753646 -20.310684) (xy 276.817674 -20.255203) (xy 276.886686 -20.20606)
			(xy 276.960056 -20.1637) (xy 277.037121 -20.128505) (xy 277.117183 -20.100796) (xy 277.199516 -20.080822)
			(xy 277.283375 -20.068765) (xy 277.368 -20.064734) (xy 277.452625 -20.068765) (xy 277.536484 -20.080822)
			(xy 277.618817 -20.100796) (xy 277.698879 -20.128505) (xy 277.775944 -20.1637) (xy 277.849314 -20.20606)
			(xy 277.918326 -20.255203) (xy 277.982354 -20.310684) (xy 278.040819 -20.371999) (xy 278.09319 -20.438595)
			(xy 278.138993 -20.509867) (xy 278.177815 -20.58517) (xy 278.209303 -20.663822) (xy 278.233171 -20.745112)
			(xy 278.249205 -20.828302) (xy 278.257258 -20.912639) (xy 278.257762 -20.955) (xy 278.257258 -20.997361)
			(xy 278.249205 -21.081698) (xy 278.233171 -21.164888) (xy 278.209303 -21.246178) (xy 278.177815 -21.32483)
			(xy 278.138993 -21.400133) (xy 278.09319 -21.471405) (xy 278.040819 -21.538001) (xy 277.982354 -21.599316)
			(xy 277.918326 -21.654797) (xy 277.849314 -21.70394) (xy 277.775944 -21.7463) (xy 277.698879 -21.781495)
			(xy 277.618817 -21.809204) (xy 277.536484 -21.829178) (xy 277.452625 -21.841235) (xy 277.368 -21.845267)
			(xy 277.283375 -21.841235) (xy 277.199516 -21.829178) (xy 277.117183 -21.809204) (xy 277.037121 -21.781495)
			(xy 276.960056 -21.7463) (xy 276.886686 -21.70394) (xy 276.817674 -21.654797) (xy 276.753646 -21.599316)
			(xy 276.695181 -21.538001) (xy 276.64281 -21.471405) (xy 276.597007 -21.400133) (xy 276.558185 -21.32483)
			(xy 276.526697 -21.246178) (xy 276.502829 -21.164888) (xy 276.486795 -21.081698) (xy 276.478742 -20.997361)
			(xy 203.254553 -20.997361) (xy 203.83754 -21.580348) (xy 203.844385 -21.587746) (xy 203.852112 -21.606345)
			(xy 203.852526 -21.616416) (xy 203.852526 -23.0886) (xy 271.702534 -23.0886) (xy 271.706565 -23.003975)
			(xy 271.718622 -22.920116) (xy 271.738596 -22.837783) (xy 271.766305 -22.757721) (xy 271.8015 -22.680656)
			(xy 271.84386 -22.607286) (xy 271.893003 -22.538274) (xy 271.948484 -22.474246) (xy 272.009799 -22.415781)
			(xy 272.076395 -22.36341) (xy 272.147667 -22.317607) (xy 272.22297 -22.278785) (xy 272.301622 -22.247297)
			(xy 272.382912 -22.223429) (xy 272.466102 -22.207395) (xy 272.550439 -22.199342) (xy 272.5928 -22.198838)
			(xy 272.635115 -22.199334) (xy 272.719363 -22.207365) (xy 272.802467 -22.223364) (xy 272.883676 -22.247186)
			(xy 272.962253 -22.278615) (xy 273.037489 -22.317368) (xy 273.073368 -22.339808) (xy 273.081757 -22.344691)
			(xy 273.1008 -22.348362) (xy 273.119843 -22.344691) (xy 273.128232 -22.339808) (xy 273.164109 -22.317367)
			(xy 273.239349 -22.278622) (xy 273.317928 -22.247198) (xy 273.399135 -22.223377) (xy 273.482238 -22.207377)
			(xy 273.566485 -22.19934) (xy 273.6088 -22.198838) (xy 273.651161 -22.199342) (xy 273.735498 -22.207395)
			(xy 273.818688 -22.223429) (xy 273.899978 -22.247297) (xy 273.97863 -22.278785) (xy 274.053933 -22.317607)
			(xy 274.125205 -22.36341) (xy 274.191801 -22.415781) (xy 274.253116 -22.474246) (xy 274.308597 -22.538274)
			(xy 274.35774 -22.607286) (xy 274.4001 -22.680656) (xy 274.435295 -22.757721) (xy 274.463004 -22.837783)
			(xy 274.482978 -22.920116) (xy 274.488942 -22.9616) (xy 291.387791 -22.9616) (xy 291.391794 -22.873738)
			(xy 291.40377 -22.786604) (xy 291.423621 -22.70092) (xy 291.45118 -22.617396) (xy 291.486221 -22.536724)
			(xy 291.528452 -22.459573) (xy 291.577524 -22.386582) (xy 291.633031 -22.318356) (xy 291.694511 -22.25546)
			(xy 291.761456 -22.198415) (xy 291.833311 -22.147694) (xy 291.909481 -22.103717) (xy 291.989334 -22.066849)
			(xy 292.072209 -22.037396) (xy 292.157419 -22.0156) (xy 292.244258 -22.001644) (xy 292.332006 -21.995641)
			(xy 292.419936 -21.997643) (xy 292.507321 -22.007633) (xy 292.593434 -22.025528) (xy 292.677564 -22.051179)
			(xy 292.759012 -22.084374) (xy 292.837105 -22.124838) (xy 292.911194 -22.172236) (xy 292.980666 -22.226175)
			(xy 293.044945 -22.286208) (xy 293.103499 -22.351837) (xy 293.155843 -22.422519) (xy 293.201542 -22.497668)
			(xy 293.240218 -22.576661) (xy 293.27155 -22.658844) (xy 293.29528 -22.743536) (xy 293.31121 -22.830035)
			(xy 293.319208 -22.917623) (xy 293.319708 -22.9616) (xy 293.927791 -22.9616) (xy 293.931794 -22.873738)
			(xy 293.94377 -22.786604) (xy 293.963621 -22.70092) (xy 293.99118 -22.617396) (xy 294.026221 -22.536724)
			(xy 294.068452 -22.459573) (xy 294.117524 -22.386582) (xy 294.173031 -22.318356) (xy 294.234511 -22.25546)
			(xy 294.301456 -22.198415) (xy 294.373311 -22.147694) (xy 294.449481 -22.103717) (xy 294.529334 -22.066849)
			(xy 294.612209 -22.037396) (xy 294.697419 -22.0156) (xy 294.784258 -22.001644) (xy 294.872006 -21.995641)
			(xy 294.959936 -21.997643) (xy 295.047321 -22.007633) (xy 295.133434 -22.025528) (xy 295.217564 -22.051179)
			(xy 295.299012 -22.084374) (xy 295.377105 -22.124838) (xy 295.451194 -22.172236) (xy 295.520666 -22.226175)
			(xy 295.584945 -22.286208) (xy 295.643499 -22.351837) (xy 295.695843 -22.422519) (xy 295.741542 -22.497668)
			(xy 295.780218 -22.576661) (xy 295.81155 -22.658844) (xy 295.83528 -22.743536) (xy 295.85121 -22.830035)
			(xy 295.859208 -22.917623) (xy 295.859708 -22.9616) (xy 296.467791 -22.9616) (xy 296.471794 -22.873738)
			(xy 296.48377 -22.786604) (xy 296.503621 -22.70092) (xy 296.53118 -22.617396) (xy 296.566221 -22.536724)
			(xy 296.608452 -22.459573) (xy 296.657524 -22.386582) (xy 296.713031 -22.318356) (xy 296.774511 -22.25546)
			(xy 296.841456 -22.198415) (xy 296.913311 -22.147694) (xy 296.989481 -22.103717) (xy 297.069334 -22.066849)
			(xy 297.152209 -22.037396) (xy 297.237419 -22.0156) (xy 297.324258 -22.001644) (xy 297.412006 -21.995641)
			(xy 297.499936 -21.997643) (xy 297.587321 -22.007633) (xy 297.673434 -22.025528) (xy 297.757564 -22.051179)
			(xy 297.839012 -22.084374) (xy 297.917105 -22.124838) (xy 297.991194 -22.172236) (xy 298.060666 -22.226175)
			(xy 298.124945 -22.286208) (xy 298.183499 -22.351837) (xy 298.235843 -22.422519) (xy 298.281542 -22.497668)
			(xy 298.320218 -22.576661) (xy 298.35155 -22.658844) (xy 298.37528 -22.743536) (xy 298.39121 -22.830035)
			(xy 298.399208 -22.917623) (xy 298.399708 -22.9616) (xy 298.399208 -23.005577) (xy 298.39121 -23.093165)
			(xy 298.37528 -23.179664) (xy 298.35155 -23.264356) (xy 298.320218 -23.346539) (xy 298.281542 -23.425532)
			(xy 298.235843 -23.500681) (xy 298.183499 -23.571363) (xy 298.124945 -23.636992) (xy 298.060666 -23.697025)
			(xy 297.991194 -23.750964) (xy 297.917105 -23.798362) (xy 297.839012 -23.838826) (xy 297.757564 -23.872021)
			(xy 297.673434 -23.897672) (xy 297.587321 -23.915567) (xy 297.499936 -23.925557) (xy 297.412006 -23.927559)
			(xy 297.324258 -23.921556) (xy 297.237419 -23.9076) (xy 297.152209 -23.885804) (xy 297.069334 -23.856351)
			(xy 296.989481 -23.819483) (xy 296.913311 -23.775506) (xy 296.841456 -23.724785) (xy 296.774511 -23.66774)
			(xy 296.713031 -23.604844) (xy 296.657524 -23.536618) (xy 296.608452 -23.463627) (xy 296.566221 -23.386476)
			(xy 296.53118 -23.305804) (xy 296.503621 -23.22228) (xy 296.48377 -23.136596) (xy 296.471794 -23.049462)
			(xy 296.467791 -22.9616) (xy 295.859708 -22.9616) (xy 295.859208 -23.005577) (xy 295.85121 -23.093165)
			(xy 295.83528 -23.179664) (xy 295.81155 -23.264356) (xy 295.780218 -23.346539) (xy 295.741542 -23.425532)
			(xy 295.695843 -23.500681) (xy 295.643499 -23.571363) (xy 295.584945 -23.636992) (xy 295.520666 -23.697025)
			(xy 295.451194 -23.750964) (xy 295.377105 -23.798362) (xy 295.299012 -23.838826) (xy 295.217564 -23.872021)
			(xy 295.133434 -23.897672) (xy 295.047321 -23.915567) (xy 294.959936 -23.925557) (xy 294.872006 -23.927559)
			(xy 294.784258 -23.921556) (xy 294.697419 -23.9076) (xy 294.612209 -23.885804) (xy 294.529334 -23.856351)
			(xy 294.449481 -23.819483) (xy 294.373311 -23.775506) (xy 294.301456 -23.724785) (xy 294.234511 -23.66774)
			(xy 294.173031 -23.604844) (xy 294.117524 -23.536618) (xy 294.068452 -23.463627) (xy 294.026221 -23.386476)
			(xy 293.99118 -23.305804) (xy 293.963621 -23.22228) (xy 293.94377 -23.136596) (xy 293.931794 -23.049462)
			(xy 293.927791 -22.9616) (xy 293.319708 -22.9616) (xy 293.319208 -23.005577) (xy 293.31121 -23.093165)
			(xy 293.29528 -23.179664) (xy 293.27155 -23.264356) (xy 293.240218 -23.346539) (xy 293.201542 -23.425532)
			(xy 293.155843 -23.500681) (xy 293.103499 -23.571363) (xy 293.044945 -23.636992) (xy 292.980666 -23.697025)
			(xy 292.911194 -23.750964) (xy 292.837105 -23.798362) (xy 292.759012 -23.838826) (xy 292.677564 -23.872021)
			(xy 292.593434 -23.897672) (xy 292.507321 -23.915567) (xy 292.419936 -23.925557) (xy 292.332006 -23.927559)
			(xy 292.244258 -23.921556) (xy 292.157419 -23.9076) (xy 292.072209 -23.885804) (xy 291.989334 -23.856351)
			(xy 291.909481 -23.819483) (xy 291.833311 -23.775506) (xy 291.761456 -23.724785) (xy 291.694511 -23.66774)
			(xy 291.633031 -23.604844) (xy 291.577524 -23.536618) (xy 291.528452 -23.463627) (xy 291.486221 -23.386476)
			(xy 291.45118 -23.305804) (xy 291.423621 -23.22228) (xy 291.40377 -23.136596) (xy 291.391794 -23.049462)
			(xy 291.387791 -22.9616) (xy 274.488942 -22.9616) (xy 274.495035 -23.003975) (xy 274.499067 -23.0886)
			(xy 274.495035 -23.173225) (xy 274.482978 -23.257084) (xy 274.463004 -23.339417) (xy 274.435295 -23.419479)
			(xy 274.4001 -23.496544) (xy 274.35774 -23.569914) (xy 274.308597 -23.638926) (xy 274.253116 -23.702954)
			(xy 274.191801 -23.761419) (xy 274.125205 -23.81379) (xy 274.053933 -23.859593) (xy 273.97863 -23.898415)
			(xy 273.899978 -23.929903) (xy 273.818688 -23.953771) (xy 273.735498 -23.969805) (xy 273.651161 -23.977858)
			(xy 273.6088 -23.978362) (xy 273.566485 -23.977866) (xy 273.482237 -23.969835) (xy 273.399133 -23.953836)
			(xy 273.317924 -23.930014) (xy 273.239347 -23.898585) (xy 273.164111 -23.859832) (xy 273.128232 -23.837392)
			(xy 273.119843 -23.832509) (xy 273.1008 -23.828838) (xy 273.081757 -23.832509) (xy 273.073368 -23.837392)
			(xy 273.037491 -23.859833) (xy 272.962251 -23.898578) (xy 272.883672 -23.930002) (xy 272.802465 -23.953823)
			(xy 272.719362 -23.969823) (xy 272.635115 -23.97786) (xy 272.5928 -23.978362) (xy 272.550439 -23.977858)
			(xy 272.466102 -23.969805) (xy 272.382912 -23.953771) (xy 272.301622 -23.929903) (xy 272.22297 -23.898415)
			(xy 272.147667 -23.859593) (xy 272.076395 -23.81379) (xy 272.009799 -23.761419) (xy 271.948484 -23.702954)
			(xy 271.893003 -23.638926) (xy 271.84386 -23.569914) (xy 271.8015 -23.496544) (xy 271.766305 -23.419479)
			(xy 271.738596 -23.339417) (xy 271.718622 -23.257084) (xy 271.706565 -23.173225) (xy 271.702534 -23.0886)
			(xy 203.852526 -23.0886) (xy 203.852526 -24.892) (xy 255.827791 -24.892) (xy 255.831794 -24.804138)
			(xy 255.84377 -24.717004) (xy 255.863621 -24.63132) (xy 255.89118 -24.547796) (xy 255.926221 -24.467124)
			(xy 255.968452 -24.389973) (xy 256.017524 -24.316982) (xy 256.073031 -24.248756) (xy 256.134511 -24.18586)
			(xy 256.201456 -24.128815) (xy 256.273311 -24.078094) (xy 256.349481 -24.034117) (xy 256.429334 -23.997249)
			(xy 256.512209 -23.967796) (xy 256.597419 -23.946) (xy 256.684258 -23.932044) (xy 256.772006 -23.926041)
			(xy 256.859936 -23.928043) (xy 256.947321 -23.938033) (xy 257.033434 -23.955928) (xy 257.117564 -23.981579)
			(xy 257.199012 -24.014774) (xy 257.277105 -24.055238) (xy 257.351194 -24.102636) (xy 257.420666 -24.156575)
			(xy 257.484945 -24.216608) (xy 257.543499 -24.282237) (xy 257.595843 -24.352919) (xy 257.641542 -24.428068)
			(xy 257.680218 -24.507061) (xy 257.71155 -24.589244) (xy 257.73528 -24.673936) (xy 257.75121 -24.760435)
			(xy 257.759208 -24.848023) (xy 257.759708 -24.892) (xy 257.759208 -24.935977) (xy 257.75121 -25.023565)
			(xy 257.73528 -25.110064) (xy 257.71155 -25.194756) (xy 257.680218 -25.276939) (xy 257.641542 -25.355932)
			(xy 257.595843 -25.431081) (xy 257.543499 -25.501763) (xy 257.484945 -25.567392) (xy 257.420666 -25.627425)
			(xy 257.410974 -25.63495) (xy 259.352032 -25.63495) (xy 259.356103 -25.579328) (xy 259.368229 -25.524891)
			(xy 259.388152 -25.4728) (xy 259.415448 -25.424165) (xy 259.449534 -25.380022) (xy 259.489683 -25.341313)
			(xy 259.535041 -25.308862) (xy 259.584641 -25.283361) (xy 259.637425 -25.265354) (xy 259.692268 -25.255224)
			(xy 259.748002 -25.253187) (xy 259.803439 -25.259287) (xy 259.857396 -25.273393) (xy 259.908725 -25.295205)
			(xy 259.956331 -25.324259) (xy 259.999199 -25.359934) (xy 260.035098 -25.4) (xy 275.715728 -25.4)
			(xy 275.719801 -25.344341) (xy 275.731936 -25.289868) (xy 275.751872 -25.237742) (xy 275.779186 -25.189074)
			(xy 275.813294 -25.144902) (xy 275.853471 -25.106167) (xy 275.898859 -25.073695) (xy 275.948491 -25.048177)
			(xy 276.001311 -25.030158) (xy 276.05619 -25.020021) (xy 276.111961 -25.017983) (xy 276.167435 -25.024086)
			(xy 276.221428 -25.038202) (xy 276.272791 -25.060029) (xy 276.320429 -25.089102) (xy 276.363325 -25.124801)
			(xy 276.400567 -25.166365) (xy 276.431361 -25.212909) (xy 276.455049 -25.26344) (xy 276.471127 -25.316882)
			(xy 276.479253 -25.372096) (xy 276.479762 -25.4) (xy 276.479253 -25.427904) (xy 276.471127 -25.483118)
			(xy 276.455049 -25.53656) (xy 276.431361 -25.587091) (xy 276.400567 -25.633635) (xy 276.363325 -25.675199)
			(xy 276.320429 -25.710898) (xy 276.272791 -25.739971) (xy 276.221428 -25.761798) (xy 276.167435 -25.775914)
			(xy 276.111961 -25.782017) (xy 276.05619 -25.779979) (xy 276.001311 -25.769842) (xy 275.948491 -25.751823)
			(xy 275.898859 -25.726305) (xy 275.853471 -25.693833) (xy 275.813294 -25.655098) (xy 275.779186 -25.610926)
			(xy 275.751872 -25.562258) (xy 275.731936 -25.510132) (xy 275.719801 -25.455659) (xy 275.715728 -25.4)
			(xy 260.035098 -25.4) (xy 260.036416 -25.401471) (xy 260.067189 -25.447984) (xy 260.090861 -25.498481)
			(xy 260.106929 -25.551888) (xy 260.115049 -25.607064) (xy 260.115558 -25.63495) (xy 260.115049 -25.662836)
			(xy 260.106929 -25.718012) (xy 260.090861 -25.771419) (xy 260.067189 -25.821916) (xy 260.036416 -25.868429)
			(xy 259.999199 -25.909966) (xy 259.956331 -25.945641) (xy 259.908725 -25.974695) (xy 259.857396 -25.996507)
			(xy 259.803439 -26.010613) (xy 259.748002 -26.016713) (xy 259.692268 -26.014676) (xy 259.637425 -26.004546)
			(xy 259.584641 -25.986539) (xy 259.535041 -25.961038) (xy 259.489683 -25.928587) (xy 259.449534 -25.889878)
			(xy 259.415448 -25.845735) (xy 259.388152 -25.7971) (xy 259.368229 -25.745009) (xy 259.356103 -25.690572)
			(xy 259.352032 -25.63495) (xy 257.410974 -25.63495) (xy 257.351194 -25.681364) (xy 257.277105 -25.728762)
			(xy 257.199012 -25.769226) (xy 257.117564 -25.802421) (xy 257.033434 -25.828072) (xy 256.947321 -25.845967)
			(xy 256.859936 -25.855957) (xy 256.772006 -25.857959) (xy 256.684258 -25.851956) (xy 256.597419 -25.838)
			(xy 256.512209 -25.816204) (xy 256.429334 -25.786751) (xy 256.349481 -25.749883) (xy 256.273311 -25.705906)
			(xy 256.201456 -25.655185) (xy 256.134511 -25.59814) (xy 256.073031 -25.535244) (xy 256.017524 -25.467018)
			(xy 255.968452 -25.394027) (xy 255.926221 -25.316876) (xy 255.89118 -25.236204) (xy 255.863621 -25.15268)
			(xy 255.84377 -25.066996) (xy 255.831794 -24.979862) (xy 255.827791 -24.892) (xy 203.852526 -24.892)
			(xy 203.852526 -30.372065) (xy 205.499205 -30.372065) (xy 205.499205 -30.287199) (xy 205.507272 -30.202717)
			(xy 205.523333 -30.119384) (xy 205.547242 -30.037956) (xy 205.578784 -29.959168) (xy 205.617672 -29.883736)
			(xy 205.663554 -29.812342) (xy 205.716015 -29.745633) (xy 205.774579 -29.684212) (xy 205.838717 -29.628637)
			(xy 205.907847 -29.579409) (xy 205.981343 -29.536976) (xy 206.058541 -29.501721) (xy 206.138739 -29.473964)
			(xy 206.221213 -29.453956) (xy 206.305216 -29.441879) (xy 206.389986 -29.437841) (xy 206.474756 -29.441879)
			(xy 206.558759 -29.453956) (xy 206.641233 -29.473964) (xy 206.721431 -29.501721) (xy 206.798629 -29.536976)
			(xy 206.872125 -29.579409) (xy 206.941255 -29.628637) (xy 207.005393 -29.684212) (xy 207.063957 -29.745633)
			(xy 207.116418 -29.812342) (xy 207.1623 -29.883736) (xy 207.201188 -29.959168) (xy 207.23273 -30.037956)
			(xy 207.256639 -30.119384) (xy 207.2727 -30.202717) (xy 207.280767 -30.287199) (xy 207.281272 -30.329632)
			(xy 207.280767 -30.372065) (xy 208.039205 -30.372065) (xy 208.039205 -30.287199) (xy 208.047272 -30.202717)
			(xy 208.063333 -30.119384) (xy 208.087242 -30.037956) (xy 208.118784 -29.959168) (xy 208.157672 -29.883736)
			(xy 208.203554 -29.812342) (xy 208.256015 -29.745633) (xy 208.314579 -29.684212) (xy 208.378717 -29.628637)
			(xy 208.447847 -29.579409) (xy 208.521343 -29.536976) (xy 208.598541 -29.501721) (xy 208.678739 -29.473964)
			(xy 208.761213 -29.453956) (xy 208.845216 -29.441879) (xy 208.929986 -29.437841) (xy 209.014756 -29.441879)
			(xy 209.098759 -29.453956) (xy 209.181233 -29.473964) (xy 209.261431 -29.501721) (xy 209.338629 -29.536976)
			(xy 209.412125 -29.579409) (xy 209.481255 -29.628637) (xy 209.545393 -29.684212) (xy 209.603957 -29.745633)
			(xy 209.656418 -29.812342) (xy 209.7023 -29.883736) (xy 209.741188 -29.959168) (xy 209.77273 -30.037956)
			(xy 209.796639 -30.119384) (xy 209.8127 -30.202717) (xy 209.820767 -30.287199) (xy 209.821272 -30.329632)
			(xy 209.820767 -30.372065) (xy 210.579205 -30.372065) (xy 210.579205 -30.287199) (xy 210.587272 -30.202717)
			(xy 210.603333 -30.119384) (xy 210.627242 -30.037956) (xy 210.658784 -29.959168) (xy 210.697672 -29.883736)
			(xy 210.743554 -29.812342) (xy 210.796015 -29.745633) (xy 210.854579 -29.684212) (xy 210.918717 -29.628637)
			(xy 210.987847 -29.579409) (xy 211.061343 -29.536976) (xy 211.138541 -29.501721) (xy 211.218739 -29.473964)
			(xy 211.301213 -29.453956) (xy 211.385216 -29.441879) (xy 211.469986 -29.437841) (xy 211.554756 -29.441879)
			(xy 211.638759 -29.453956) (xy 211.721233 -29.473964) (xy 211.801431 -29.501721) (xy 211.878629 -29.536976)
			(xy 211.952125 -29.579409) (xy 212.021255 -29.628637) (xy 212.085393 -29.684212) (xy 212.143957 -29.745633)
			(xy 212.196418 -29.812342) (xy 212.2423 -29.883736) (xy 212.281188 -29.959168) (xy 212.286325 -29.972)
			(xy 255.827791 -29.972) (xy 255.831794 -29.884138) (xy 255.84377 -29.797004) (xy 255.863621 -29.71132)
			(xy 255.89118 -29.627796) (xy 255.926221 -29.547124) (xy 255.968452 -29.469973) (xy 256.017524 -29.396982)
			(xy 256.073031 -29.328756) (xy 256.134511 -29.26586) (xy 256.201456 -29.208815) (xy 256.273311 -29.158094)
			(xy 256.349481 -29.114117) (xy 256.429334 -29.077249) (xy 256.512209 -29.047796) (xy 256.597419 -29.026)
			(xy 256.684258 -29.012044) (xy 256.772006 -29.006041) (xy 256.859936 -29.008043) (xy 256.947321 -29.018033)
			(xy 257.033434 -29.035928) (xy 257.117564 -29.061579) (xy 257.199012 -29.094774) (xy 257.277105 -29.135238)
			(xy 257.351194 -29.182636) (xy 257.420666 -29.236575) (xy 257.484945 -29.296608) (xy 257.520983 -29.337)
			(xy 259.352032 -29.337) (xy 259.356103 -29.281378) (xy 259.368229 -29.226941) (xy 259.388152 -29.17485)
			(xy 259.415448 -29.126215) (xy 259.449534 -29.082072) (xy 259.489683 -29.043363) (xy 259.535041 -29.010912)
			(xy 259.584641 -28.985411) (xy 259.637425 -28.967404) (xy 259.692268 -28.957274) (xy 259.748002 -28.955237)
			(xy 259.803439 -28.961337) (xy 259.857396 -28.975443) (xy 259.908725 -28.997255) (xy 259.956331 -29.026309)
			(xy 259.999199 -29.061984) (xy 260.036416 -29.103521) (xy 260.067189 -29.150034) (xy 260.090861 -29.200531)
			(xy 260.106929 -29.253938) (xy 260.115049 -29.309114) (xy 260.115558 -29.337) (xy 260.115049 -29.364886)
			(xy 260.106929 -29.420062) (xy 260.090861 -29.473469) (xy 260.067189 -29.523966) (xy 260.036416 -29.570479)
			(xy 259.999199 -29.612016) (xy 259.956331 -29.647691) (xy 259.908725 -29.676745) (xy 259.857396 -29.698557)
			(xy 259.803439 -29.712663) (xy 259.748002 -29.718763) (xy 259.692268 -29.716726) (xy 259.637425 -29.706596)
			(xy 259.584641 -29.688589) (xy 259.535041 -29.663088) (xy 259.489683 -29.630637) (xy 259.449534 -29.591928)
			(xy 259.415448 -29.547785) (xy 259.388152 -29.49915) (xy 259.368229 -29.447059) (xy 259.356103 -29.392622)
			(xy 259.352032 -29.337) (xy 257.520983 -29.337) (xy 257.543499 -29.362237) (xy 257.595843 -29.432919)
			(xy 257.641542 -29.508068) (xy 257.680218 -29.587061) (xy 257.71155 -29.669244) (xy 257.73528 -29.753936)
			(xy 257.75121 -29.840435) (xy 257.759208 -29.928023) (xy 257.759708 -29.972) (xy 257.759208 -30.015977)
			(xy 257.75121 -30.103565) (xy 257.73528 -30.190064) (xy 257.71155 -30.274756) (xy 257.680218 -30.356939)
			(xy 257.641542 -30.435932) (xy 257.595843 -30.511081) (xy 257.543499 -30.581763) (xy 257.484945 -30.647392)
			(xy 257.420666 -30.707425) (xy 257.351194 -30.761364) (xy 257.277105 -30.808762) (xy 257.199012 -30.849226)
			(xy 257.117564 -30.882421) (xy 257.033434 -30.908072) (xy 256.947321 -30.925967) (xy 256.859936 -30.935957)
			(xy 256.772006 -30.937959) (xy 256.684258 -30.931956) (xy 256.597419 -30.918) (xy 256.512209 -30.896204)
			(xy 256.429334 -30.866751) (xy 256.349481 -30.829883) (xy 256.273311 -30.785906) (xy 256.201456 -30.735185)
			(xy 256.134511 -30.67814) (xy 256.073031 -30.615244) (xy 256.017524 -30.547018) (xy 255.968452 -30.474027)
			(xy 255.926221 -30.396876) (xy 255.89118 -30.316204) (xy 255.863621 -30.23268) (xy 255.84377 -30.146996)
			(xy 255.831794 -30.059862) (xy 255.827791 -29.972) (xy 212.286325 -29.972) (xy 212.31273 -30.037956)
			(xy 212.336639 -30.119384) (xy 212.3527 -30.202717) (xy 212.360767 -30.287199) (xy 212.361272 -30.329632)
			(xy 212.360767 -30.372065) (xy 212.3527 -30.456547) (xy 212.336639 -30.53988) (xy 212.31273 -30.621308)
			(xy 212.281188 -30.700096) (xy 212.2423 -30.775528) (xy 212.196418 -30.846922) (xy 212.143957 -30.913631)
			(xy 212.085393 -30.975052) (xy 212.021255 -31.030627) (xy 211.952125 -31.079855) (xy 211.878629 -31.122288)
			(xy 211.801431 -31.157543) (xy 211.721233 -31.1853) (xy 211.638759 -31.205308) (xy 211.554756 -31.217385)
			(xy 211.469986 -31.221424) (xy 211.385216 -31.217385) (xy 211.301213 -31.205308) (xy 211.218739 -31.1853)
			(xy 211.138541 -31.157543) (xy 211.061343 -31.122288) (xy 210.987847 -31.079855) (xy 210.918717 -31.030627)
			(xy 210.854579 -30.975052) (xy 210.796015 -30.913631) (xy 210.743554 -30.846922) (xy 210.697672 -30.775528)
			(xy 210.658784 -30.700096) (xy 210.627242 -30.621308) (xy 210.603333 -30.53988) (xy 210.587272 -30.456547)
			(xy 210.579205 -30.372065) (xy 209.820767 -30.372065) (xy 209.8127 -30.456547) (xy 209.796639 -30.53988)
			(xy 209.77273 -30.621308) (xy 209.741188 -30.700096) (xy 209.7023 -30.775528) (xy 209.656418 -30.846922)
			(xy 209.603957 -30.913631) (xy 209.545393 -30.975052) (xy 209.481255 -31.030627) (xy 209.412125 -31.079855)
			(xy 209.338629 -31.122288) (xy 209.261431 -31.157543) (xy 209.181233 -31.1853) (xy 209.098759 -31.205308)
			(xy 209.014756 -31.217385) (xy 208.929986 -31.221424) (xy 208.845216 -31.217385) (xy 208.761213 -31.205308)
			(xy 208.678739 -31.1853) (xy 208.598541 -31.157543) (xy 208.521343 -31.122288) (xy 208.447847 -31.079855)
			(xy 208.378717 -31.030627) (xy 208.314579 -30.975052) (xy 208.256015 -30.913631) (xy 208.203554 -30.846922)
			(xy 208.157672 -30.775528) (xy 208.118784 -30.700096) (xy 208.087242 -30.621308) (xy 208.063333 -30.53988)
			(xy 208.047272 -30.456547) (xy 208.039205 -30.372065) (xy 207.280767 -30.372065) (xy 207.2727 -30.456547)
			(xy 207.256639 -30.53988) (xy 207.23273 -30.621308) (xy 207.201188 -30.700096) (xy 207.1623 -30.775528)
			(xy 207.116418 -30.846922) (xy 207.063957 -30.913631) (xy 207.005393 -30.975052) (xy 206.941255 -31.030627)
			(xy 206.872125 -31.079855) (xy 206.798629 -31.122288) (xy 206.721431 -31.157543) (xy 206.641233 -31.1853)
			(xy 206.558759 -31.205308) (xy 206.474756 -31.217385) (xy 206.389986 -31.221424) (xy 206.305216 -31.217385)
			(xy 206.221213 -31.205308) (xy 206.138739 -31.1853) (xy 206.058541 -31.157543) (xy 205.981343 -31.122288)
			(xy 205.907847 -31.079855) (xy 205.838717 -31.030627) (xy 205.774579 -30.975052) (xy 205.716015 -30.913631)
			(xy 205.663554 -30.846922) (xy 205.617672 -30.775528) (xy 205.578784 -30.700096) (xy 205.547242 -30.621308)
			(xy 205.523333 -30.53988) (xy 205.507272 -30.456547) (xy 205.499205 -30.372065) (xy 203.852526 -30.372065)
			(xy 203.852526 -32.912065) (xy 205.499205 -32.912065) (xy 205.499205 -32.827199) (xy 205.507272 -32.742717)
			(xy 205.523333 -32.659384) (xy 205.547242 -32.577956) (xy 205.578784 -32.499168) (xy 205.617672 -32.423736)
			(xy 205.663554 -32.352342) (xy 205.716015 -32.285633) (xy 205.774579 -32.224212) (xy 205.838717 -32.168637)
			(xy 205.907847 -32.119409) (xy 205.981343 -32.076976) (xy 206.058541 -32.041721) (xy 206.138739 -32.013964)
			(xy 206.221213 -31.993956) (xy 206.305216 -31.981879) (xy 206.389986 -31.977841) (xy 206.474756 -31.981879)
			(xy 206.558759 -31.993956) (xy 206.641233 -32.013964) (xy 206.721431 -32.041721) (xy 206.798629 -32.076976)
			(xy 206.872125 -32.119409) (xy 206.941255 -32.168637) (xy 207.005393 -32.224212) (xy 207.063957 -32.285633)
			(xy 207.116418 -32.352342) (xy 207.1623 -32.423736) (xy 207.201188 -32.499168) (xy 207.23273 -32.577956)
			(xy 207.256639 -32.659384) (xy 207.2727 -32.742717) (xy 207.280767 -32.827199) (xy 207.281272 -32.869632)
			(xy 207.280767 -32.912065) (xy 208.039205 -32.912065) (xy 208.039205 -32.827199) (xy 208.047272 -32.742717)
			(xy 208.063333 -32.659384) (xy 208.087242 -32.577956) (xy 208.118784 -32.499168) (xy 208.157672 -32.423736)
			(xy 208.203554 -32.352342) (xy 208.256015 -32.285633) (xy 208.314579 -32.224212) (xy 208.378717 -32.168637)
			(xy 208.447847 -32.119409) (xy 208.521343 -32.076976) (xy 208.598541 -32.041721) (xy 208.678739 -32.013964)
			(xy 208.761213 -31.993956) (xy 208.845216 -31.981879) (xy 208.929986 -31.977841) (xy 209.014756 -31.981879)
			(xy 209.098759 -31.993956) (xy 209.181233 -32.013964) (xy 209.261431 -32.041721) (xy 209.338629 -32.076976)
			(xy 209.412125 -32.119409) (xy 209.481255 -32.168637) (xy 209.545393 -32.224212) (xy 209.603957 -32.285633)
			(xy 209.656418 -32.352342) (xy 209.7023 -32.423736) (xy 209.741188 -32.499168) (xy 209.77273 -32.577956)
			(xy 209.796639 -32.659384) (xy 209.8127 -32.742717) (xy 209.820767 -32.827199) (xy 209.821272 -32.869632)
			(xy 209.820767 -32.912065) (xy 210.579205 -32.912065) (xy 210.579205 -32.827199) (xy 210.587272 -32.742717)
			(xy 210.603333 -32.659384) (xy 210.627242 -32.577956) (xy 210.658784 -32.499168) (xy 210.697672 -32.423736)
			(xy 210.743554 -32.352342) (xy 210.796015 -32.285633) (xy 210.854579 -32.224212) (xy 210.918717 -32.168637)
			(xy 210.987847 -32.119409) (xy 211.061343 -32.076976) (xy 211.138541 -32.041721) (xy 211.218739 -32.013964)
			(xy 211.301213 -31.993956) (xy 211.385216 -31.981879) (xy 211.469986 -31.977841) (xy 211.554756 -31.981879)
			(xy 211.638759 -31.993956) (xy 211.721233 -32.013964) (xy 211.801431 -32.041721) (xy 211.878629 -32.076976)
			(xy 211.952125 -32.119409) (xy 212.021255 -32.168637) (xy 212.085393 -32.224212) (xy 212.143957 -32.285633)
			(xy 212.196418 -32.352342) (xy 212.2423 -32.423736) (xy 212.281188 -32.499168) (xy 212.31273 -32.577956)
			(xy 212.336639 -32.659384) (xy 212.3527 -32.742717) (xy 212.360767 -32.827199) (xy 212.361272 -32.869632)
			(xy 212.360767 -32.912065) (xy 212.3527 -32.996547) (xy 212.336639 -33.07988) (xy 212.31273 -33.161308)
			(xy 212.281188 -33.240096) (xy 212.2423 -33.315528) (xy 212.196418 -33.386922) (xy 212.143957 -33.453631)
			(xy 212.085393 -33.515052) (xy 212.021255 -33.570627) (xy 211.952125 -33.619855) (xy 211.878629 -33.662288)
			(xy 211.801431 -33.697543) (xy 211.721233 -33.7253) (xy 211.638759 -33.745308) (xy 211.554756 -33.757385)
			(xy 211.469986 -33.761424) (xy 211.385216 -33.757385) (xy 211.301213 -33.745308) (xy 211.218739 -33.7253)
			(xy 211.138541 -33.697543) (xy 211.061343 -33.662288) (xy 210.987847 -33.619855) (xy 210.918717 -33.570627)
			(xy 210.854579 -33.515052) (xy 210.796015 -33.453631) (xy 210.743554 -33.386922) (xy 210.697672 -33.315528)
			(xy 210.658784 -33.240096) (xy 210.627242 -33.161308) (xy 210.603333 -33.07988) (xy 210.587272 -32.996547)
			(xy 210.579205 -32.912065) (xy 209.820767 -32.912065) (xy 209.8127 -32.996547) (xy 209.796639 -33.07988)
			(xy 209.77273 -33.161308) (xy 209.741188 -33.240096) (xy 209.7023 -33.315528) (xy 209.656418 -33.386922)
			(xy 209.603957 -33.453631) (xy 209.545393 -33.515052) (xy 209.481255 -33.570627) (xy 209.412125 -33.619855)
			(xy 209.338629 -33.662288) (xy 209.261431 -33.697543) (xy 209.181233 -33.7253) (xy 209.098759 -33.745308)
			(xy 209.014756 -33.757385) (xy 208.929986 -33.761424) (xy 208.845216 -33.757385) (xy 208.761213 -33.745308)
			(xy 208.678739 -33.7253) (xy 208.598541 -33.697543) (xy 208.521343 -33.662288) (xy 208.447847 -33.619855)
			(xy 208.378717 -33.570627) (xy 208.314579 -33.515052) (xy 208.256015 -33.453631) (xy 208.203554 -33.386922)
			(xy 208.157672 -33.315528) (xy 208.118784 -33.240096) (xy 208.087242 -33.161308) (xy 208.063333 -33.07988)
			(xy 208.047272 -32.996547) (xy 208.039205 -32.912065) (xy 207.280767 -32.912065) (xy 207.2727 -32.996547)
			(xy 207.256639 -33.07988) (xy 207.23273 -33.161308) (xy 207.201188 -33.240096) (xy 207.1623 -33.315528)
			(xy 207.116418 -33.386922) (xy 207.063957 -33.453631) (xy 207.005393 -33.515052) (xy 206.941255 -33.570627)
			(xy 206.872125 -33.619855) (xy 206.798629 -33.662288) (xy 206.721431 -33.697543) (xy 206.641233 -33.7253)
			(xy 206.558759 -33.745308) (xy 206.474756 -33.757385) (xy 206.389986 -33.761424) (xy 206.305216 -33.757385)
			(xy 206.221213 -33.745308) (xy 206.138739 -33.7253) (xy 206.058541 -33.697543) (xy 205.981343 -33.662288)
			(xy 205.907847 -33.619855) (xy 205.838717 -33.570627) (xy 205.774579 -33.515052) (xy 205.716015 -33.453631)
			(xy 205.663554 -33.386922) (xy 205.617672 -33.315528) (xy 205.578784 -33.240096) (xy 205.547242 -33.161308)
			(xy 205.523333 -33.07988) (xy 205.507272 -32.996547) (xy 205.499205 -32.912065) (xy 203.852526 -32.912065)
			(xy 203.852526 -35.452065) (xy 208.039205 -35.452065) (xy 208.039205 -35.367199) (xy 208.047272 -35.282717)
			(xy 208.063333 -35.199384) (xy 208.087242 -35.117956) (xy 208.118784 -35.039168) (xy 208.157672 -34.963736)
			(xy 208.203554 -34.892342) (xy 208.256015 -34.825633) (xy 208.314579 -34.764212) (xy 208.378717 -34.708637)
			(xy 208.447847 -34.659409) (xy 208.521343 -34.616976) (xy 208.598541 -34.581721) (xy 208.678739 -34.553964)
			(xy 208.761213 -34.533956) (xy 208.845216 -34.521879) (xy 208.929986 -34.517841) (xy 209.014756 -34.521879)
			(xy 209.098759 -34.533956) (xy 209.181233 -34.553964) (xy 209.261431 -34.581721) (xy 209.338629 -34.616976)
			(xy 209.412125 -34.659409) (xy 209.481255 -34.708637) (xy 209.545393 -34.764212) (xy 209.603957 -34.825633)
			(xy 209.656418 -34.892342) (xy 209.7023 -34.963736) (xy 209.741188 -35.039168) (xy 209.77273 -35.117956)
			(xy 209.796639 -35.199384) (xy 209.8127 -35.282717) (xy 209.820767 -35.367199) (xy 209.821272 -35.409632)
			(xy 209.820767 -35.452065) (xy 210.579205 -35.452065) (xy 210.579205 -35.367199) (xy 210.587272 -35.282717)
			(xy 210.603333 -35.199384) (xy 210.627242 -35.117956) (xy 210.658784 -35.039168) (xy 210.697672 -34.963736)
			(xy 210.743554 -34.892342) (xy 210.796015 -34.825633) (xy 210.854579 -34.764212) (xy 210.918717 -34.708637)
			(xy 210.987847 -34.659409) (xy 211.061343 -34.616976) (xy 211.138541 -34.581721) (xy 211.218739 -34.553964)
			(xy 211.301213 -34.533956) (xy 211.385216 -34.521879) (xy 211.469986 -34.517841) (xy 211.554756 -34.521879)
			(xy 211.638759 -34.533956) (xy 211.721233 -34.553964) (xy 211.801431 -34.581721) (xy 211.878629 -34.616976)
			(xy 211.952125 -34.659409) (xy 212.021255 -34.708637) (xy 212.085393 -34.764212) (xy 212.143957 -34.825633)
			(xy 212.196418 -34.892342) (xy 212.2423 -34.963736) (xy 212.281188 -35.039168) (xy 212.31273 -35.117956)
			(xy 212.336639 -35.199384) (xy 212.3527 -35.282717) (xy 212.360767 -35.367199) (xy 212.361272 -35.409632)
			(xy 212.360767 -35.452065) (xy 212.3527 -35.536547) (xy 212.336639 -35.61988) (xy 212.31273 -35.701308)
			(xy 212.281188 -35.780096) (xy 212.2423 -35.855528) (xy 212.196418 -35.926922) (xy 212.143957 -35.993631)
			(xy 212.085393 -36.055052) (xy 212.021255 -36.110627) (xy 211.952125 -36.159855) (xy 211.878629 -36.202288)
			(xy 211.801431 -36.237543) (xy 211.721233 -36.2653) (xy 211.638759 -36.285308) (xy 211.554756 -36.297385)
			(xy 211.469986 -36.301424) (xy 211.385216 -36.297385) (xy 211.301213 -36.285308) (xy 211.218739 -36.2653)
			(xy 211.138541 -36.237543) (xy 211.061343 -36.202288) (xy 210.987847 -36.159855) (xy 210.918717 -36.110627)
			(xy 210.854579 -36.055052) (xy 210.796015 -35.993631) (xy 210.743554 -35.926922) (xy 210.697672 -35.855528)
			(xy 210.658784 -35.780096) (xy 210.627242 -35.701308) (xy 210.603333 -35.61988) (xy 210.587272 -35.536547)
			(xy 210.579205 -35.452065) (xy 209.820767 -35.452065) (xy 209.8127 -35.536547) (xy 209.796639 -35.61988)
			(xy 209.77273 -35.701308) (xy 209.741188 -35.780096) (xy 209.7023 -35.855528) (xy 209.656418 -35.926922)
			(xy 209.603957 -35.993631) (xy 209.545393 -36.055052) (xy 209.481255 -36.110627) (xy 209.412125 -36.159855)
			(xy 209.338629 -36.202288) (xy 209.261431 -36.237543) (xy 209.181233 -36.2653) (xy 209.098759 -36.285308)
			(xy 209.014756 -36.297385) (xy 208.929986 -36.301424) (xy 208.845216 -36.297385) (xy 208.761213 -36.285308)
			(xy 208.678739 -36.2653) (xy 208.598541 -36.237543) (xy 208.521343 -36.202288) (xy 208.447847 -36.159855)
			(xy 208.378717 -36.110627) (xy 208.314579 -36.055052) (xy 208.256015 -35.993631) (xy 208.203554 -35.926922)
			(xy 208.157672 -35.855528) (xy 208.118784 -35.780096) (xy 208.087242 -35.701308) (xy 208.063333 -35.61988)
			(xy 208.047272 -35.536547) (xy 208.039205 -35.452065) (xy 203.852526 -35.452065) (xy 203.852526 -37.992065)
			(xy 205.499205 -37.992065) (xy 205.499205 -37.907199) (xy 205.507272 -37.822717) (xy 205.523333 -37.739384)
			(xy 205.547242 -37.657956) (xy 205.578784 -37.579168) (xy 205.617672 -37.503736) (xy 205.663554 -37.432342)
			(xy 205.716015 -37.365633) (xy 205.774579 -37.304212) (xy 205.838717 -37.248637) (xy 205.907847 -37.199409)
			(xy 205.981343 -37.156976) (xy 206.058541 -37.121721) (xy 206.138739 -37.093964) (xy 206.221213 -37.073956)
			(xy 206.305216 -37.061879) (xy 206.389986 -37.057841) (xy 206.474756 -37.061879) (xy 206.558759 -37.073956)
			(xy 206.641233 -37.093964) (xy 206.721431 -37.121721) (xy 206.798629 -37.156976) (xy 206.872125 -37.199409)
			(xy 206.941255 -37.248637) (xy 207.005393 -37.304212) (xy 207.063957 -37.365633) (xy 207.116418 -37.432342)
			(xy 207.1623 -37.503736) (xy 207.201188 -37.579168) (xy 207.23273 -37.657956) (xy 207.256639 -37.739384)
			(xy 207.2727 -37.822717) (xy 207.280767 -37.907199) (xy 207.281272 -37.949632) (xy 207.280767 -37.992065)
			(xy 208.039205 -37.992065) (xy 208.039205 -37.907199) (xy 208.047272 -37.822717) (xy 208.063333 -37.739384)
			(xy 208.087242 -37.657956) (xy 208.118784 -37.579168) (xy 208.157672 -37.503736) (xy 208.203554 -37.432342)
			(xy 208.256015 -37.365633) (xy 208.314579 -37.304212) (xy 208.378717 -37.248637) (xy 208.447847 -37.199409)
			(xy 208.521343 -37.156976) (xy 208.598541 -37.121721) (xy 208.678739 -37.093964) (xy 208.761213 -37.073956)
			(xy 208.845216 -37.061879) (xy 208.929986 -37.057841) (xy 209.014756 -37.061879) (xy 209.098759 -37.073956)
			(xy 209.181233 -37.093964) (xy 209.261431 -37.121721) (xy 209.338629 -37.156976) (xy 209.412125 -37.199409)
			(xy 209.481255 -37.248637) (xy 209.545393 -37.304212) (xy 209.603957 -37.365633) (xy 209.656418 -37.432342)
			(xy 209.7023 -37.503736) (xy 209.741188 -37.579168) (xy 209.77273 -37.657956) (xy 209.796639 -37.739384)
			(xy 209.8127 -37.822717) (xy 209.820767 -37.907199) (xy 209.821272 -37.949632) (xy 209.820767 -37.992065)
			(xy 210.579205 -37.992065) (xy 210.579205 -37.907199) (xy 210.587272 -37.822717) (xy 210.603333 -37.739384)
			(xy 210.627242 -37.657956) (xy 210.658784 -37.579168) (xy 210.697672 -37.503736) (xy 210.743554 -37.432342)
			(xy 210.796015 -37.365633) (xy 210.854579 -37.304212) (xy 210.918717 -37.248637) (xy 210.987847 -37.199409)
			(xy 211.061343 -37.156976) (xy 211.138541 -37.121721) (xy 211.218739 -37.093964) (xy 211.301213 -37.073956)
			(xy 211.385216 -37.061879) (xy 211.469986 -37.057841) (xy 211.554756 -37.061879) (xy 211.638759 -37.073956)
			(xy 211.721233 -37.093964) (xy 211.801431 -37.121721) (xy 211.878629 -37.156976) (xy 211.952125 -37.199409)
			(xy 212.021255 -37.248637) (xy 212.085393 -37.304212) (xy 212.143957 -37.365633) (xy 212.196418 -37.432342)
			(xy 212.2423 -37.503736) (xy 212.281188 -37.579168) (xy 212.31273 -37.657956) (xy 212.336639 -37.739384)
			(xy 212.3527 -37.822717) (xy 212.360767 -37.907199) (xy 212.361272 -37.949632) (xy 212.360767 -37.992065)
			(xy 212.356685 -38.03481) (xy 245.302523 -38.03481) (xy 245.302523 -37.864454) (xy 245.310508 -37.694286)
			(xy 245.32646 -37.524679) (xy 245.350345 -37.356007) (xy 245.382109 -37.188639) (xy 245.421684 -37.022944)
			(xy 245.468981 -36.859286) (xy 245.523898 -36.698025) (xy 245.586313 -36.539515) (xy 245.656089 -36.384105)
			(xy 245.733072 -36.232137) (xy 245.817094 -36.083943) (xy 245.90797 -35.939851) (xy 246.0055 -35.800177)
			(xy 246.10947 -35.665228) (xy 246.219651 -35.5353) (xy 246.3358 -35.41068) (xy 246.457664 -35.291641)
			(xy 246.584972 -35.178445) (xy 246.717447 -35.07134) (xy 246.854797 -34.970563) (xy 246.996719 -34.876334)
			(xy 247.142901 -34.788861) (xy 247.293024 -34.708336) (xy 247.446755 -34.634936) (xy 247.603758 -34.568822)
			(xy 247.763688 -34.51014) (xy 247.926192 -34.459019) (xy 248.090913 -34.415571) (xy 248.257491 -34.379892)
			(xy 248.425557 -34.35206) (xy 248.594743 -34.332136) (xy 248.764677 -34.320164) (xy 248.934986 -34.316171)
			(xy 249.105295 -34.320164) (xy 249.275229 -34.332136) (xy 249.444415 -34.35206) (xy 249.612481 -34.379892)
			(xy 249.779059 -34.415571) (xy 249.94378 -34.459019) (xy 250.106284 -34.51014) (xy 250.266214 -34.568822)
			(xy 250.423217 -34.634936) (xy 250.576948 -34.708336) (xy 250.727071 -34.788861) (xy 250.873253 -34.876334)
			(xy 251.015175 -34.970563) (xy 251.152525 -35.07134) (xy 251.285 -35.178445) (xy 251.412308 -35.291641)
			(xy 251.534172 -35.41068) (xy 251.650321 -35.5353) (xy 251.760502 -35.665228) (xy 251.864472 -35.800177)
			(xy 251.962002 -35.939851) (xy 252.052878 -36.083943) (xy 252.1369 -36.232137) (xy 252.213883 -36.384105)
			(xy 252.283659 -36.539515) (xy 252.346074 -36.698025) (xy 252.400991 -36.859286) (xy 252.448288 -37.022944)
			(xy 252.487863 -37.188639) (xy 252.519627 -37.356007) (xy 252.543512 -37.524679) (xy 252.559464 -37.694286)
			(xy 252.567449 -37.864454) (xy 252.567948 -37.949632) (xy 252.567449 -38.03481) (xy 252.559464 -38.204978)
			(xy 252.543512 -38.374585) (xy 252.519627 -38.543257) (xy 252.487863 -38.710625) (xy 252.448288 -38.87632)
			(xy 252.400991 -39.039978) (xy 252.346074 -39.201239) (xy 252.283659 -39.359749) (xy 252.213883 -39.515159)
			(xy 252.1369 -39.667127) (xy 252.052878 -39.815321) (xy 251.962002 -39.959413) (xy 251.864472 -40.099087)
			(xy 251.760502 -40.234036) (xy 251.650321 -40.363964) (xy 251.534172 -40.488584) (xy 251.412308 -40.607623)
			(xy 251.285 -40.720819) (xy 251.152525 -40.827924) (xy 251.015175 -40.928701) (xy 250.873253 -41.02293)
			(xy 250.727071 -41.110403) (xy 250.576948 -41.190928) (xy 250.423217 -41.264328) (xy 250.266214 -41.330442)
			(xy 250.106284 -41.389124) (xy 249.94378 -41.440245) (xy 249.779059 -41.483693) (xy 249.612481 -41.519372)
			(xy 249.444415 -41.547204) (xy 249.275229 -41.567128) (xy 249.105295 -41.5791) (xy 248.934986 -41.583094)
			(xy 248.764677 -41.5791) (xy 248.594743 -41.567128) (xy 248.425557 -41.547204) (xy 248.257491 -41.519372)
			(xy 248.090913 -41.483693) (xy 247.926192 -41.440245) (xy 247.763688 -41.389124) (xy 247.603758 -41.330442)
			(xy 247.446755 -41.264328) (xy 247.293024 -41.190928) (xy 247.142901 -41.110403) (xy 246.996719 -41.02293)
			(xy 246.854797 -40.928701) (xy 246.717447 -40.827924) (xy 246.584972 -40.720819) (xy 246.457664 -40.607623)
			(xy 246.3358 -40.488584) (xy 246.219651 -40.363964) (xy 246.10947 -40.234036) (xy 246.0055 -40.099087)
			(xy 245.90797 -39.959413) (xy 245.817094 -39.815321) (xy 245.733072 -39.667127) (xy 245.656089 -39.515159)
			(xy 245.586313 -39.359749) (xy 245.523898 -39.201239) (xy 245.468981 -39.039978) (xy 245.421684 -38.87632)
			(xy 245.382109 -38.710625) (xy 245.350345 -38.543257) (xy 245.32646 -38.374585) (xy 245.310508 -38.204978)
			(xy 245.302523 -38.03481) (xy 212.356685 -38.03481) (xy 212.3527 -38.076547) (xy 212.336639 -38.15988)
			(xy 212.31273 -38.241308) (xy 212.281188 -38.320096) (xy 212.2423 -38.395528) (xy 212.196418 -38.466922)
			(xy 212.143957 -38.533631) (xy 212.085393 -38.595052) (xy 212.021255 -38.650627) (xy 211.952125 -38.699855)
			(xy 211.878629 -38.742288) (xy 211.801431 -38.777543) (xy 211.721233 -38.8053) (xy 211.638759 -38.825308)
			(xy 211.554756 -38.837385) (xy 211.469986 -38.841424) (xy 211.385216 -38.837385) (xy 211.301213 -38.825308)
			(xy 211.218739 -38.8053) (xy 211.138541 -38.777543) (xy 211.061343 -38.742288) (xy 210.987847 -38.699855)
			(xy 210.918717 -38.650627) (xy 210.854579 -38.595052) (xy 210.796015 -38.533631) (xy 210.743554 -38.466922)
			(xy 210.697672 -38.395528) (xy 210.658784 -38.320096) (xy 210.627242 -38.241308) (xy 210.603333 -38.15988)
			(xy 210.587272 -38.076547) (xy 210.579205 -37.992065) (xy 209.820767 -37.992065) (xy 209.8127 -38.076547)
			(xy 209.796639 -38.15988) (xy 209.77273 -38.241308) (xy 209.741188 -38.320096) (xy 209.7023 -38.395528)
			(xy 209.656418 -38.466922) (xy 209.603957 -38.533631) (xy 209.545393 -38.595052) (xy 209.481255 -38.650627)
			(xy 209.412125 -38.699855) (xy 209.338629 -38.742288) (xy 209.261431 -38.777543) (xy 209.181233 -38.8053)
			(xy 209.098759 -38.825308) (xy 209.014756 -38.837385) (xy 208.929986 -38.841424) (xy 208.845216 -38.837385)
			(xy 208.761213 -38.825308) (xy 208.678739 -38.8053) (xy 208.598541 -38.777543) (xy 208.521343 -38.742288)
			(xy 208.447847 -38.699855) (xy 208.378717 -38.650627) (xy 208.314579 -38.595052) (xy 208.256015 -38.533631)
			(xy 208.203554 -38.466922) (xy 208.157672 -38.395528) (xy 208.118784 -38.320096) (xy 208.087242 -38.241308)
			(xy 208.063333 -38.15988) (xy 208.047272 -38.076547) (xy 208.039205 -37.992065) (xy 207.280767 -37.992065)
			(xy 207.2727 -38.076547) (xy 207.256639 -38.15988) (xy 207.23273 -38.241308) (xy 207.201188 -38.320096)
			(xy 207.1623 -38.395528) (xy 207.116418 -38.466922) (xy 207.063957 -38.533631) (xy 207.005393 -38.595052)
			(xy 206.941255 -38.650627) (xy 206.872125 -38.699855) (xy 206.798629 -38.742288) (xy 206.721431 -38.777543)
			(xy 206.641233 -38.8053) (xy 206.558759 -38.825308) (xy 206.474756 -38.837385) (xy 206.389986 -38.841424)
			(xy 206.305216 -38.837385) (xy 206.221213 -38.825308) (xy 206.138739 -38.8053) (xy 206.058541 -38.777543)
			(xy 205.981343 -38.742288) (xy 205.907847 -38.699855) (xy 205.838717 -38.650627) (xy 205.774579 -38.595052)
			(xy 205.716015 -38.533631) (xy 205.663554 -38.466922) (xy 205.617672 -38.395528) (xy 205.578784 -38.320096)
			(xy 205.547242 -38.241308) (xy 205.523333 -38.15988) (xy 205.507272 -38.076547) (xy 205.499205 -37.992065)
			(xy 203.852526 -37.992065) (xy 203.852526 -45.444918) (xy 203.852953 -45.454986) (xy 203.860675 -45.473584)
			(xy 203.867512 -45.480986) (xy 204.344016 -45.95749) (xy 204.351415 -45.964335) (xy 204.370013 -45.972065)
			(xy 204.380084 -45.972476) (xy 212.457284 -45.972476) (xy 212.460078 -45.973492) (xy 212.586062 -45.973492)
			(xy 212.596127 -45.973926) (xy 212.614716 -45.981655) (xy 212.62213 -45.988478) (xy 212.707474 -46.073822)
			(xy 212.71611 -46.077378) (xy 212.813138 -46.177708) (xy 214.048848 -47.413672) (xy 214.063326 -47.42942)
			(xy 214.064342 -47.43069) (xy 214.234522 -47.60087) (xy 214.241366 -47.608269) (xy 214.249087 -47.626868)
			(xy 214.249508 -47.636938) (xy 214.249508 -47.883826) (xy 214.249762 -47.885604) (xy 214.250524 -47.899828)
			(xy 214.250524 -53.0606) (xy 218.972128 -53.0606) (xy 218.976201 -53.004941) (xy 218.988336 -52.950468)
			(xy 219.008272 -52.898342) (xy 219.035586 -52.849674) (xy 219.069694 -52.805502) (xy 219.109871 -52.766767)
			(xy 219.155259 -52.734295) (xy 219.204891 -52.708777) (xy 219.257711 -52.690758) (xy 219.31259 -52.680621)
			(xy 219.368361 -52.678583) (xy 219.423835 -52.684686) (xy 219.477828 -52.698802) (xy 219.529191 -52.720629)
			(xy 219.576829 -52.749702) (xy 219.619725 -52.785401) (xy 219.656967 -52.826965) (xy 219.687761 -52.873509)
			(xy 219.711449 -52.92404) (xy 219.727527 -52.977482) (xy 219.735653 -53.032696) (xy 219.736162 -53.0606)
			(xy 219.735653 -53.088504) (xy 219.727527 -53.143718) (xy 219.711449 -53.19716) (xy 219.687761 -53.247691)
			(xy 219.656967 -53.294235) (xy 219.619725 -53.335799) (xy 219.576829 -53.371498) (xy 219.529191 -53.400571)
			(xy 219.477828 -53.422398) (xy 219.423835 -53.436514) (xy 219.368361 -53.442617) (xy 219.31259 -53.440579)
			(xy 219.257711 -53.430442) (xy 219.204891 -53.412423) (xy 219.155259 -53.386905) (xy 219.109871 -53.354433)
			(xy 219.069694 -53.315698) (xy 219.035586 -53.271526) (xy 219.008272 -53.222858) (xy 218.988336 -53.170732)
			(xy 218.976201 -53.116259) (xy 218.972128 -53.0606) (xy 214.250524 -53.0606) (xy 214.250524 -63.6905)
			(xy 215.708482 -63.6905) (xy 215.712553 -63.634878) (xy 215.724679 -63.580441) (xy 215.744602 -63.52835)
			(xy 215.771898 -63.479715) (xy 215.805984 -63.435572) (xy 215.846133 -63.396863) (xy 215.891491 -63.364412)
			(xy 215.941091 -63.338911) (xy 215.993875 -63.320904) (xy 216.048718 -63.310774) (xy 216.104452 -63.308737)
			(xy 216.159889 -63.314837) (xy 216.213846 -63.328943) (xy 216.265175 -63.350755) (xy 216.312781 -63.379809)
			(xy 216.355649 -63.415484) (xy 216.392866 -63.457021) (xy 216.423639 -63.503534) (xy 216.447311 -63.554031)
			(xy 216.463379 -63.607438) (xy 216.471499 -63.662614) (xy 216.472008 -63.6905) (xy 216.471499 -63.718386)
			(xy 216.463379 -63.773562) (xy 216.447311 -63.826969) (xy 216.423639 -63.877466) (xy 216.392866 -63.923979)
			(xy 216.355649 -63.965516) (xy 216.312781 -64.001191) (xy 216.265175 -64.030245) (xy 216.213846 -64.052057)
			(xy 216.159889 -64.066163) (xy 216.104452 -64.072263) (xy 216.048718 -64.070226) (xy 215.993875 -64.060096)
			(xy 215.941091 -64.042089) (xy 215.891491 -64.016588) (xy 215.846133 -63.984137) (xy 215.805984 -63.945428)
			(xy 215.771898 -63.901285) (xy 215.744602 -63.85265) (xy 215.724679 -63.800559) (xy 215.712553 -63.746122)
			(xy 215.708482 -63.6905) (xy 214.250524 -63.6905) (xy 214.250524 -64.622172) (xy 214.249762 -64.636396)
			(xy 214.249508 -64.638174) (xy 214.249508 -64.885062) (xy 214.249074 -64.895127) (xy 214.241345 -64.913716)
			(xy 214.234522 -64.92113) (xy 214.064342 -65.09131) (xy 214.063326 -65.09258) (xy 214.048848 -65.108328)
			(xy 213.340442 -65.816734) (xy 213.33714 -65.820544) (xy 213.209632 -65.976754) (xy 213.203105 -65.984025)
			(xy 213.185994 -65.993425) (xy 213.176358 -65.995042) (xy 213.166452 -65.996312) (xy 213.157054 -66.001392)
			(xy 213.153939 -66.003188) (xy 213.1482 -66.00752) (xy 213.145624 -66.010028) (xy 212.537294 -66.618358)
			(xy 212.529897 -66.625208) (xy 212.511299 -66.632947) (xy 212.501226 -66.633344) (xy 204.635862 -66.633344)
			(xy 204.62799 -66.63364) (xy 204.612991 -66.638429) (xy 204.606398 -66.642742) (xy 204.574066 -66.665356)
			(xy 204.506084 -66.705412) (xy 204.43482 -66.739289) (xy 204.360835 -66.766719) (xy 204.284711 -66.787488)
			(xy 204.207047 -66.80143) (xy 204.128453 -66.808438) (xy 204.089 -66.808858) (xy 204.049548 -66.808419)
			(xy 203.970956 -66.801405) (xy 203.893294 -66.78746) (xy 203.817172 -66.766693) (xy 203.743188 -66.739267)
			(xy 203.671922 -66.705397) (xy 203.603936 -66.66535) (xy 203.571602 -66.642742) (xy 203.565017 -66.638413)
			(xy 203.550013 -66.633624) (xy 203.542138 -66.633344) (xy 177.301652 -66.633344) (xy 177.288952 -66.64071)
			(xy 177.288698 -66.640964) (xy 177.282727 -66.644243) (xy 177.269598 -66.647862) (xy 177.26279 -66.648076)
			(xy 86.113366 -66.648076) (xy 86.09457 -66.655696) (xy 86.087458 -66.663062) (xy 84.840771 -67.909749)
			(xy 90.062555 -67.909749) (xy 90.062555 -67.829883) (xy 90.070635 -67.750428) (xy 90.086712 -67.672198)
			(xy 90.110621 -67.595996) (xy 90.142116 -67.522603) (xy 90.180875 -67.452773) (xy 90.226499 -67.387223)
			(xy 90.278521 -67.326624) (xy 90.336406 -67.2716) (xy 90.399562 -67.222714) (xy 90.467339 -67.180468)
			(xy 90.539042 -67.145296) (xy 90.613936 -67.117559) (xy 90.691251 -67.09754) (xy 90.770195 -67.085447)
			(xy 90.849958 -67.081402) (xy 90.929721 -67.085447) (xy 91.008665 -67.09754) (xy 91.08598 -67.117559)
			(xy 91.160874 -67.145296) (xy 91.232577 -67.180468) (xy 91.300354 -67.222714) (xy 91.36351 -67.2716)
			(xy 91.421395 -67.326624) (xy 91.473417 -67.387223) (xy 91.519041 -67.452773) (xy 91.5578 -67.522603)
			(xy 91.589295 -67.595996) (xy 91.613204 -67.672198) (xy 91.629281 -67.750428) (xy 91.637361 -67.829883)
			(xy 91.637866 -67.869816) (xy 91.637361 -67.909749) (xy 92.062551 -67.909749) (xy 92.062551 -67.829883)
			(xy 92.070631 -67.750428) (xy 92.086708 -67.672198) (xy 92.110617 -67.595996) (xy 92.142112 -67.522603)
			(xy 92.180871 -67.452773) (xy 92.226495 -67.387223) (xy 92.278517 -67.326624) (xy 92.336402 -67.2716)
			(xy 92.399558 -67.222714) (xy 92.467335 -67.180468) (xy 92.539038 -67.145296) (xy 92.613932 -67.117559)
			(xy 92.691247 -67.09754) (xy 92.770191 -67.085447) (xy 92.849954 -67.081402) (xy 92.929717 -67.085447)
			(xy 93.008661 -67.09754) (xy 93.085976 -67.117559) (xy 93.16087 -67.145296) (xy 93.232573 -67.180468)
			(xy 93.30035 -67.222714) (xy 93.363506 -67.2716) (xy 93.421391 -67.326624) (xy 93.473413 -67.387223)
			(xy 93.519037 -67.452773) (xy 93.557796 -67.522603) (xy 93.589291 -67.595996) (xy 93.6132 -67.672198)
			(xy 93.629277 -67.750428) (xy 93.637357 -67.829883) (xy 93.637862 -67.869816) (xy 93.637357 -67.909749)
			(xy 94.062547 -67.909749) (xy 94.062547 -67.829883) (xy 94.070627 -67.750428) (xy 94.086704 -67.672198)
			(xy 94.110613 -67.595996) (xy 94.142108 -67.522603) (xy 94.180867 -67.452773) (xy 94.226491 -67.387223)
			(xy 94.278513 -67.326624) (xy 94.336398 -67.2716) (xy 94.399554 -67.222714) (xy 94.467331 -67.180468)
			(xy 94.539034 -67.145296) (xy 94.613928 -67.117559) (xy 94.691243 -67.09754) (xy 94.770187 -67.085447)
			(xy 94.84995 -67.081402) (xy 94.929713 -67.085447) (xy 95.008657 -67.09754) (xy 95.085972 -67.117559)
			(xy 95.160866 -67.145296) (xy 95.232569 -67.180468) (xy 95.300346 -67.222714) (xy 95.363502 -67.2716)
			(xy 95.421387 -67.326624) (xy 95.473409 -67.387223) (xy 95.519033 -67.452773) (xy 95.557792 -67.522603)
			(xy 95.589287 -67.595996) (xy 95.613196 -67.672198) (xy 95.629273 -67.750428) (xy 95.637353 -67.829883)
			(xy 95.637858 -67.869816) (xy 95.637353 -67.909749) (xy 96.062543 -67.909749) (xy 96.062543 -67.829883)
			(xy 96.070623 -67.750428) (xy 96.0867 -67.672198) (xy 96.110609 -67.595996) (xy 96.142104 -67.522603)
			(xy 96.180863 -67.452773) (xy 96.226487 -67.387223) (xy 96.278509 -67.326624) (xy 96.336394 -67.2716)
			(xy 96.39955 -67.222714) (xy 96.467327 -67.180468) (xy 96.53903 -67.145296) (xy 96.613924 -67.117559)
			(xy 96.691239 -67.09754) (xy 96.770183 -67.085447) (xy 96.849946 -67.081402) (xy 96.929709 -67.085447)
			(xy 97.008653 -67.09754) (xy 97.085968 -67.117559) (xy 97.160862 -67.145296) (xy 97.232565 -67.180468)
			(xy 97.300342 -67.222714) (xy 97.363498 -67.2716) (xy 97.421383 -67.326624) (xy 97.473405 -67.387223)
			(xy 97.519029 -67.452773) (xy 97.557788 -67.522603) (xy 97.589283 -67.595996) (xy 97.613192 -67.672198)
			(xy 97.629269 -67.750428) (xy 97.637349 -67.829883) (xy 97.637854 -67.869816) (xy 97.637349 -67.909749)
			(xy 98.062539 -67.909749) (xy 98.062539 -67.829883) (xy 98.070619 -67.750428) (xy 98.086696 -67.672198)
			(xy 98.110605 -67.595996) (xy 98.1421 -67.522603) (xy 98.180859 -67.452773) (xy 98.226483 -67.387223)
			(xy 98.278505 -67.326624) (xy 98.33639 -67.2716) (xy 98.399546 -67.222714) (xy 98.467323 -67.180468)
			(xy 98.539026 -67.145296) (xy 98.61392 -67.117559) (xy 98.691235 -67.09754) (xy 98.770179 -67.085447)
			(xy 98.849942 -67.081402) (xy 98.929705 -67.085447) (xy 99.008649 -67.09754) (xy 99.085964 -67.117559)
			(xy 99.160858 -67.145296) (xy 99.232561 -67.180468) (xy 99.300338 -67.222714) (xy 99.363494 -67.2716)
			(xy 99.421379 -67.326624) (xy 99.473401 -67.387223) (xy 99.519025 -67.452773) (xy 99.557784 -67.522603)
			(xy 99.589279 -67.595996) (xy 99.613188 -67.672198) (xy 99.629265 -67.750428) (xy 99.637345 -67.829883)
			(xy 99.63785 -67.869816) (xy 99.637345 -67.909749) (xy 100.062535 -67.909749) (xy 100.062535 -67.829883)
			(xy 100.070615 -67.750428) (xy 100.086692 -67.672198) (xy 100.110601 -67.595996) (xy 100.142096 -67.522603)
			(xy 100.180855 -67.452773) (xy 100.226479 -67.387223) (xy 100.278501 -67.326624) (xy 100.336386 -67.2716)
			(xy 100.399542 -67.222714) (xy 100.467319 -67.180468) (xy 100.539022 -67.145296) (xy 100.613916 -67.117559)
			(xy 100.691231 -67.09754) (xy 100.770175 -67.085447) (xy 100.849938 -67.081402) (xy 100.929701 -67.085447)
			(xy 101.008645 -67.09754) (xy 101.08596 -67.117559) (xy 101.160854 -67.145296) (xy 101.232557 -67.180468)
			(xy 101.300334 -67.222714) (xy 101.36349 -67.2716) (xy 101.421375 -67.326624) (xy 101.473397 -67.387223)
			(xy 101.519021 -67.452773) (xy 101.55778 -67.522603) (xy 101.589275 -67.595996) (xy 101.613184 -67.672198)
			(xy 101.629261 -67.750428) (xy 101.637341 -67.829883) (xy 101.637846 -67.869816) (xy 101.637679 -67.882992)
			(xy 102.061562 -67.882992) (xy 102.064201 -67.804016) (xy 102.074731 -67.7257) (xy 102.093049 -67.648832)
			(xy 102.118968 -67.574183) (xy 102.152229 -67.502503) (xy 102.192499 -67.434513) (xy 102.239371 -67.370896)
			(xy 102.292376 -67.312289) (xy 102.350982 -67.259283) (xy 102.414598 -67.212409) (xy 102.482587 -67.172138)
			(xy 102.554266 -67.138875) (xy 102.628914 -67.112954) (xy 102.705782 -67.094635) (xy 102.784098 -67.084102)
			(xy 102.863074 -67.081462) (xy 102.941919 -67.08674) (xy 103.019838 -67.099883) (xy 103.096051 -67.12076)
			(xy 103.169792 -67.149161) (xy 103.240319 -67.184801) (xy 103.306925 -67.227321) (xy 103.368939 -67.276294)
			(xy 103.425741 -67.331229) (xy 103.476758 -67.391574) (xy 103.521479 -67.456723) (xy 103.559454 -67.52602)
			(xy 103.590301 -67.598771) (xy 103.613712 -67.674244) (xy 103.629451 -67.751682) (xy 103.637359 -67.830306)
			(xy 103.637842 -67.869816) (xy 130.062224 -67.869816) (xy 130.062729 -67.829883) (xy 130.070809 -67.750428)
			(xy 130.086886 -67.672198) (xy 130.110795 -67.595996) (xy 130.14229 -67.522603) (xy 130.181049 -67.452773)
			(xy 130.226673 -67.387223) (xy 130.278695 -67.326624) (xy 130.33658 -67.2716) (xy 130.399736 -67.222714)
			(xy 130.467513 -67.180468) (xy 130.539216 -67.145296) (xy 130.61411 -67.117559) (xy 130.691425 -67.09754)
			(xy 130.770369 -67.085447) (xy 130.850132 -67.081402) (xy 130.929895 -67.085447) (xy 131.008839 -67.09754)
			(xy 131.086154 -67.117559) (xy 131.161048 -67.145296) (xy 131.232751 -67.180468) (xy 131.300528 -67.222714)
			(xy 131.363684 -67.2716) (xy 131.421569 -67.326624) (xy 131.473591 -67.387223) (xy 131.519215 -67.452773)
			(xy 131.557974 -67.522603) (xy 131.589469 -67.595996) (xy 131.613378 -67.672198) (xy 131.629455 -67.750428)
			(xy 131.637535 -67.829883) (xy 131.63804 -67.869816) (xy 131.637512 -67.909749) (xy 132.062725 -67.909749)
			(xy 132.062725 -67.829883) (xy 132.070805 -67.750428) (xy 132.086882 -67.672198) (xy 132.110791 -67.595996)
			(xy 132.142286 -67.522603) (xy 132.181045 -67.452773) (xy 132.226669 -67.387223) (xy 132.278691 -67.326624)
			(xy 132.336576 -67.2716) (xy 132.399732 -67.222714) (xy 132.467509 -67.180468) (xy 132.539212 -67.145296)
			(xy 132.614106 -67.117559) (xy 132.691421 -67.09754) (xy 132.770365 -67.085447) (xy 132.850128 -67.081402)
			(xy 132.929891 -67.085447) (xy 133.008835 -67.09754) (xy 133.08615 -67.117559) (xy 133.161044 -67.145296)
			(xy 133.232747 -67.180468) (xy 133.300524 -67.222714) (xy 133.36368 -67.2716) (xy 133.421565 -67.326624)
			(xy 133.473587 -67.387223) (xy 133.519211 -67.452773) (xy 133.55797 -67.522603) (xy 133.589465 -67.595996)
			(xy 133.613374 -67.672198) (xy 133.629451 -67.750428) (xy 133.637531 -67.829883) (xy 133.638036 -67.869816)
			(xy 133.637531 -67.909749) (xy 134.062721 -67.909749) (xy 134.062721 -67.829883) (xy 134.070801 -67.750428)
			(xy 134.086878 -67.672198) (xy 134.110787 -67.595996) (xy 134.142282 -67.522603) (xy 134.181041 -67.452773)
			(xy 134.226665 -67.387223) (xy 134.278687 -67.326624) (xy 134.336572 -67.2716) (xy 134.399728 -67.222714)
			(xy 134.467505 -67.180468) (xy 134.539208 -67.145296) (xy 134.614102 -67.117559) (xy 134.691417 -67.09754)
			(xy 134.770361 -67.085447) (xy 134.850124 -67.081402) (xy 134.929887 -67.085447) (xy 135.008831 -67.09754)
			(xy 135.086146 -67.117559) (xy 135.16104 -67.145296) (xy 135.232743 -67.180468) (xy 135.30052 -67.222714)
			(xy 135.363676 -67.2716) (xy 135.421561 -67.326624) (xy 135.473583 -67.387223) (xy 135.519207 -67.452773)
			(xy 135.557966 -67.522603) (xy 135.589461 -67.595996) (xy 135.61337 -67.672198) (xy 135.629447 -67.750428)
			(xy 135.637527 -67.829883) (xy 135.638032 -67.869816) (xy 135.637527 -67.909749) (xy 136.062717 -67.909749)
			(xy 136.062717 -67.829883) (xy 136.070797 -67.750428) (xy 136.086874 -67.672198) (xy 136.110783 -67.595996)
			(xy 136.142278 -67.522603) (xy 136.181037 -67.452773) (xy 136.226661 -67.387223) (xy 136.278683 -67.326624)
			(xy 136.336568 -67.2716) (xy 136.399724 -67.222714) (xy 136.467501 -67.180468) (xy 136.539204 -67.145296)
			(xy 136.614098 -67.117559) (xy 136.691413 -67.09754) (xy 136.770357 -67.085447) (xy 136.85012 -67.081402)
			(xy 136.929883 -67.085447) (xy 137.008827 -67.09754) (xy 137.086142 -67.117559) (xy 137.161036 -67.145296)
			(xy 137.232739 -67.180468) (xy 137.300516 -67.222714) (xy 137.363672 -67.2716) (xy 137.421557 -67.326624)
			(xy 137.473579 -67.387223) (xy 137.519203 -67.452773) (xy 137.557962 -67.522603) (xy 137.589457 -67.595996)
			(xy 137.613366 -67.672198) (xy 137.629443 -67.750428) (xy 137.637523 -67.829883) (xy 137.638028 -67.869816)
			(xy 137.637523 -67.909749) (xy 138.062713 -67.909749) (xy 138.062713 -67.829883) (xy 138.070793 -67.750428)
			(xy 138.08687 -67.672198) (xy 138.110779 -67.595996) (xy 138.142274 -67.522603) (xy 138.181033 -67.452773)
			(xy 138.226657 -67.387223) (xy 138.278679 -67.326624) (xy 138.336564 -67.2716) (xy 138.39972 -67.222714)
			(xy 138.467497 -67.180468) (xy 138.5392 -67.145296) (xy 138.614094 -67.117559) (xy 138.691409 -67.09754)
			(xy 138.770353 -67.085447) (xy 138.850116 -67.081402) (xy 138.929879 -67.085447) (xy 139.008823 -67.09754)
			(xy 139.086138 -67.117559) (xy 139.161032 -67.145296) (xy 139.232735 -67.180468) (xy 139.300512 -67.222714)
			(xy 139.363668 -67.2716) (xy 139.421553 -67.326624) (xy 139.473575 -67.387223) (xy 139.519199 -67.452773)
			(xy 139.557958 -67.522603) (xy 139.589453 -67.595996) (xy 139.613362 -67.672198) (xy 139.629439 -67.750428)
			(xy 139.637519 -67.829883) (xy 139.638024 -67.869816) (xy 139.637519 -67.909749) (xy 140.062709 -67.909749)
			(xy 140.062709 -67.829883) (xy 140.070789 -67.750428) (xy 140.086866 -67.672198) (xy 140.110775 -67.595996)
			(xy 140.14227 -67.522603) (xy 140.181029 -67.452773) (xy 140.226653 -67.387223) (xy 140.278675 -67.326624)
			(xy 140.33656 -67.2716) (xy 140.399716 -67.222714) (xy 140.467493 -67.180468) (xy 140.539196 -67.145296)
			(xy 140.61409 -67.117559) (xy 140.691405 -67.09754) (xy 140.770349 -67.085447) (xy 140.850112 -67.081402)
			(xy 140.929875 -67.085447) (xy 141.008819 -67.09754) (xy 141.086134 -67.117559) (xy 141.161028 -67.145296)
			(xy 141.232731 -67.180468) (xy 141.300508 -67.222714) (xy 141.363664 -67.2716) (xy 141.421549 -67.326624)
			(xy 141.473571 -67.387223) (xy 141.519195 -67.452773) (xy 141.557954 -67.522603) (xy 141.589449 -67.595996)
			(xy 141.613358 -67.672198) (xy 141.629435 -67.750428) (xy 141.637515 -67.829883) (xy 141.63802 -67.869816)
			(xy 141.637853 -67.883008) (xy 142.059755 -67.883008) (xy 142.062402 -67.803831) (xy 142.072961 -67.725317)
			(xy 142.091326 -67.648254) (xy 142.117313 -67.573416) (xy 142.15066 -67.501555) (xy 142.191033 -67.433394)
			(xy 142.238026 -67.369615) (xy 142.291166 -67.310861) (xy 142.349921 -67.257721) (xy 142.4137 -67.210729)
			(xy 142.481863 -67.170357) (xy 142.553724 -67.13701) (xy 142.628562 -67.111024) (xy 142.705625 -67.09266)
			(xy 142.784139 -67.082101) (xy 142.863316 -67.079455) (xy 142.942361 -67.084747) (xy 143.020478 -67.097925)
			(xy 143.096884 -67.118856) (xy 143.170812 -67.147329) (xy 143.241518 -67.18306) (xy 143.308292 -67.225688)
			(xy 143.370464 -67.274787) (xy 143.427409 -67.329861) (xy 143.478556 -67.39036) (xy 143.52339 -67.455674)
			(xy 143.561461 -67.525147) (xy 143.592387 -67.598083) (xy 143.615857 -67.673748) (xy 143.631635 -67.751382)
			(xy 143.639563 -67.830205) (xy 143.640048 -67.869816) (xy 143.639625 -67.906368) (xy 143.639311 -67.909749)
			(xy 170.062903 -67.909749) (xy 170.062903 -67.829883) (xy 170.070983 -67.750428) (xy 170.08706 -67.672198)
			(xy 170.110969 -67.595996) (xy 170.142464 -67.522603) (xy 170.181223 -67.452773) (xy 170.226847 -67.387223)
			(xy 170.278869 -67.326624) (xy 170.336754 -67.2716) (xy 170.39991 -67.222714) (xy 170.467687 -67.180468)
			(xy 170.53939 -67.145296) (xy 170.614284 -67.117559) (xy 170.691599 -67.09754) (xy 170.770543 -67.085447)
			(xy 170.850306 -67.081402) (xy 170.930069 -67.085447) (xy 171.009013 -67.09754) (xy 171.086328 -67.117559)
			(xy 171.161222 -67.145296) (xy 171.232925 -67.180468) (xy 171.300702 -67.222714) (xy 171.363858 -67.2716)
			(xy 171.421743 -67.326624) (xy 171.473765 -67.387223) (xy 171.519389 -67.452773) (xy 171.558148 -67.522603)
			(xy 171.589643 -67.595996) (xy 171.613552 -67.672198) (xy 171.629629 -67.750428) (xy 171.637709 -67.829883)
			(xy 171.638214 -67.869816) (xy 171.637709 -67.909749) (xy 172.062899 -67.909749) (xy 172.062899 -67.829883)
			(xy 172.070979 -67.750428) (xy 172.087056 -67.672198) (xy 172.110965 -67.595996) (xy 172.14246 -67.522603)
			(xy 172.181219 -67.452773) (xy 172.226843 -67.387223) (xy 172.278865 -67.326624) (xy 172.33675 -67.2716)
			(xy 172.399906 -67.222714) (xy 172.467683 -67.180468) (xy 172.539386 -67.145296) (xy 172.61428 -67.117559)
			(xy 172.691595 -67.09754) (xy 172.770539 -67.085447) (xy 172.850302 -67.081402) (xy 172.930065 -67.085447)
			(xy 173.009009 -67.09754) (xy 173.086324 -67.117559) (xy 173.161218 -67.145296) (xy 173.232921 -67.180468)
			(xy 173.300698 -67.222714) (xy 173.363854 -67.2716) (xy 173.421739 -67.326624) (xy 173.473761 -67.387223)
			(xy 173.519385 -67.452773) (xy 173.558144 -67.522603) (xy 173.589639 -67.595996) (xy 173.613548 -67.672198)
			(xy 173.629625 -67.750428) (xy 173.637705 -67.829883) (xy 173.63821 -67.869816) (xy 173.637705 -67.909749)
			(xy 174.062895 -67.909749) (xy 174.062895 -67.829883) (xy 174.070975 -67.750428) (xy 174.087052 -67.672198)
			(xy 174.110961 -67.595996) (xy 174.142456 -67.522603) (xy 174.181215 -67.452773) (xy 174.226839 -67.387223)
			(xy 174.278861 -67.326624) (xy 174.336746 -67.2716) (xy 174.399902 -67.222714) (xy 174.467679 -67.180468)
			(xy 174.539382 -67.145296) (xy 174.614276 -67.117559) (xy 174.691591 -67.09754) (xy 174.770535 -67.085447)
			(xy 174.850298 -67.081402) (xy 174.930061 -67.085447) (xy 175.009005 -67.09754) (xy 175.08632 -67.117559)
			(xy 175.161214 -67.145296) (xy 175.232917 -67.180468) (xy 175.300694 -67.222714) (xy 175.36385 -67.2716)
			(xy 175.421735 -67.326624) (xy 175.473757 -67.387223) (xy 175.519381 -67.452773) (xy 175.55814 -67.522603)
			(xy 175.589635 -67.595996) (xy 175.613544 -67.672198) (xy 175.629621 -67.750428) (xy 175.637701 -67.829883)
			(xy 175.638206 -67.869816) (xy 175.637701 -67.909749) (xy 176.062891 -67.909749) (xy 176.062891 -67.829883)
			(xy 176.070971 -67.750428) (xy 176.087048 -67.672198) (xy 176.110957 -67.595996) (xy 176.142452 -67.522603)
			(xy 176.181211 -67.452773) (xy 176.226835 -67.387223) (xy 176.278857 -67.326624) (xy 176.336742 -67.2716)
			(xy 176.399898 -67.222714) (xy 176.467675 -67.180468) (xy 176.539378 -67.145296) (xy 176.614272 -67.117559)
			(xy 176.691587 -67.09754) (xy 176.770531 -67.085447) (xy 176.850294 -67.081402) (xy 176.930057 -67.085447)
			(xy 177.009001 -67.09754) (xy 177.086316 -67.117559) (xy 177.16121 -67.145296) (xy 177.232913 -67.180468)
			(xy 177.30069 -67.222714) (xy 177.363846 -67.2716) (xy 177.421731 -67.326624) (xy 177.473753 -67.387223)
			(xy 177.519377 -67.452773) (xy 177.558136 -67.522603) (xy 177.589631 -67.595996) (xy 177.61354 -67.672198)
			(xy 177.629617 -67.750428) (xy 177.637697 -67.829883) (xy 177.638202 -67.869816) (xy 177.637697 -67.909749)
			(xy 178.062887 -67.909749) (xy 178.062887 -67.829883) (xy 178.070967 -67.750428) (xy 178.087044 -67.672198)
			(xy 178.110953 -67.595996) (xy 178.142448 -67.522603) (xy 178.181207 -67.452773) (xy 178.226831 -67.387223)
			(xy 178.278853 -67.326624) (xy 178.336738 -67.2716) (xy 178.399894 -67.222714) (xy 178.467671 -67.180468)
			(xy 178.539374 -67.145296) (xy 178.614268 -67.117559) (xy 178.691583 -67.09754) (xy 178.770527 -67.085447)
			(xy 178.85029 -67.081402) (xy 178.930053 -67.085447) (xy 179.008997 -67.09754) (xy 179.086312 -67.117559)
			(xy 179.161206 -67.145296) (xy 179.232909 -67.180468) (xy 179.300686 -67.222714) (xy 179.363842 -67.2716)
			(xy 179.421727 -67.326624) (xy 179.473749 -67.387223) (xy 179.519373 -67.452773) (xy 179.558132 -67.522603)
			(xy 179.589627 -67.595996) (xy 179.613536 -67.672198) (xy 179.629613 -67.750428) (xy 179.637693 -67.829883)
			(xy 179.638198 -67.869816) (xy 179.637693 -67.909749) (xy 180.062883 -67.909749) (xy 180.062883 -67.829883)
			(xy 180.070963 -67.750428) (xy 180.08704 -67.672198) (xy 180.110949 -67.595996) (xy 180.142444 -67.522603)
			(xy 180.181203 -67.452773) (xy 180.226827 -67.387223) (xy 180.278849 -67.326624) (xy 180.336734 -67.2716)
			(xy 180.39989 -67.222714) (xy 180.467667 -67.180468) (xy 180.53937 -67.145296) (xy 180.614264 -67.117559)
			(xy 180.691579 -67.09754) (xy 180.770523 -67.085447) (xy 180.850286 -67.081402) (xy 180.930049 -67.085447)
			(xy 181.008993 -67.09754) (xy 181.086308 -67.117559) (xy 181.161202 -67.145296) (xy 181.232905 -67.180468)
			(xy 181.300682 -67.222714) (xy 181.363838 -67.2716) (xy 181.421723 -67.326624) (xy 181.473745 -67.387223)
			(xy 181.519369 -67.452773) (xy 181.558128 -67.522603) (xy 181.589623 -67.595996) (xy 181.613532 -67.672198)
			(xy 181.629609 -67.750428) (xy 181.637689 -67.829883) (xy 181.638194 -67.869816) (xy 181.638027 -67.882991)
			(xy 182.059981 -67.882991) (xy 182.062629 -67.803817) (xy 182.07319 -67.725306) (xy 182.091556 -67.648246)
			(xy 182.117543 -67.573412) (xy 182.15089 -67.501555) (xy 182.191262 -67.433396) (xy 182.238254 -67.369621)
			(xy 182.291394 -67.31087) (xy 182.350147 -67.257733) (xy 182.413924 -67.210744) (xy 182.482085 -67.170374)
			(xy 182.553943 -67.13703) (xy 182.628779 -67.111046) (xy 182.705839 -67.092684) (xy 182.784351 -67.082127)
			(xy 182.863525 -67.079481) (xy 182.942566 -67.084774) (xy 183.02068 -67.097952) (xy 183.097083 -67.118883)
			(xy 183.171007 -67.147356) (xy 183.24171 -67.183085) (xy 183.308481 -67.225713) (xy 183.370651 -67.274809)
			(xy 183.427593 -67.329882) (xy 183.450296 -67.356736) (xy 198.970898 -67.356736) (xy 198.974971 -67.301077)
			(xy 198.987106 -67.246604) (xy 199.007042 -67.194478) (xy 199.034356 -67.14581) (xy 199.068464 -67.101638)
			(xy 199.108641 -67.062903) (xy 199.154029 -67.030431) (xy 199.203661 -67.004913) (xy 199.256481 -66.986894)
			(xy 199.31136 -66.976757) (xy 199.367131 -66.974719) (xy 199.422605 -66.980822) (xy 199.476598 -66.994938)
			(xy 199.527961 -67.016765) (xy 199.575599 -67.045838) (xy 199.618495 -67.081537) (xy 199.655737 -67.123101)
			(xy 199.686531 -67.169645) (xy 199.710219 -67.220176) (xy 199.726297 -67.273618) (xy 199.734423 -67.328832)
			(xy 199.734932 -67.356736) (xy 199.734423 -67.38464) (xy 199.726297 -67.439854) (xy 199.710219 -67.493296)
			(xy 199.686531 -67.543827) (xy 199.676713 -67.558666) (xy 201.522582 -67.558666) (xy 201.526653 -67.503044)
			(xy 201.538779 -67.448607) (xy 201.558702 -67.396516) (xy 201.585998 -67.347881) (xy 201.620084 -67.303738)
			(xy 201.660233 -67.265029) (xy 201.705591 -67.232578) (xy 201.755191 -67.207077) (xy 201.807975 -67.18907)
			(xy 201.862818 -67.17894) (xy 201.918552 -67.176903) (xy 201.973989 -67.183003) (xy 202.027946 -67.197109)
			(xy 202.079275 -67.218921) (xy 202.126881 -67.247975) (xy 202.169749 -67.28365) (xy 202.206966 -67.325187)
			(xy 202.209522 -67.32905) (xy 204.341982 -67.32905) (xy 204.346053 -67.273428) (xy 204.358179 -67.218991)
			(xy 204.378102 -67.1669) (xy 204.405398 -67.118265) (xy 204.439484 -67.074122) (xy 204.479633 -67.035413)
			(xy 204.524991 -67.002962) (xy 204.574591 -66.977461) (xy 204.627375 -66.959454) (xy 204.682218 -66.949324)
			(xy 204.737952 -66.947287) (xy 204.793389 -66.953387) (xy 204.847346 -66.967493) (xy 204.898675 -66.989305)
			(xy 204.946281 -67.018359) (xy 204.989149 -67.054034) (xy 205.026366 -67.095571) (xy 205.057139 -67.142084)
			(xy 205.080811 -67.192581) (xy 205.096879 -67.245988) (xy 205.104999 -67.301164) (xy 205.105508 -67.32905)
			(xy 205.104999 -67.356936) (xy 205.096879 -67.412112) (xy 205.080811 -67.465519) (xy 205.057139 -67.516016)
			(xy 205.026366 -67.562529) (xy 204.989149 -67.604066) (xy 204.946281 -67.639741) (xy 204.898675 -67.668795)
			(xy 204.847346 -67.690607) (xy 204.793389 -67.704713) (xy 204.737952 -67.710813) (xy 204.682218 -67.708776)
			(xy 204.627375 -67.698646) (xy 204.574591 -67.680639) (xy 204.524991 -67.655138) (xy 204.479633 -67.622687)
			(xy 204.439484 -67.583978) (xy 204.405398 -67.539835) (xy 204.378102 -67.4912) (xy 204.358179 -67.439109)
			(xy 204.346053 -67.384672) (xy 204.341982 -67.32905) (xy 202.209522 -67.32905) (xy 202.237739 -67.3717)
			(xy 202.261411 -67.422197) (xy 202.277479 -67.475604) (xy 202.285599 -67.53078) (xy 202.286108 -67.558666)
			(xy 202.285599 -67.586552) (xy 202.277479 -67.641728) (xy 202.261411 -67.695135) (xy 202.237739 -67.745632)
			(xy 202.206966 -67.792145) (xy 202.169749 -67.833682) (xy 202.126881 -67.869357) (xy 202.079275 -67.898411)
			(xy 202.027946 -67.920223) (xy 201.973989 -67.934329) (xy 201.918552 -67.940429) (xy 201.862818 -67.938392)
			(xy 201.807975 -67.928262) (xy 201.755191 -67.910255) (xy 201.705591 -67.884754) (xy 201.660233 -67.852303)
			(xy 201.620084 -67.813594) (xy 201.585998 -67.769451) (xy 201.558702 -67.720816) (xy 201.538779 -67.668725)
			(xy 201.526653 -67.614288) (xy 201.522582 -67.558666) (xy 199.676713 -67.558666) (xy 199.655737 -67.590371)
			(xy 199.618495 -67.631935) (xy 199.575599 -67.667634) (xy 199.527961 -67.696707) (xy 199.476598 -67.718534)
			(xy 199.422605 -67.73265) (xy 199.367131 -67.738753) (xy 199.31136 -67.736715) (xy 199.256481 -67.726578)
			(xy 199.203661 -67.708559) (xy 199.154029 -67.683041) (xy 199.108641 -67.650569) (xy 199.068464 -67.611834)
			(xy 199.034356 -67.567662) (xy 199.007042 -67.518994) (xy 198.987106 -67.466868) (xy 198.974971 -67.412395)
			(xy 198.970898 -67.356736) (xy 183.450296 -67.356736) (xy 183.478737 -67.390378) (xy 183.523569 -67.45569)
			(xy 183.561639 -67.525161) (xy 183.592563 -67.598094) (xy 183.616032 -67.673756) (xy 183.631809 -67.751387)
			(xy 183.639737 -67.830207) (xy 183.640222 -67.869816) (xy 183.639802 -67.906369) (xy 183.633051 -67.979161)
			(xy 183.6196 -68.051018) (xy 183.599564 -68.121324) (xy 183.573114 -68.189477) (xy 183.557164 -68.222368)
			(xy 183.557164 -68.245736) (xy 183.557519 -68.255116) (xy 183.564313 -68.272602) (xy 183.570372 -68.279772)
			(xy 183.6293 -68.344288) (xy 183.636515 -68.351454) (xy 183.654965 -68.359958) (xy 183.675268 -68.360675)
			(xy 183.684926 -68.357496) (xy 183.747619 -68.334043) (xy 183.875322 -68.293882) (xy 184.005232 -68.261565)
			(xy 184.136867 -68.237213) (xy 184.269741 -68.220916) (xy 184.40336 -68.212734) (xy 184.470294 -68.212208)
			(xy 184.537211 -68.212721) (xy 184.670798 -68.220866) (xy 184.803642 -68.237125) (xy 184.93525 -68.261439)
			(xy 185.065134 -68.293717) (xy 185.192813 -68.33384) (xy 185.317814 -68.381659) (xy 185.439672 -68.436997)
			(xy 185.557937 -68.499649) (xy 185.67217 -68.569381) (xy 185.781947 -68.645937) (xy 185.886862 -68.729031)
			(xy 185.986526 -68.818356) (xy 186.080568 -68.913581) (xy 186.168641 -69.014353) (xy 186.250418 -69.120298)
			(xy 186.288426 -69.175376) (xy 186.29122 -69.17944) (xy 186.298586 -69.186806) (xy 186.305996 -69.193633)
			(xy 186.324588 -69.20136) (xy 186.334654 -69.201792) (xy 186.415934 -69.201792) (xy 186.426005 -69.201386)
			(xy 186.444603 -69.193652) (xy 186.452002 -69.186806) (xy 186.459368 -69.17944) (xy 186.462162 -69.175376)
			(xy 186.500174 -69.1203) (xy 186.58195 -69.014355) (xy 186.670023 -68.913583) (xy 186.764065 -68.818357)
			(xy 186.863728 -68.729032) (xy 186.968642 -68.645937) (xy 187.078419 -68.569381) (xy 187.192652 -68.499648)
			(xy 187.310917 -68.436996) (xy 187.432775 -68.381658) (xy 187.557775 -68.333838) (xy 187.685454 -68.293715)
			(xy 187.815338 -68.261436) (xy 187.946946 -68.237121) (xy 188.07979 -68.220861) (xy 188.213377 -68.212716)
			(xy 188.280294 -68.212208) (xy 188.346684 -68.212667) (xy 188.479223 -68.220684) (xy 188.611036 -68.236689)
			(xy 188.741642 -68.260623) (xy 188.870565 -68.292399) (xy 188.997333 -68.331901) (xy 189.121486 -68.378986)
			(xy 189.242569 -68.433481) (xy 189.360141 -68.495187) (xy 189.473772 -68.563879) (xy 189.583049 -68.639307)
			(xy 189.677559 -68.71335) (xy 206.881982 -68.71335) (xy 206.886053 -68.657728) (xy 206.898179 -68.603291)
			(xy 206.918102 -68.5512) (xy 206.945398 -68.502565) (xy 206.979484 -68.458422) (xy 207.019633 -68.419713)
			(xy 207.064991 -68.387262) (xy 207.114591 -68.361761) (xy 207.167375 -68.343754) (xy 207.222218 -68.333624)
			(xy 207.277952 -68.331587) (xy 207.333389 -68.337687) (xy 207.387346 -68.351793) (xy 207.438675 -68.373605)
			(xy 207.486281 -68.402659) (xy 207.529149 -68.438334) (xy 207.566366 -68.479871) (xy 207.597139 -68.526384)
			(xy 207.620811 -68.576881) (xy 207.636879 -68.630288) (xy 207.644999 -68.685464) (xy 207.645508 -68.71335)
			(xy 207.645012 -68.740548) (xy 208.153028 -68.740548) (xy 208.153028 -68.686052) (xy 208.160784 -68.632112)
			(xy 208.176137 -68.579824) (xy 208.198775 -68.530253) (xy 208.228237 -68.484409) (xy 208.263924 -68.443224)
			(xy 208.305109 -68.407537) (xy 208.350953 -68.378075) (xy 208.400524 -68.355437) (xy 208.452812 -68.340084)
			(xy 208.506752 -68.332328) (xy 208.534 -68.331842) (xy 208.534254 -68.331842) (xy 208.564051 -68.332447)
			(xy 208.62292 -68.341719) (xy 208.679632 -68.360029) (xy 208.732808 -68.386931) (xy 208.781156 -68.421773)
			(xy 208.802732 -68.442332) (xy 208.802986 -68.442586) (xy 208.812483 -68.450921) (xy 208.836747 -68.457855)
			(xy 208.849214 -68.455794) (xy 208.932526 -68.437506) (xy 208.938751 -68.435957) (xy 208.950196 -68.430173)
			(xy 208.955132 -68.426076) (xy 208.960212 -68.421758) (xy 208.96707 -68.411598) (xy 208.969356 -68.405502)
			(xy 208.984207 -68.366575) (xy 209.020232 -68.291442) (xy 209.063125 -68.220007) (xy 209.11251 -68.152896)
			(xy 209.167955 -68.090698) (xy 209.228973 -68.033957) (xy 209.29503 -67.98317) (xy 209.365546 -67.938784)
			(xy 209.439905 -67.901186) (xy 209.517453 -67.870706) (xy 209.597512 -67.847612) (xy 209.679379 -67.832106)
			(xy 209.762338 -67.824323) (xy 209.804 -67.823842) (xy 209.843738 -67.824255) (xy 209.922898 -67.831348)
			(xy 210.001109 -67.845476) (xy 210.077747 -67.866527) (xy 210.152201 -67.894333) (xy 210.223877 -67.928672)
			(xy 210.292202 -67.96927) (xy 210.356632 -68.015803) (xy 210.38693 -68.04152) (xy 210.389978 -68.04406)
			(xy 210.394296 -68.046854) (xy 210.400482 -68.050307) (xy 210.414138 -68.054052) (xy 210.42122 -68.05422)
			(xy 210.460082 -68.053966) (xy 210.476846 -68.047616) (xy 210.483958 -68.041266) (xy 210.514439 -68.014861)
			(xy 210.579399 -67.967064) (xy 210.648418 -67.925341) (xy 210.72093 -67.890035) (xy 210.796339 -67.861437)
			(xy 210.874027 -67.83978) (xy 210.953356 -67.825243) (xy 211.033675 -67.817944) (xy 211.074 -67.817492)
			(xy 211.074508 -67.817492) (xy 211.113469 -67.81792) (xy 211.191091 -67.824769) (xy 211.267817 -67.838378)
			(xy 211.343059 -67.858644) (xy 211.416241 -67.885412) (xy 211.451698 -67.901566) (xy 211.45964 -67.904944)
			(xy 211.476794 -67.906724) (xy 211.493559 -67.902679) (xy 211.500974 -67.898264) (xy 211.524302 -67.883664)
			(xy 211.574265 -67.860596) (xy 211.627024 -67.844945) (xy 211.681484 -67.837038) (xy 211.736516 -67.837038)
			(xy 211.790976 -67.844945) (xy 211.843735 -67.860596) (xy 211.893698 -67.883664) (xy 211.917026 -67.898264)
			(xy 211.924471 -67.902611) (xy 211.941219 -67.906637) (xy 211.958358 -67.904909) (xy 211.966302 -67.901566)
			(xy 212.00178 -67.885395) (xy 212.075009 -67.858607) (xy 212.150303 -67.838334) (xy 212.227083 -67.824734)
			(xy 212.304758 -67.817909) (xy 212.343746 -67.817492) (xy 212.344254 -67.817492) (xy 212.384285 -67.817917)
			(xy 212.464021 -67.82513) (xy 212.542787 -67.839475) (xy 212.619946 -67.860835) (xy 212.694876 -67.889038)
			(xy 212.766969 -67.923856) (xy 212.835645 -67.965008) (xy 212.900348 -68.012161) (xy 212.93074 -68.038218)
			(xy 212.937852 -68.044568) (xy 212.95487 -68.050918) (xy 213.00313 -68.050918) (xy 213.020148 -68.044568)
			(xy 213.02726 -68.038218) (xy 213.057661 -68.01217) (xy 213.122352 -67.965) (xy 213.191022 -67.923836)
			(xy 213.263114 -67.889011) (xy 213.338044 -67.860807) (xy 213.415207 -67.839453) (xy 213.493976 -67.825122)
			(xy 213.573715 -67.817929) (xy 213.613746 -67.817492) (xy 213.614254 -67.817492) (xy 213.653241 -67.81791)
			(xy 213.730915 -67.824745) (xy 213.807693 -67.838351) (xy 213.882986 -67.858621) (xy 213.956217 -67.885402)
			(xy 213.991698 -67.901566) (xy 213.99964 -67.904944) (xy 214.016794 -67.906724) (xy 214.033559 -67.902679)
			(xy 214.040974 -67.898264) (xy 214.064305 -67.883668) (xy 214.114265 -67.860591) (xy 214.167023 -67.844935)
			(xy 214.221484 -67.837025) (xy 214.249 -67.836542) (xy 214.249254 -67.836542) (xy 214.279093 -67.837118)
			(xy 214.338037 -67.846457) (xy 214.394805 -67.864869) (xy 214.44801 -67.891903) (xy 214.47252 -67.908932)
			(xy 214.485982 -67.910202) (xy 214.492641 -67.910593) (xy 214.505771 -67.908284) (xy 214.51189 -67.90563)
			(xy 214.550343 -67.888423) (xy 214.62983 -67.860496) (xy 214.711601 -67.840212) (xy 214.75319 -67.833494)
			(xy 214.762588 -67.832224) (xy 214.764366 -67.83197) (xy 214.794128 -67.828167) (xy 214.853997 -67.824098)
			(xy 214.884 -67.823842) (xy 214.884254 -67.823842) (xy 214.924284 -67.82428) (xy 215.004019 -67.831492)
			(xy 215.082785 -67.845836) (xy 215.159944 -67.867194) (xy 215.234873 -67.895396) (xy 215.306967 -67.930212)
			(xy 215.375644 -67.971362) (xy 215.440347 -68.018512) (xy 215.47074 -68.044568) (xy 215.477852 -68.050918)
			(xy 215.49487 -68.057268) (xy 215.54313 -68.057268) (xy 215.560148 -68.050918) (xy 215.56726 -68.044568)
			(xy 215.597654 -68.018512) (xy 215.662347 -67.971343) (xy 215.731018 -67.930181) (xy 215.803111 -67.895358)
			(xy 215.878043 -67.867155) (xy 215.955205 -67.845802) (xy 216.033975 -67.831472) (xy 216.113715 -67.824279)
			(xy 216.153746 -67.823842) (xy 216.154 -67.823842) (xy 216.192428 -67.824256) (xy 216.268996 -67.830911)
			(xy 216.344705 -67.844144) (xy 216.41899 -67.863858) (xy 216.491298 -67.889905) (xy 216.526364 -67.90563)
			(xy 216.534432 -67.908968) (xy 216.551816 -67.910508) (xy 216.568716 -67.906151) (xy 216.576148 -67.901566)
			(xy 216.599881 -67.886219) (xy 216.650915 -67.861939) (xy 216.704972 -67.845451) (xy 216.760869 -67.837115)
			(xy 216.817385 -67.837115) (xy 216.873282 -67.845451) (xy 216.927339 -67.861939) (xy 216.978373 -67.886219)
			(xy 217.002106 -67.901566) (xy 217.009498 -67.906122) (xy 217.026308 -67.910437) (xy 217.043596 -67.908912)
			(xy 217.051636 -67.90563) (xy 217.086695 -67.889888) (xy 217.159004 -67.863843) (xy 217.233292 -67.844132)
			(xy 217.309002 -67.830904) (xy 217.385571 -67.824257) (xy 217.424 -67.823842) (xy 217.466351 -67.824246)
			(xy 217.550669 -67.832297) (xy 217.63384 -67.848327) (xy 217.715111 -67.87219) (xy 217.793745 -67.903671)
			(xy 217.869031 -67.942483) (xy 217.940287 -67.988276) (xy 218.006867 -68.040636) (xy 218.068169 -68.099087)
			(xy 218.123636 -68.1631) (xy 218.172768 -68.232096) (xy 218.215119 -68.30545) (xy 218.250305 -68.382497)
			(xy 218.278009 -68.46254) (xy 218.297978 -68.544855) (xy 218.310032 -68.628694) (xy 218.314063 -68.7133)
			(xy 218.310032 -68.797906) (xy 218.297978 -68.881745) (xy 218.278009 -68.96406) (xy 218.250305 -69.044103)
			(xy 218.215119 -69.12115) (xy 218.172768 -69.194504) (xy 218.123636 -69.2635) (xy 218.068169 -69.327513)
			(xy 218.006867 -69.385964) (xy 217.940287 -69.438324) (xy 217.869031 -69.484117) (xy 217.793745 -69.522929)
			(xy 217.715111 -69.55441) (xy 217.63384 -69.578273) (xy 217.550669 -69.594303) (xy 217.466351 -69.602354)
			(xy 217.424 -69.602858) (xy 217.423746 -69.602858) (xy 217.383716 -69.60242) (xy 217.303981 -69.595208)
			(xy 217.225215 -69.580864) (xy 217.148056 -69.559506) (xy 217.073127 -69.531304) (xy 217.001033 -69.496488)
			(xy 216.932356 -69.455338) (xy 216.867653 -69.408188) (xy 216.83726 -69.382132) (xy 216.830148 -69.375782)
			(xy 216.81313 -69.369432) (xy 216.765124 -69.369432) (xy 216.74836 -69.375782) (xy 216.741248 -69.381878)
			(xy 216.720684 -69.399585) (xy 216.677729 -69.432756) (xy 216.655396 -69.448172) (xy 216.620488 -69.471374)
			(xy 216.547111 -69.511903) (xy 216.470247 -69.545349) (xy 216.390577 -69.571417) (xy 216.308809 -69.589875)
			(xy 216.225668 -69.60056) (xy 216.141889 -69.603377) (xy 216.058218 -69.5983) (xy 215.975394 -69.585376)
			(xy 215.894154 -69.564718) (xy 215.815217 -69.53651) (xy 215.739284 -69.501002) (xy 215.667027 -69.458508)
			(xy 215.599088 -69.409406) (xy 215.56726 -69.382132) (xy 215.560148 -69.375782) (xy 215.54313 -69.369432)
			(xy 215.49487 -69.369432) (xy 215.477852 -69.375782) (xy 215.47074 -69.382132) (xy 215.440346 -69.408188)
			(xy 215.375653 -69.455357) (xy 215.306982 -69.496519) (xy 215.234889 -69.531342) (xy 215.159957 -69.559545)
			(xy 215.082795 -69.580898) (xy 215.004025 -69.595228) (xy 214.924285 -69.602421) (xy 214.884254 -69.602858)
			(xy 214.884 -69.602858) (xy 214.843675 -69.602414) (xy 214.763355 -69.595115) (xy 214.684026 -69.580577)
			(xy 214.606338 -69.558919) (xy 214.530929 -69.530319) (xy 214.458418 -69.495012) (xy 214.3894 -69.453287)
			(xy 214.324441 -69.405487) (xy 214.293958 -69.379084) (xy 214.286846 -69.372734) (xy 214.270082 -69.366384)
			(xy 214.220806 -69.36613) (xy 214.202772 -69.373242) (xy 214.196168 -69.379338) (xy 214.165889 -69.404984)
			(xy 214.101519 -69.451394) (xy 214.033271 -69.491885) (xy 213.961687 -69.526135) (xy 213.887336 -69.553871)
			(xy 213.81081 -69.574874) (xy 213.732717 -69.588974) (xy 213.653678 -69.596062) (xy 213.614 -69.596508)
			(xy 213.613746 -69.596508) (xy 213.573715 -69.596083) (xy 213.493979 -69.58887) (xy 213.415213 -69.574525)
			(xy 213.338054 -69.553165) (xy 213.263124 -69.524962) (xy 213.191031 -69.490144) (xy 213.122355 -69.448992)
			(xy 213.057652 -69.401839) (xy 213.02726 -69.375782) (xy 213.020148 -69.369432) (xy 213.00313 -69.363082)
			(xy 212.95487 -69.363082) (xy 212.937852 -69.369432) (xy 212.93074 -69.375782) (xy 212.898288 -69.403569)
			(xy 212.828948 -69.453488) (xy 212.755142 -69.496531) (xy 212.677551 -69.532301) (xy 212.596888 -69.56047)
			(xy 212.513897 -69.580779) (xy 212.429341 -69.593039) (xy 212.344 -69.597138) (xy 212.258659 -69.593039)
			(xy 212.174103 -69.580779) (xy 212.091112 -69.56047) (xy 212.010449 -69.532301) (xy 211.932858 -69.496531)
			(xy 211.859052 -69.453488) (xy 211.789712 -69.403569) (xy 211.75726 -69.375782) (xy 211.750148 -69.369432)
			(xy 211.73313 -69.363082) (xy 211.68487 -69.363082) (xy 211.667852 -69.369432) (xy 211.66074 -69.375782)
			(xy 211.630339 -69.40183) (xy 211.565648 -69.449) (xy 211.496978 -69.490164) (xy 211.424886 -69.524989)
			(xy 211.349956 -69.553193) (xy 211.272793 -69.574547) (xy 211.194024 -69.588878) (xy 211.114285 -69.596071)
			(xy 211.074254 -69.596508) (xy 211.074 -69.596508) (xy 211.034262 -69.596083) (xy 210.955103 -69.588991)
			(xy 210.876893 -69.574863) (xy 210.800255 -69.553814) (xy 210.725801 -69.526009) (xy 210.654125 -69.491672)
			(xy 210.5858 -69.451076) (xy 210.521369 -69.404545) (xy 210.49107 -69.37883) (xy 210.488022 -69.37629)
			(xy 210.483704 -69.373496) (xy 210.47752 -69.37004) (xy 210.463862 -69.366297) (xy 210.45678 -69.36613)
			(xy 210.417918 -69.366384) (xy 210.401154 -69.372734) (xy 210.394042 -69.379084) (xy 210.363568 -69.405497)
			(xy 210.298606 -69.453293) (xy 210.229586 -69.495014) (xy 210.157073 -69.530318) (xy 210.081663 -69.558915)
			(xy 210.003974 -69.580571) (xy 209.924645 -69.595108) (xy 209.844325 -69.602406) (xy 209.804 -69.602858)
			(xy 209.76234 -69.602421) (xy 209.679387 -69.594614) (xy 209.597526 -69.579088) (xy 209.517475 -69.555977)
			(xy 209.439935 -69.525486) (xy 209.365585 -69.48788) (xy 209.295075 -69.443489) (xy 209.229023 -69.392701)
			(xy 209.168008 -69.335962) (xy 209.112563 -69.273768) (xy 209.063175 -69.206663) (xy 209.020275 -69.135236)
			(xy 208.984239 -69.060112) (xy 208.969356 -69.021198) (xy 208.96707 -69.015102) (xy 208.960212 -69.004942)
			(xy 208.955132 -69.000624) (xy 208.950169 -68.996566) (xy 208.938737 -68.990778) (xy 208.932526 -68.989194)
			(xy 208.849214 -68.970906) (xy 208.836748 -68.96891) (xy 208.812502 -68.97582) (xy 208.802986 -68.984114)
			(xy 208.802478 -68.984622) (xy 208.780922 -69.005153) (xy 208.732609 -69.039931) (xy 208.67948 -69.06678)
			(xy 208.622824 -69.085047) (xy 208.564018 -69.09429) (xy 208.534254 -69.094858) (xy 208.534 -69.094858)
			(xy 208.506752 -69.094272) (xy 208.452812 -69.086516) (xy 208.400524 -69.071163) (xy 208.350953 -69.048525)
			(xy 208.305109 -69.019063) (xy 208.263924 -68.983376) (xy 208.228237 -68.942191) (xy 208.198775 -68.896347)
			(xy 208.176137 -68.846776) (xy 208.160784 -68.794488) (xy 208.153028 -68.740548) (xy 207.645012 -68.740548)
			(xy 207.644999 -68.741236) (xy 207.636879 -68.796412) (xy 207.620811 -68.849819) (xy 207.597139 -68.900316)
			(xy 207.566366 -68.946829) (xy 207.529149 -68.988366) (xy 207.486281 -69.024041) (xy 207.438675 -69.053095)
			(xy 207.387346 -69.074907) (xy 207.333389 -69.089013) (xy 207.277952 -69.095113) (xy 207.222218 -69.093076)
			(xy 207.167375 -69.082946) (xy 207.114591 -69.064939) (xy 207.064991 -69.039438) (xy 207.019633 -69.006987)
			(xy 206.979484 -68.968278) (xy 206.945398 -68.924135) (xy 206.918102 -68.8755) (xy 206.898179 -68.823409)
			(xy 206.886053 -68.768972) (xy 206.881982 -68.71335) (xy 189.677559 -68.71335) (xy 189.687572 -68.721195)
			(xy 189.78696 -68.809245) (xy 189.880851 -68.903136) (xy 189.968901 -69.002523) (xy 190.050789 -69.107046)
			(xy 190.126218 -69.216323) (xy 190.19491 -69.329954) (xy 190.256617 -69.447526) (xy 190.311112 -69.568609)
			(xy 190.358197 -69.692761) (xy 190.397699 -69.81953) (xy 190.429476 -69.948452) (xy 190.453411 -70.079058)
			(xy 190.469416 -70.210871) (xy 190.477433 -70.34341) (xy 190.477433 -70.47619) (xy 190.469416 -70.608729)
			(xy 190.453411 -70.740542) (xy 190.429476 -70.871148) (xy 190.404149 -70.9739) (xy 203.300384 -70.9739)
			(xy 203.304414 -70.88928) (xy 203.316471 -70.805425) (xy 203.336444 -70.723097) (xy 203.364152 -70.64304)
			(xy 203.399344 -70.565979) (xy 203.441702 -70.492613) (xy 203.490843 -70.423605) (xy 203.54632 -70.35958)
			(xy 203.607632 -70.301119) (xy 203.674224 -70.248751) (xy 203.745492 -70.20295) (xy 203.820791 -70.164131)
			(xy 203.899439 -70.132645) (xy 203.980724 -70.108777) (xy 204.063909 -70.092745) (xy 204.148242 -70.084692)
			(xy 204.1906 -70.084188) (xy 204.232384 -70.084696) (xy 204.315581 -70.092581) (xy 204.356716 -70.099936)
			(xy 204.370429 -70.101963) (xy 204.39803 -70.099598) (xy 204.423977 -70.089892) (xy 204.446355 -70.073562)
			(xy 204.463513 -70.051813) (xy 204.474186 -70.026249) (xy 204.47635 -70.01256) (xy 204.482179 -69.96979)
			(xy 204.501164 -69.885577) (xy 204.528213 -69.803598) (xy 204.563072 -69.724623) (xy 204.605414 -69.649394)
			(xy 204.654841 -69.578618) (xy 204.710888 -69.512961) (xy 204.773029 -69.453038) (xy 204.84068 -69.399414)
			(xy 204.913205 -69.352592) (xy 204.95133 -69.332348) (xy 204.958836 -69.32815) (xy 204.970657 -69.315671)
			(xy 204.977697 -69.299989) (xy 204.978762 -69.291454) (xy 204.981465 -69.264536) (xy 204.993501 -69.211793)
			(xy 205.012868 -69.161279) (xy 205.039175 -69.114007) (xy 205.071896 -69.070925) (xy 205.110374 -69.032897)
			(xy 205.153839 -69.000686) (xy 205.201417 -68.974937) (xy 205.252156 -68.956167) (xy 205.305037 -68.944753)
			(xy 205.359 -68.940922) (xy 205.412963 -68.944753) (xy 205.465844 -68.956167) (xy 205.516583 -68.974937)
			(xy 205.564161 -69.000686) (xy 205.607626 -69.032897) (xy 205.646104 -69.070925) (xy 205.678825 -69.114007)
			(xy 205.705132 -69.161279) (xy 205.724499 -69.211793) (xy 205.736535 -69.264536) (xy 205.739238 -69.291454)
			(xy 205.74032 -69.299987) (xy 205.747341 -69.315672) (xy 205.759174 -69.328135) (xy 205.76667 -69.332348)
			(xy 205.802532 -69.351354) (xy 205.870983 -69.394976) (xy 205.935175 -69.444653) (xy 205.994575 -69.499971)
			(xy 206.048689 -69.56047) (xy 206.097066 -69.625648) (xy 206.139304 -69.694961) (xy 206.175053 -69.767834)
			(xy 206.204014 -69.843661) (xy 206.225947 -69.921811) (xy 206.24067 -70.001633) (xy 206.24806 -70.082465)
			(xy 206.248508 -70.12305) (xy 206.248081 -70.164153) (xy 206.240492 -70.246009) (xy 206.225382 -70.326815)
			(xy 206.202882 -70.405883) (xy 206.173182 -70.482537) (xy 206.136536 -70.556124) (xy 206.093258 -70.626016)
			(xy 206.043715 -70.691616) (xy 205.988331 -70.752366) (xy 205.927578 -70.807747) (xy 205.861974 -70.857286)
			(xy 205.79208 -70.900561) (xy 205.718491 -70.937202) (xy 205.641835 -70.966898) (xy 205.562766 -70.989394)
			(xy 205.481959 -71.004499) (xy 205.400103 -71.012083) (xy 205.359 -71.012558) (xy 205.357984 -71.012558)
			(xy 205.316523 -71.012059) (xy 205.233965 -71.004302) (xy 205.193138 -70.997064) (xy 205.179462 -70.994871)
			(xy 205.151872 -70.997235) (xy 205.125933 -71.006929) (xy 205.103554 -71.023239) (xy 205.086384 -71.044964)
			(xy 205.075686 -71.070505) (xy 205.073504 -71.084186) (xy 205.067638 -71.126698) (xy 205.048859 -71.210442)
			(xy 205.022103 -71.291987) (xy 204.987619 -71.370578) (xy 204.945728 -71.445482) (xy 204.896818 -71.516005)
			(xy 204.841345 -71.58149) (xy 204.779824 -71.641329) (xy 204.712826 -71.694966) (xy 204.640975 -71.741903)
			(xy 204.564939 -71.781703) (xy 204.485423 -71.813995) (xy 204.403167 -71.838481) (xy 204.318936 -71.854933)
			(xy 204.233512 -71.863197) (xy 204.1906 -71.863712) (xy 204.148242 -71.863108) (xy 204.063909 -71.855055)
			(xy 203.980724 -71.839023) (xy 203.899439 -71.815155) (xy 203.820791 -71.783669) (xy 203.745492 -71.74485)
			(xy 203.674224 -71.699049) (xy 203.607632 -71.646681) (xy 203.54632 -71.58822) (xy 203.490843 -71.524195)
			(xy 203.441702 -71.455187) (xy 203.399344 -71.381821) (xy 203.364152 -71.30476) (xy 203.336444 -71.224703)
			(xy 203.316471 -71.142375) (xy 203.304414 -71.05852) (xy 203.300384 -70.9739) (xy 190.404149 -70.9739)
			(xy 190.397699 -71.00007) (xy 190.358197 -71.126839) (xy 190.311112 -71.250991) (xy 190.256617 -71.372074)
			(xy 190.19491 -71.489646) (xy 190.126218 -71.603277) (xy 190.050789 -71.712554) (xy 189.968901 -71.817077)
			(xy 189.880851 -71.916464) (xy 189.788315 -72.009) (xy 209.82889 -72.009) (xy 209.832961 -71.953378)
			(xy 209.845087 -71.898941) (xy 209.86501 -71.84685) (xy 209.892306 -71.798215) (xy 209.926392 -71.754072)
			(xy 209.966541 -71.715363) (xy 210.011899 -71.682912) (xy 210.061499 -71.657411) (xy 210.114283 -71.639404)
			(xy 210.169126 -71.629274) (xy 210.22486 -71.627237) (xy 210.280297 -71.633337) (xy 210.334254 -71.647443)
			(xy 210.385583 -71.669255) (xy 210.433189 -71.698309) (xy 210.476057 -71.733984) (xy 210.513274 -71.775521)
			(xy 210.544047 -71.822034) (xy 210.567719 -71.872531) (xy 210.583787 -71.925938) (xy 210.591907 -71.981114)
			(xy 210.592416 -72.009) (xy 210.591907 -72.036886) (xy 210.583787 -72.092062) (xy 210.567719 -72.145469)
			(xy 210.544047 -72.195966) (xy 210.513274 -72.242479) (xy 210.476057 -72.284016) (xy 210.433189 -72.319691)
			(xy 210.385583 -72.348745) (xy 210.334254 -72.370557) (xy 210.280297 -72.384663) (xy 210.22486 -72.390763)
			(xy 210.169126 -72.388726) (xy 210.114283 -72.378596) (xy 210.061499 -72.360589) (xy 210.011899 -72.335088)
			(xy 209.966541 -72.302637) (xy 209.926392 -72.263928) (xy 209.892306 -72.219785) (xy 209.86501 -72.17115)
			(xy 209.845087 -72.119059) (xy 209.832961 -72.064622) (xy 209.82889 -72.009) (xy 189.788315 -72.009)
			(xy 189.78696 -72.010355) (xy 189.687572 -72.098405) (xy 189.583049 -72.180293) (xy 189.473772 -72.255721)
			(xy 189.360141 -72.324413) (xy 189.242569 -72.386119) (xy 189.121486 -72.440614) (xy 188.997333 -72.487699)
			(xy 188.903302 -72.517) (xy 204.468728 -72.517) (xy 204.472801 -72.461341) (xy 204.484936 -72.406868)
			(xy 204.504872 -72.354742) (xy 204.532186 -72.306074) (xy 204.566294 -72.261902) (xy 204.606471 -72.223167)
			(xy 204.651859 -72.190695) (xy 204.701491 -72.165177) (xy 204.754311 -72.147158) (xy 204.80919 -72.137021)
			(xy 204.864961 -72.134983) (xy 204.920435 -72.141086) (xy 204.974428 -72.155202) (xy 205.025791 -72.177029)
			(xy 205.073429 -72.206102) (xy 205.116325 -72.241801) (xy 205.153567 -72.283365) (xy 205.184361 -72.329909)
			(xy 205.208049 -72.38044) (xy 205.224127 -72.433882) (xy 205.232253 -72.489096) (xy 205.232762 -72.517)
			(xy 205.232253 -72.544904) (xy 205.224127 -72.600118) (xy 205.208049 -72.65356) (xy 205.184361 -72.704091)
			(xy 205.153567 -72.750635) (xy 205.116325 -72.792199) (xy 205.073429 -72.827898) (xy 205.025791 -72.856971)
			(xy 204.974428 -72.878798) (xy 204.920435 -72.892914) (xy 204.864961 -72.899017) (xy 204.80919 -72.896979)
			(xy 204.754311 -72.886842) (xy 204.701491 -72.868823) (xy 204.651859 -72.843305) (xy 204.606471 -72.810833)
			(xy 204.566294 -72.772098) (xy 204.532186 -72.727926) (xy 204.504872 -72.679258) (xy 204.484936 -72.627132)
			(xy 204.472801 -72.572659) (xy 204.468728 -72.517) (xy 188.903302 -72.517) (xy 188.870565 -72.527201)
			(xy 188.741642 -72.558977) (xy 188.611036 -72.582911) (xy 188.479223 -72.598916) (xy 188.346684 -72.606933)
			(xy 188.280294 -72.607424) (xy 188.213377 -72.606907) (xy 188.07979 -72.598761) (xy 187.946947 -72.582501)
			(xy 187.815339 -72.558187) (xy 187.685455 -72.525909) (xy 187.557777 -72.485786) (xy 187.432777 -72.437967)
			(xy 187.310918 -72.382629) (xy 187.192653 -72.319978) (xy 187.07842 -72.250246) (xy 186.968643 -72.173691)
			(xy 186.863728 -72.090597) (xy 186.764064 -72.001273) (xy 186.670022 -71.906049) (xy 186.581948 -71.805277)
			(xy 186.500171 -71.699333) (xy 186.462162 -71.644256) (xy 186.459368 -71.640192) (xy 186.452002 -71.632826)
			(xy 186.444592 -71.625998) (xy 186.426001 -71.618271) (xy 186.415934 -71.61784) (xy 186.334654 -71.61784)
			(xy 186.324586 -71.618283) (xy 186.305988 -71.62599) (xy 186.298586 -71.632826) (xy 186.29122 -71.640192)
			(xy 186.288426 -71.644256) (xy 186.250399 -71.699321) (xy 186.168625 -71.805268) (xy 186.080555 -71.906042)
			(xy 185.986515 -72.001268) (xy 185.886853 -72.090596) (xy 185.78194 -72.173692) (xy 185.672164 -72.250249)
			(xy 185.557932 -72.319983) (xy 185.439668 -72.382635) (xy 185.317811 -72.437974) (xy 185.192811 -72.485795)
			(xy 185.065132 -72.525919) (xy 184.935249 -72.558198) (xy 184.803641 -72.582512) (xy 184.670798 -72.598772)
			(xy 184.537211 -72.606917) (xy 184.470294 -72.607424) (xy 184.403905 -72.606913) (xy 184.271368 -72.598895)
			(xy 184.139558 -72.58289) (xy 184.008954 -72.558956) (xy 183.880034 -72.52718) (xy 183.753267 -72.487678)
			(xy 183.629117 -72.440594) (xy 183.508036 -72.3861) (xy 183.390467 -72.324394) (xy 183.276837 -72.255703)
			(xy 183.167562 -72.180276) (xy 183.063041 -72.098389) (xy 182.963655 -72.010341) (xy 182.869766 -71.916453)
			(xy 182.781717 -71.817067) (xy 182.69983 -71.712546) (xy 182.624402 -71.603271) (xy 182.555711 -71.489642)
			(xy 182.494005 -71.372073) (xy 182.43951 -71.250992) (xy 182.392426 -71.126842) (xy 182.352923 -71.000076)
			(xy 182.321146 -70.871156) (xy 182.297211 -70.740552) (xy 182.281206 -70.608742) (xy 182.273188 -70.476205)
			(xy 182.272686 -70.409816) (xy 182.272686 -70.409562) (xy 182.273191 -70.341861) (xy 182.281541 -70.206716)
			(xy 182.298195 -70.072341) (xy 182.323089 -69.939246) (xy 182.35613 -69.807937) (xy 182.397191 -69.67891)
			(xy 182.446118 -69.552656) (xy 182.502724 -69.429653) (xy 182.566795 -69.310369) (xy 182.638087 -69.195254)
			(xy 182.716331 -69.084747) (xy 182.801229 -68.979267) (xy 182.89246 -68.879212) (xy 182.940706 -68.831714)
			(xy 182.947687 -68.824342) (xy 182.955591 -68.805656) (xy 182.955635 -68.785366) (xy 182.952136 -68.775834)
			(xy 182.916068 -68.688966) (xy 182.91395 -68.684212) (xy 182.908055 -68.675638) (xy 182.904384 -68.671948)
			(xy 182.896764 -68.664582) (xy 182.882794 -68.658994) (xy 182.850282 -68.659756) (xy 182.810673 -68.659236)
			(xy 182.731853 -68.651304) (xy 182.654223 -68.635523) (xy 182.578562 -68.612051) (xy 182.50563 -68.581124)
			(xy 182.436161 -68.543052) (xy 182.370851 -68.498217) (xy 182.310357 -68.44707) (xy 182.255287 -68.390125)
			(xy 182.206193 -68.327954) (xy 182.163568 -68.26118) (xy 182.127842 -68.190476) (xy 182.099372 -68.116551)
			(xy 182.078445 -68.040147) (xy 182.06527 -67.962032) (xy 182.059981 -67.882991) (xy 181.638027 -67.882991)
			(xy 181.637689 -67.909749) (xy 181.629609 -67.989204) (xy 181.613532 -68.067434) (xy 181.589623 -68.143636)
			(xy 181.558128 -68.217029) (xy 181.519369 -68.286859) (xy 181.473745 -68.352409) (xy 181.421723 -68.413008)
			(xy 181.363838 -68.468032) (xy 181.300682 -68.516918) (xy 181.232905 -68.559164) (xy 181.161202 -68.594336)
			(xy 181.086308 -68.622073) (xy 181.008993 -68.642092) (xy 180.930049 -68.654185) (xy 180.850286 -68.658231)
			(xy 180.770523 -68.654185) (xy 180.691579 -68.642092) (xy 180.614264 -68.622073) (xy 180.53937 -68.594336)
			(xy 180.467667 -68.559164) (xy 180.39989 -68.516918) (xy 180.336734 -68.468032) (xy 180.278849 -68.413008)
			(xy 180.226827 -68.352409) (xy 180.181203 -68.286859) (xy 180.142444 -68.217029) (xy 180.110949 -68.143636)
			(xy 180.08704 -68.067434) (xy 180.070963 -67.989204) (xy 180.062883 -67.909749) (xy 179.637693 -67.909749)
			(xy 179.629613 -67.989204) (xy 179.613536 -68.067434) (xy 179.589627 -68.143636) (xy 179.558132 -68.217029)
			(xy 179.519373 -68.286859) (xy 179.473749 -68.352409) (xy 179.421727 -68.413008) (xy 179.363842 -68.468032)
			(xy 179.300686 -68.516918) (xy 179.232909 -68.559164) (xy 179.161206 -68.594336) (xy 179.086312 -68.622073)
			(xy 179.008997 -68.642092) (xy 178.930053 -68.654185) (xy 178.85029 -68.658231) (xy 178.770527 -68.654185)
			(xy 178.691583 -68.642092) (xy 178.614268 -68.622073) (xy 178.539374 -68.594336) (xy 178.467671 -68.559164)
			(xy 178.399894 -68.516918) (xy 178.336738 -68.468032) (xy 178.278853 -68.413008) (xy 178.226831 -68.352409)
			(xy 178.181207 -68.286859) (xy 178.142448 -68.217029) (xy 178.110953 -68.143636) (xy 178.087044 -68.067434)
			(xy 178.070967 -67.989204) (xy 178.062887 -67.909749) (xy 177.637697 -67.909749) (xy 177.629617 -67.989204)
			(xy 177.61354 -68.067434) (xy 177.589631 -68.143636) (xy 177.558136 -68.217029) (xy 177.519377 -68.286859)
			(xy 177.473753 -68.352409) (xy 177.421731 -68.413008) (xy 177.363846 -68.468032) (xy 177.30069 -68.516918)
			(xy 177.232913 -68.559164) (xy 177.16121 -68.594336) (xy 177.086316 -68.622073) (xy 177.009001 -68.642092)
			(xy 176.930057 -68.654185) (xy 176.850294 -68.658231) (xy 176.770531 -68.654185) (xy 176.691587 -68.642092)
			(xy 176.614272 -68.622073) (xy 176.539378 -68.594336) (xy 176.467675 -68.559164) (xy 176.399898 -68.516918)
			(xy 176.336742 -68.468032) (xy 176.278857 -68.413008) (xy 176.226835 -68.352409) (xy 176.181211 -68.286859)
			(xy 176.142452 -68.217029) (xy 176.110957 -68.143636) (xy 176.087048 -68.067434) (xy 176.070971 -67.989204)
			(xy 176.062891 -67.909749) (xy 175.637701 -67.909749) (xy 175.629621 -67.989204) (xy 175.613544 -68.067434)
			(xy 175.589635 -68.143636) (xy 175.55814 -68.217029) (xy 175.519381 -68.286859) (xy 175.473757 -68.352409)
			(xy 175.421735 -68.413008) (xy 175.36385 -68.468032) (xy 175.300694 -68.516918) (xy 175.232917 -68.559164)
			(xy 175.161214 -68.594336) (xy 175.08632 -68.622073) (xy 175.009005 -68.642092) (xy 174.930061 -68.654185)
			(xy 174.850298 -68.658231) (xy 174.770535 -68.654185) (xy 174.691591 -68.642092) (xy 174.614276 -68.622073)
			(xy 174.539382 -68.594336) (xy 174.467679 -68.559164) (xy 174.399902 -68.516918) (xy 174.336746 -68.468032)
			(xy 174.278861 -68.413008) (xy 174.226839 -68.352409) (xy 174.181215 -68.286859) (xy 174.142456 -68.217029)
			(xy 174.110961 -68.143636) (xy 174.087052 -68.067434) (xy 174.070975 -67.989204) (xy 174.062895 -67.909749)
			(xy 173.637705 -67.909749) (xy 173.629625 -67.989204) (xy 173.613548 -68.067434) (xy 173.589639 -68.143636)
			(xy 173.558144 -68.217029) (xy 173.519385 -68.286859) (xy 173.473761 -68.352409) (xy 173.421739 -68.413008)
			(xy 173.363854 -68.468032) (xy 173.300698 -68.516918) (xy 173.232921 -68.559164) (xy 173.161218 -68.594336)
			(xy 173.086324 -68.622073) (xy 173.009009 -68.642092) (xy 172.930065 -68.654185) (xy 172.850302 -68.658231)
			(xy 172.770539 -68.654185) (xy 172.691595 -68.642092) (xy 172.61428 -68.622073) (xy 172.539386 -68.594336)
			(xy 172.467683 -68.559164) (xy 172.399906 -68.516918) (xy 172.33675 -68.468032) (xy 172.278865 -68.413008)
			(xy 172.226843 -68.352409) (xy 172.181219 -68.286859) (xy 172.14246 -68.217029) (xy 172.110965 -68.143636)
			(xy 172.087056 -68.067434) (xy 172.070979 -67.989204) (xy 172.062899 -67.909749) (xy 171.637709 -67.909749)
			(xy 171.629629 -67.989204) (xy 171.613552 -68.067434) (xy 171.589643 -68.143636) (xy 171.558148 -68.217029)
			(xy 171.519389 -68.286859) (xy 171.473765 -68.352409) (xy 171.421743 -68.413008) (xy 171.363858 -68.468032)
			(xy 171.300702 -68.516918) (xy 171.232925 -68.559164) (xy 171.161222 -68.594336) (xy 171.086328 -68.622073)
			(xy 171.009013 -68.642092) (xy 170.930069 -68.654185) (xy 170.850306 -68.658231) (xy 170.770543 -68.654185)
			(xy 170.691599 -68.642092) (xy 170.614284 -68.622073) (xy 170.53939 -68.594336) (xy 170.467687 -68.559164)
			(xy 170.39991 -68.516918) (xy 170.336754 -68.468032) (xy 170.278869 -68.413008) (xy 170.226847 -68.352409)
			(xy 170.181223 -68.286859) (xy 170.142464 -68.217029) (xy 170.110969 -68.143636) (xy 170.08706 -68.067434)
			(xy 170.070983 -67.989204) (xy 170.062903 -67.909749) (xy 143.639311 -67.909749) (xy 143.632875 -67.979161)
			(xy 143.619424 -68.051018) (xy 143.599389 -68.121324) (xy 143.57294 -68.189476) (xy 143.55699 -68.222368)
			(xy 143.55699 -68.245736) (xy 143.557363 -68.255114) (xy 143.564146 -68.272599) (xy 143.570198 -68.279772)
			(xy 143.629126 -68.344288) (xy 143.636325 -68.351472) (xy 143.654784 -68.359972) (xy 143.675093 -68.36068)
			(xy 143.684752 -68.357496) (xy 143.747442 -68.334035) (xy 143.875146 -68.293875) (xy 144.005056 -68.26156)
			(xy 144.136692 -68.23721) (xy 144.269566 -68.220914) (xy 144.403185 -68.212733) (xy 144.47012 -68.212208)
			(xy 144.537038 -68.2127) (xy 144.670625 -68.220847) (xy 144.803469 -68.237107) (xy 144.935077 -68.261423)
			(xy 145.064962 -68.293703) (xy 145.192641 -68.333827) (xy 145.317642 -68.381648) (xy 145.4395 -68.436987)
			(xy 145.557765 -68.49964) (xy 145.671998 -68.569374) (xy 145.781775 -68.64593) (xy 145.88669 -68.729026)
			(xy 145.986353 -68.818352) (xy 146.080395 -68.913579) (xy 146.168467 -69.014352) (xy 146.250244 -69.120298)
			(xy 146.288252 -69.175376) (xy 146.291046 -69.17944) (xy 146.298412 -69.186806) (xy 146.305813 -69.193645)
			(xy 146.324412 -69.201365) (xy 146.33448 -69.201792) (xy 146.41576 -69.201792) (xy 146.425827 -69.201348)
			(xy 146.444425 -69.193641) (xy 146.451828 -69.186806) (xy 146.459194 -69.17944) (xy 146.461988 -69.175376)
			(xy 146.499982 -69.120288) (xy 146.58176 -69.014343) (xy 146.669834 -68.913571) (xy 146.763877 -68.818346)
			(xy 146.863541 -68.72902) (xy 146.968457 -68.645926) (xy 147.078235 -68.569371) (xy 147.192469 -68.499638)
			(xy 147.310735 -68.436987) (xy 147.432595 -68.38165) (xy 147.557596 -68.333831) (xy 147.685276 -68.293708)
			(xy 147.815161 -68.261431) (xy 147.94677 -68.237117) (xy 148.079614 -68.220859) (xy 148.213202 -68.212715)
			(xy 148.28012 -68.212208) (xy 148.34651 -68.212678) (xy 148.479047 -68.220696) (xy 148.610858 -68.236702)
			(xy 148.741462 -68.260637) (xy 148.870383 -68.292414) (xy 148.99715 -68.331918) (xy 149.1213 -68.379003)
			(xy 149.242381 -68.433498) (xy 149.359951 -68.495204) (xy 149.473581 -68.563897) (xy 149.582855 -68.639324)
			(xy 149.687377 -68.721212) (xy 149.786763 -68.809262) (xy 149.880652 -68.903152) (xy 149.9687 -69.002539)
			(xy 150.050587 -69.107061) (xy 150.126014 -69.216336) (xy 150.194706 -69.329966) (xy 150.256411 -69.447537)
			(xy 150.310905 -69.568618) (xy 150.357989 -69.692769) (xy 150.397491 -69.819537) (xy 150.429267 -69.948458)
			(xy 150.453201 -70.079062) (xy 150.469206 -70.210873) (xy 150.477223 -70.34341) (xy 150.477223 -70.409816)
			(xy 163.730183 -70.409816) (xy 163.73421 -70.293213) (xy 163.746272 -70.177166) (xy 163.766311 -70.062228)
			(xy 163.794233 -69.948946) (xy 163.829903 -69.83786) (xy 163.873152 -69.7295) (xy 163.923775 -69.624382)
			(xy 163.981528 -69.523007) (xy 164.046139 -69.425858) (xy 164.117297 -69.333398) (xy 164.194665 -69.246067)
			(xy 164.277874 -69.164283) (xy 164.366527 -69.088434) (xy 164.460201 -69.018882) (xy 164.558451 -68.955958)
			(xy 164.660808 -68.899962) (xy 164.766784 -68.851162) (xy 164.875875 -68.80979) (xy 164.987559 -68.776042)
			(xy 165.101306 -68.75008) (xy 165.216574 -68.732027) (xy 165.332812 -68.72197) (xy 165.449466 -68.719956)
			(xy 165.565982 -68.725995) (xy 165.681804 -68.740059) (xy 165.796379 -68.762079) (xy 165.909162 -68.791952)
			(xy 166.019616 -68.829534) (xy 166.127213 -68.874648) (xy 166.231442 -68.927077) (xy 166.331805 -68.986572)
			(xy 166.427824 -69.052849) (xy 166.519042 -69.125593) (xy 166.605024 -69.204457) (xy 166.685361 -69.289065)
			(xy 166.759668 -69.379014) (xy 166.827593 -69.473875) (xy 166.888812 -69.573196) (xy 166.943032 -69.676504)
			(xy 166.989996 -69.783307) (xy 167.029479 -69.893095) (xy 167.061294 -70.005346) (xy 167.085289 -70.119524)
			(xy 167.101349 -70.235086) (xy 167.109398 -70.35148) (xy 167.109902 -70.409816) (xy 167.540183 -70.409816)
			(xy 167.54421 -70.293213) (xy 167.556272 -70.177166) (xy 167.576311 -70.062228) (xy 167.604233 -69.948946)
			(xy 167.639903 -69.83786) (xy 167.683152 -69.7295) (xy 167.733775 -69.624382) (xy 167.791528 -69.523007)
			(xy 167.856139 -69.425858) (xy 167.927297 -69.333398) (xy 168.004665 -69.246067) (xy 168.087874 -69.164283)
			(xy 168.176527 -69.088434) (xy 168.270201 -69.018882) (xy 168.368451 -68.955958) (xy 168.470808 -68.899962)
			(xy 168.576784 -68.851162) (xy 168.685875 -68.80979) (xy 168.797559 -68.776042) (xy 168.911306 -68.75008)
			(xy 169.026574 -68.732027) (xy 169.142812 -68.72197) (xy 169.259466 -68.719956) (xy 169.375982 -68.725995)
			(xy 169.491804 -68.740059) (xy 169.606379 -68.762079) (xy 169.719162 -68.791952) (xy 169.829616 -68.829534)
			(xy 169.937213 -68.874648) (xy 170.041442 -68.927077) (xy 170.141805 -68.986572) (xy 170.237824 -69.052849)
			(xy 170.329042 -69.125593) (xy 170.415024 -69.204457) (xy 170.495361 -69.289065) (xy 170.569668 -69.379014)
			(xy 170.637593 -69.473875) (xy 170.698812 -69.573196) (xy 170.753032 -69.676504) (xy 170.799996 -69.783307)
			(xy 170.839479 -69.893095) (xy 170.871294 -70.005346) (xy 170.895289 -70.119524) (xy 170.911349 -70.235086)
			(xy 170.919398 -70.35148) (xy 170.919902 -70.409816) (xy 170.919398 -70.468152) (xy 170.911349 -70.584546)
			(xy 170.895289 -70.700108) (xy 170.871294 -70.814286) (xy 170.839479 -70.926537) (xy 170.799996 -71.036325)
			(xy 170.753032 -71.143128) (xy 170.698812 -71.246436) (xy 170.637593 -71.345757) (xy 170.569668 -71.440618)
			(xy 170.495361 -71.530567) (xy 170.415024 -71.615175) (xy 170.329042 -71.694039) (xy 170.237824 -71.766783)
			(xy 170.141805 -71.83306) (xy 170.041442 -71.892555) (xy 169.937213 -71.944984) (xy 169.829616 -71.990098)
			(xy 169.719162 -72.02768) (xy 169.606379 -72.057553) (xy 169.491804 -72.079573) (xy 169.375982 -72.093637)
			(xy 169.259466 -72.099676) (xy 169.142812 -72.097662) (xy 169.026574 -72.087605) (xy 168.911306 -72.069552)
			(xy 168.797559 -72.04359) (xy 168.685875 -72.009842) (xy 168.576784 -71.96847) (xy 168.470808 -71.91967)
			(xy 168.368451 -71.863674) (xy 168.270201 -71.80075) (xy 168.176527 -71.731198) (xy 168.087874 -71.655349)
			(xy 168.004665 -71.573565) (xy 167.927297 -71.486234) (xy 167.856139 -71.393774) (xy 167.791528 -71.296625)
			(xy 167.733775 -71.19525) (xy 167.683152 -71.090132) (xy 167.639903 -70.981772) (xy 167.604233 -70.870686)
			(xy 167.576311 -70.757404) (xy 167.556272 -70.642466) (xy 167.54421 -70.526419) (xy 167.540183 -70.409816)
			(xy 167.109902 -70.409816) (xy 167.109398 -70.468152) (xy 167.101349 -70.584546) (xy 167.085289 -70.700108)
			(xy 167.061294 -70.814286) (xy 167.029479 -70.926537) (xy 166.989996 -71.036325) (xy 166.943032 -71.143128)
			(xy 166.888812 -71.246436) (xy 166.827593 -71.345757) (xy 166.759668 -71.440618) (xy 166.685361 -71.530567)
			(xy 166.605024 -71.615175) (xy 166.519042 -71.694039) (xy 166.427824 -71.766783) (xy 166.331805 -71.83306)
			(xy 166.231442 -71.892555) (xy 166.127213 -71.944984) (xy 166.019616 -71.990098) (xy 165.909162 -72.02768)
			(xy 165.796379 -72.057553) (xy 165.681804 -72.079573) (xy 165.565982 -72.093637) (xy 165.449466 -72.099676)
			(xy 165.332812 -72.097662) (xy 165.216574 -72.087605) (xy 165.101306 -72.069552) (xy 164.987559 -72.04359)
			(xy 164.875875 -72.009842) (xy 164.766784 -71.96847) (xy 164.660808 -71.91967) (xy 164.558451 -71.863674)
			(xy 164.460201 -71.80075) (xy 164.366527 -71.731198) (xy 164.277874 -71.655349) (xy 164.194665 -71.573565)
			(xy 164.117297 -71.486234) (xy 164.046139 -71.393774) (xy 163.981528 -71.296625) (xy 163.923775 -71.19525)
			(xy 163.873152 -71.090132) (xy 163.829903 -70.981772) (xy 163.794233 -70.870686) (xy 163.766311 -70.757404)
			(xy 163.746272 -70.642466) (xy 163.73421 -70.526419) (xy 163.730183 -70.409816) (xy 150.477223 -70.409816)
			(xy 150.477223 -70.47619) (xy 150.469206 -70.608727) (xy 150.453201 -70.740538) (xy 150.429267 -70.871142)
			(xy 150.397491 -71.000063) (xy 150.357989 -71.126831) (xy 150.310905 -71.250982) (xy 150.256411 -71.372063)
			(xy 150.194706 -71.489634) (xy 150.126014 -71.603264) (xy 150.050587 -71.712539) (xy 149.9687 -71.817061)
			(xy 149.880652 -71.916448) (xy 149.786763 -72.010338) (xy 149.687377 -72.098388) (xy 149.582855 -72.180276)
			(xy 149.473581 -72.255703) (xy 149.359951 -72.324396) (xy 149.242381 -72.386102) (xy 149.1213 -72.440597)
			(xy 148.99715 -72.487682) (xy 148.870383 -72.527186) (xy 148.741462 -72.558963) (xy 148.610858 -72.582898)
			(xy 148.479047 -72.598904) (xy 148.34651 -72.606922) (xy 148.28012 -72.607424) (xy 148.213203 -72.606886)
			(xy 148.079617 -72.598742) (xy 147.946774 -72.582484) (xy 147.815167 -72.558171) (xy 147.685283 -72.525894)
			(xy 147.557605 -72.485773) (xy 147.432605 -72.437955) (xy 147.310746 -72.382619) (xy 147.192481 -72.319969)
			(xy 147.078248 -72.250238) (xy 146.968471 -72.173685) (xy 146.863556 -72.090592) (xy 146.763892 -72.001269)
			(xy 146.669849 -71.906046) (xy 146.581775 -71.805276) (xy 146.499997 -71.699333) (xy 146.461988 -71.644256)
			(xy 146.459194 -71.640192) (xy 146.451828 -71.632826) (xy 146.444409 -71.62601) (xy 146.425824 -71.618275)
			(xy 146.41576 -71.61784) (xy 146.33448 -71.61784) (xy 146.324408 -71.618244) (xy 146.30581 -71.625979)
			(xy 146.298412 -71.632826) (xy 146.291046 -71.640192) (xy 146.288252 -71.644256) (xy 146.250208 -71.699309)
			(xy 146.168435 -71.805256) (xy 146.080366 -71.90603) (xy 145.986327 -72.001257) (xy 145.886667 -72.090584)
			(xy 145.781755 -72.173681) (xy 145.67198 -72.250238) (xy 145.55775 -72.319973) (xy 145.439487 -72.382626)
			(xy 145.31763 -72.437966) (xy 145.192632 -72.485787) (xy 145.064954 -72.525912) (xy 144.935072 -72.558193)
			(xy 144.803465 -72.582509) (xy 144.670623 -72.59877) (xy 144.537037 -72.606916) (xy 144.47012 -72.607424)
			(xy 144.403731 -72.606897) (xy 144.271194 -72.598882) (xy 144.139383 -72.582878) (xy 144.008779 -72.558945)
			(xy 143.879859 -72.52717) (xy 143.753092 -72.487669) (xy 143.628941 -72.440586) (xy 143.50786 -72.386093)
			(xy 143.39029 -72.324389) (xy 143.27666 -72.255699) (xy 143.167384 -72.180273) (xy 143.062862 -72.098386)
			(xy 142.963475 -72.010339) (xy 142.869586 -71.916451) (xy 142.781537 -71.817065) (xy 142.699649 -71.712545)
			(xy 142.624221 -71.603271) (xy 142.555529 -71.489642) (xy 142.493822 -71.372072) (xy 142.439327 -71.250992)
			(xy 142.392242 -71.126842) (xy 142.352739 -71.000076) (xy 142.320962 -70.871156) (xy 142.297027 -70.740552)
			(xy 142.281022 -70.608742) (xy 142.273004 -70.476205) (xy 142.272512 -70.409816) (xy 142.272512 -70.409562)
			(xy 142.272998 -70.34186) (xy 142.281348 -70.206714) (xy 142.298003 -70.072339) (xy 142.322898 -69.939243)
			(xy 142.355939 -69.807933) (xy 142.397001 -69.678905) (xy 142.445928 -69.55265) (xy 142.502536 -69.429647)
			(xy 142.566607 -69.310362) (xy 142.637901 -69.195247) (xy 142.716146 -69.08474) (xy 142.801046 -68.979259)
			(xy 142.892278 -68.879205) (xy 142.940532 -68.831714) (xy 142.947507 -68.824336) (xy 142.95542 -68.805654)
			(xy 142.955464 -68.785365) (xy 142.951962 -68.775834) (xy 142.913862 -68.683886) (xy 142.910052 -68.678806)
			(xy 142.902178 -68.668138) (xy 142.88389 -68.658994) (xy 142.850108 -68.659756) (xy 142.810497 -68.659263)
			(xy 142.731674 -68.651334) (xy 142.65404 -68.635555) (xy 142.578375 -68.612084) (xy 142.50544 -68.581158)
			(xy 142.435967 -68.543086) (xy 142.370653 -68.498251) (xy 142.310156 -68.447104) (xy 142.255081 -68.390158)
			(xy 142.205984 -68.327986) (xy 142.163356 -68.261211) (xy 142.127626 -68.190504) (xy 142.099153 -68.116577)
			(xy 142.078223 -68.04017) (xy 142.065046 -67.962053) (xy 142.059755 -67.883008) (xy 141.637853 -67.883008)
			(xy 141.637515 -67.909749) (xy 141.629435 -67.989204) (xy 141.613358 -68.067434) (xy 141.589449 -68.143636)
			(xy 141.557954 -68.217029) (xy 141.519195 -68.286859) (xy 141.473571 -68.352409) (xy 141.421549 -68.413008)
			(xy 141.363664 -68.468032) (xy 141.300508 -68.516918) (xy 141.232731 -68.559164) (xy 141.161028 -68.594336)
			(xy 141.086134 -68.622073) (xy 141.008819 -68.642092) (xy 140.929875 -68.654185) (xy 140.850112 -68.658231)
			(xy 140.770349 -68.654185) (xy 140.691405 -68.642092) (xy 140.61409 -68.622073) (xy 140.539196 -68.594336)
			(xy 140.467493 -68.559164) (xy 140.399716 -68.516918) (xy 140.33656 -68.468032) (xy 140.278675 -68.413008)
			(xy 140.226653 -68.352409) (xy 140.181029 -68.286859) (xy 140.14227 -68.217029) (xy 140.110775 -68.143636)
			(xy 140.086866 -68.067434) (xy 140.070789 -67.989204) (xy 140.062709 -67.909749) (xy 139.637519 -67.909749)
			(xy 139.629439 -67.989204) (xy 139.613362 -68.067434) (xy 139.589453 -68.143636) (xy 139.557958 -68.217029)
			(xy 139.519199 -68.286859) (xy 139.473575 -68.352409) (xy 139.421553 -68.413008) (xy 139.363668 -68.468032)
			(xy 139.300512 -68.516918) (xy 139.232735 -68.559164) (xy 139.161032 -68.594336) (xy 139.086138 -68.622073)
			(xy 139.008823 -68.642092) (xy 138.929879 -68.654185) (xy 138.850116 -68.658231) (xy 138.770353 -68.654185)
			(xy 138.691409 -68.642092) (xy 138.614094 -68.622073) (xy 138.5392 -68.594336) (xy 138.467497 -68.559164)
			(xy 138.39972 -68.516918) (xy 138.336564 -68.468032) (xy 138.278679 -68.413008) (xy 138.226657 -68.352409)
			(xy 138.181033 -68.286859) (xy 138.142274 -68.217029) (xy 138.110779 -68.143636) (xy 138.08687 -68.067434)
			(xy 138.070793 -67.989204) (xy 138.062713 -67.909749) (xy 137.637523 -67.909749) (xy 137.629443 -67.989204)
			(xy 137.613366 -68.067434) (xy 137.589457 -68.143636) (xy 137.557962 -68.217029) (xy 137.519203 -68.286859)
			(xy 137.473579 -68.352409) (xy 137.421557 -68.413008) (xy 137.363672 -68.468032) (xy 137.300516 -68.516918)
			(xy 137.232739 -68.559164) (xy 137.161036 -68.594336) (xy 137.086142 -68.622073) (xy 137.008827 -68.642092)
			(xy 136.929883 -68.654185) (xy 136.85012 -68.658231) (xy 136.770357 -68.654185) (xy 136.691413 -68.642092)
			(xy 136.614098 -68.622073) (xy 136.539204 -68.594336) (xy 136.467501 -68.559164) (xy 136.399724 -68.516918)
			(xy 136.336568 -68.468032) (xy 136.278683 -68.413008) (xy 136.226661 -68.352409) (xy 136.181037 -68.286859)
			(xy 136.142278 -68.217029) (xy 136.110783 -68.143636) (xy 136.086874 -68.067434) (xy 136.070797 -67.989204)
			(xy 136.062717 -67.909749) (xy 135.637527 -67.909749) (xy 135.629447 -67.989204) (xy 135.61337 -68.067434)
			(xy 135.589461 -68.143636) (xy 135.557966 -68.217029) (xy 135.519207 -68.286859) (xy 135.473583 -68.352409)
			(xy 135.421561 -68.413008) (xy 135.363676 -68.468032) (xy 135.30052 -68.516918) (xy 135.232743 -68.559164)
			(xy 135.16104 -68.594336) (xy 135.086146 -68.622073) (xy 135.008831 -68.642092) (xy 134.929887 -68.654185)
			(xy 134.850124 -68.658231) (xy 134.770361 -68.654185) (xy 134.691417 -68.642092) (xy 134.614102 -68.622073)
			(xy 134.539208 -68.594336) (xy 134.467505 -68.559164) (xy 134.399728 -68.516918) (xy 134.336572 -68.468032)
			(xy 134.278687 -68.413008) (xy 134.226665 -68.352409) (xy 134.181041 -68.286859) (xy 134.142282 -68.217029)
			(xy 134.110787 -68.143636) (xy 134.086878 -68.067434) (xy 134.070801 -67.989204) (xy 134.062721 -67.909749)
			(xy 133.637531 -67.909749) (xy 133.629451 -67.989204) (xy 133.613374 -68.067434) (xy 133.589465 -68.143636)
			(xy 133.55797 -68.217029) (xy 133.519211 -68.286859) (xy 133.473587 -68.352409) (xy 133.421565 -68.413008)
			(xy 133.36368 -68.468032) (xy 133.300524 -68.516918) (xy 133.232747 -68.559164) (xy 133.161044 -68.594336)
			(xy 133.08615 -68.622073) (xy 133.008835 -68.642092) (xy 132.929891 -68.654185) (xy 132.850128 -68.658231)
			(xy 132.770365 -68.654185) (xy 132.691421 -68.642092) (xy 132.614106 -68.622073) (xy 132.539212 -68.594336)
			(xy 132.467509 -68.559164) (xy 132.399732 -68.516918) (xy 132.336576 -68.468032) (xy 132.278691 -68.413008)
			(xy 132.226669 -68.352409) (xy 132.181045 -68.286859) (xy 132.142286 -68.217029) (xy 132.110791 -68.143636)
			(xy 132.086882 -68.067434) (xy 132.070805 -67.989204) (xy 132.062725 -67.909749) (xy 131.637512 -67.909749)
			(xy 131.637504 -67.91037) (xy 131.629176 -67.991048) (xy 131.612599 -68.070443) (xy 131.58795 -68.147713)
			(xy 131.555489 -68.222041) (xy 131.51556 -68.292638) (xy 131.492498 -68.326) (xy 131.469209 -68.357955)
			(xy 131.417194 -68.417517) (xy 131.359475 -68.471569) (xy 131.29663 -68.519566) (xy 131.229294 -68.561026)
			(xy 131.158143 -68.595533) (xy 131.083894 -68.622738) (xy 131.007292 -68.642368) (xy 130.929109 -68.654225)
			(xy 130.850132 -68.658191) (xy 130.771155 -68.654225) (xy 130.692972 -68.642368) (xy 130.61637 -68.622738)
			(xy 130.542121 -68.595533) (xy 130.47097 -68.561026) (xy 130.403634 -68.519566) (xy 130.340789 -68.471569)
			(xy 130.28307 -68.417517) (xy 130.231055 -68.357955) (xy 130.207766 -68.326) (xy 130.184702 -68.29264)
			(xy 130.144775 -68.22204) (xy 130.112314 -68.147712) (xy 130.087663 -68.070442) (xy 130.071081 -67.991048)
			(xy 130.062746 -67.91037) (xy 130.062224 -67.869816) (xy 103.637842 -67.869816) (xy 103.637196 -67.913377)
			(xy 103.627494 -67.999959) (xy 103.608287 -68.084939) (xy 103.579811 -68.167278) (xy 103.561642 -68.206874)
			(xy 103.559102 -68.212208) (xy 103.556816 -68.222876) (xy 103.556816 -68.246244) (xy 103.557184 -68.255712)
			(xy 103.564119 -68.273332) (xy 103.570278 -68.280534) (xy 103.625904 -68.340986) (xy 103.633424 -68.348389)
			(xy 103.652705 -68.356913) (xy 103.663242 -68.357496) (xy 103.684578 -68.357496) (xy 103.693214 -68.354194)
			(xy 103.755279 -68.331259) (xy 103.881647 -68.291988) (xy 104.010151 -68.260397) (xy 104.140323 -68.236601)
			(xy 104.271692 -68.220685) (xy 104.403781 -68.212708) (xy 104.469946 -68.212208) (xy 104.536864 -68.21268)
			(xy 104.670452 -68.220827) (xy 104.803296 -68.23709) (xy 104.934905 -68.261407) (xy 105.06479 -68.293688)
			(xy 105.192469 -68.333814) (xy 105.31747 -68.381636) (xy 105.439328 -68.436977) (xy 105.557593 -68.499631)
			(xy 105.671826 -68.569366) (xy 105.781603 -68.645924) (xy 105.886517 -68.729021) (xy 105.98618 -68.818349)
			(xy 106.080222 -68.913576) (xy 106.168294 -69.01435) (xy 106.25007 -69.120297) (xy 106.288078 -69.175376)
			(xy 106.290872 -69.17944) (xy 106.298238 -69.186806) (xy 106.30563 -69.193656) (xy 106.324235 -69.20137)
			(xy 106.334306 -69.201792) (xy 106.415586 -69.201792) (xy 106.425655 -69.201361) (xy 106.444253 -69.193645)
			(xy 106.451654 -69.186806) (xy 106.45902 -69.17944) (xy 106.461814 -69.175376) (xy 106.499791 -69.120276)
			(xy 106.58157 -69.014331) (xy 106.669645 -68.913559) (xy 106.763689 -68.818334) (xy 106.863355 -68.729009)
			(xy 106.968272 -68.645915) (xy 107.078052 -68.56936) (xy 107.192287 -68.499628) (xy 107.310554 -68.436978)
			(xy 107.432415 -68.381641) (xy 107.557417 -68.333824) (xy 107.685098 -68.293702) (xy 107.814984 -68.261426)
			(xy 107.946594 -68.237114) (xy 108.079439 -68.220856) (xy 108.213028 -68.212714) (xy 108.279946 -68.212208)
			(xy 108.2802 -68.212208) (xy 108.346806 -68.212727) (xy 108.479773 -68.220793) (xy 108.612007 -68.236902)
			(xy 108.743022 -68.260993) (xy 108.872336 -68.292979) (xy 108.999475 -68.332742) (xy 109.12397 -68.380136)
			(xy 109.245365 -68.434986) (xy 109.363213 -68.497092) (xy 109.420406 -68.531232) (xy 109.42066 -68.531486)
			(xy 109.429906 -68.536368) (xy 109.450624 -68.538999) (xy 109.460792 -68.536566) (xy 109.54258 -68.51269)
			(xy 109.558836 -68.498974) (xy 109.563662 -68.489322) (xy 109.582312 -68.452431) (xy 109.625501 -68.381941)
			(xy 109.675039 -68.315758) (xy 109.730499 -68.254452) (xy 109.791402 -68.198551) (xy 109.857226 -68.148536)
			(xy 109.927402 -68.104838) (xy 110.001327 -68.067833) (xy 110.078363 -68.037841) (xy 110.157848 -68.015119)
			(xy 110.239098 -67.999862) (xy 110.321411 -67.992203) (xy 110.362746 -67.991736) (xy 110.405062 -67.99221)
			(xy 110.489311 -68.000245) (xy 110.572415 -68.016248) (xy 110.653623 -68.040074) (xy 110.7322 -68.071508)
			(xy 110.807436 -68.110264) (xy 110.843314 -68.132706) (xy 110.851703 -68.137589) (xy 110.870746 -68.14126)
			(xy 110.889789 -68.137589) (xy 110.898178 -68.132706) (xy 110.93406 -68.110273) (xy 111.0093 -68.071533)
			(xy 111.087878 -68.040113) (xy 111.169085 -68.016295) (xy 111.252187 -68.000296) (xy 111.336432 -67.992261)
			(xy 111.42106 -67.992261) (xy 111.505305 -68.000296) (xy 111.588407 -68.016295) (xy 111.669614 -68.040113)
			(xy 111.748192 -68.071533) (xy 111.823432 -68.110273) (xy 111.859314 -68.132706) (xy 111.867703 -68.137589)
			(xy 111.886746 -68.14126) (xy 111.905789 -68.137589) (xy 111.914178 -68.132706) (xy 111.950069 -68.110288)
			(xy 112.025305 -68.07154) (xy 112.103881 -68.040112) (xy 112.185086 -68.016287) (xy 112.268187 -68.000282)
			(xy 112.352432 -67.99224) (xy 112.394746 -67.991736) (xy 112.435851 -67.992123) (xy 112.517709 -67.999712)
			(xy 112.598517 -68.014822) (xy 112.677587 -68.037324) (xy 112.754243 -68.067025) (xy 112.827832 -68.103673)
			(xy 112.897725 -68.146954) (xy 112.963327 -68.196499) (xy 113.024077 -68.251886) (xy 113.079458 -68.312642)
			(xy 113.128997 -68.378249) (xy 113.172271 -68.448147) (xy 113.208911 -68.521739) (xy 113.238605 -68.598399)
			(xy 113.261098 -68.677471) (xy 113.2762 -68.758281) (xy 113.283781 -68.840139) (xy 113.284254 -68.881244)
			(xy 113.283765 -68.923559) (xy 113.275731 -69.007807) (xy 113.25973 -69.090911) (xy 113.235906 -69.172119)
			(xy 113.204476 -69.250697) (xy 113.165723 -69.325933) (xy 113.143284 -69.361812) (xy 113.138369 -69.370184)
			(xy 113.134713 -69.389237) (xy 113.138396 -69.408286) (xy 113.143284 -69.416676) (xy 113.165756 -69.452534)
			(xy 113.204494 -69.527777) (xy 113.235913 -69.606359) (xy 113.259727 -69.687569) (xy 113.275723 -69.770674)
			(xy 113.283756 -69.854922) (xy 113.283752 -69.939552) (xy 113.275713 -70.023799) (xy 113.25971 -70.106903)
			(xy 113.235888 -70.188111) (xy 113.204463 -70.26669) (xy 113.165719 -70.34193) (xy 113.143284 -70.377812)
			(xy 113.138369 -70.386184) (xy 113.134713 -70.405237) (xy 113.135598 -70.409816) (xy 123.730009 -70.409816)
			(xy 123.734036 -70.293213) (xy 123.746098 -70.177166) (xy 123.766137 -70.062228) (xy 123.794059 -69.948946)
			(xy 123.829729 -69.83786) (xy 123.872978 -69.7295) (xy 123.923601 -69.624382) (xy 123.981354 -69.523007)
			(xy 124.045965 -69.425858) (xy 124.117123 -69.333398) (xy 124.194491 -69.246067) (xy 124.2777 -69.164283)
			(xy 124.366353 -69.088434) (xy 124.460027 -69.018882) (xy 124.558277 -68.955958) (xy 124.660634 -68.899962)
			(xy 124.76661 -68.851162) (xy 124.875701 -68.80979) (xy 124.987385 -68.776042) (xy 125.101132 -68.75008)
			(xy 125.2164 -68.732027) (xy 125.332638 -68.72197) (xy 125.449292 -68.719956) (xy 125.565808 -68.725995)
			(xy 125.68163 -68.740059) (xy 125.796205 -68.762079) (xy 125.908988 -68.791952) (xy 126.019442 -68.829534)
			(xy 126.127039 -68.874648) (xy 126.231268 -68.927077) (xy 126.331631 -68.986572) (xy 126.42765 -69.052849)
			(xy 126.518868 -69.125593) (xy 126.60485 -69.204457) (xy 126.685187 -69.289065) (xy 126.759494 -69.379014)
			(xy 126.827419 -69.473875) (xy 126.888638 -69.573196) (xy 126.942858 -69.676504) (xy 126.989822 -69.783307)
			(xy 127.029305 -69.893095) (xy 127.06112 -70.005346) (xy 127.085115 -70.119524) (xy 127.101175 -70.235086)
			(xy 127.109224 -70.35148) (xy 127.109728 -70.409816) (xy 127.540009 -70.409816) (xy 127.544036 -70.293213)
			(xy 127.556098 -70.177166) (xy 127.576137 -70.062228) (xy 127.604059 -69.948946) (xy 127.639729 -69.83786)
			(xy 127.682978 -69.7295) (xy 127.733601 -69.624382) (xy 127.791354 -69.523007) (xy 127.855965 -69.425858)
			(xy 127.927123 -69.333398) (xy 128.004491 -69.246067) (xy 128.0877 -69.164283) (xy 128.176353 -69.088434)
			(xy 128.270027 -69.018882) (xy 128.368277 -68.955958) (xy 128.470634 -68.899962) (xy 128.57661 -68.851162)
			(xy 128.685701 -68.80979) (xy 128.797385 -68.776042) (xy 128.911132 -68.75008) (xy 129.0264 -68.732027)
			(xy 129.142638 -68.72197) (xy 129.259292 -68.719956) (xy 129.375808 -68.725995) (xy 129.49163 -68.740059)
			(xy 129.606205 -68.762079) (xy 129.718988 -68.791952) (xy 129.829442 -68.829534) (xy 129.937039 -68.874648)
			(xy 130.041268 -68.927077) (xy 130.141631 -68.986572) (xy 130.23765 -69.052849) (xy 130.328868 -69.125593)
			(xy 130.41485 -69.204457) (xy 130.495187 -69.289065) (xy 130.569494 -69.379014) (xy 130.637419 -69.473875)
			(xy 130.698638 -69.573196) (xy 130.752858 -69.676504) (xy 130.799822 -69.783307) (xy 130.839305 -69.893095)
			(xy 130.87112 -70.005346) (xy 130.895115 -70.119524) (xy 130.911175 -70.235086) (xy 130.919224 -70.35148)
			(xy 130.919728 -70.409816) (xy 130.919224 -70.468152) (xy 130.911175 -70.584546) (xy 130.895115 -70.700108)
			(xy 130.87112 -70.814286) (xy 130.839305 -70.926537) (xy 130.799822 -71.036325) (xy 130.752858 -71.143128)
			(xy 130.698638 -71.246436) (xy 130.637419 -71.345757) (xy 130.569494 -71.440618) (xy 130.495187 -71.530567)
			(xy 130.41485 -71.615175) (xy 130.328868 -71.694039) (xy 130.23765 -71.766783) (xy 130.141631 -71.83306)
			(xy 130.041268 -71.892555) (xy 129.937039 -71.944984) (xy 129.829442 -71.990098) (xy 129.718988 -72.02768)
			(xy 129.606205 -72.057553) (xy 129.49163 -72.079573) (xy 129.375808 -72.093637) (xy 129.259292 -72.099676)
			(xy 129.142638 -72.097662) (xy 129.0264 -72.087605) (xy 128.911132 -72.069552) (xy 128.797385 -72.04359)
			(xy 128.685701 -72.009842) (xy 128.57661 -71.96847) (xy 128.470634 -71.91967) (xy 128.368277 -71.863674)
			(xy 128.270027 -71.80075) (xy 128.176353 -71.731198) (xy 128.0877 -71.655349) (xy 128.004491 -71.573565)
			(xy 127.927123 -71.486234) (xy 127.855965 -71.393774) (xy 127.791354 -71.296625) (xy 127.733601 -71.19525)
			(xy 127.682978 -71.090132) (xy 127.639729 -70.981772) (xy 127.604059 -70.870686) (xy 127.576137 -70.757404)
			(xy 127.556098 -70.642466) (xy 127.544036 -70.526419) (xy 127.540009 -70.409816) (xy 127.109728 -70.409816)
			(xy 127.109224 -70.468152) (xy 127.101175 -70.584546) (xy 127.085115 -70.700108) (xy 127.06112 -70.814286)
			(xy 127.029305 -70.926537) (xy 126.989822 -71.036325) (xy 126.942858 -71.143128) (xy 126.888638 -71.246436)
			(xy 126.827419 -71.345757) (xy 126.759494 -71.440618) (xy 126.685187 -71.530567) (xy 126.60485 -71.615175)
			(xy 126.518868 -71.694039) (xy 126.42765 -71.766783) (xy 126.331631 -71.83306) (xy 126.231268 -71.892555)
			(xy 126.127039 -71.944984) (xy 126.019442 -71.990098) (xy 125.908988 -72.02768) (xy 125.796205 -72.057553)
			(xy 125.68163 -72.079573) (xy 125.565808 -72.093637) (xy 125.449292 -72.099676) (xy 125.332638 -72.097662)
			(xy 125.2164 -72.087605) (xy 125.101132 -72.069552) (xy 124.987385 -72.04359) (xy 124.875701 -72.009842)
			(xy 124.76661 -71.96847) (xy 124.660634 -71.91967) (xy 124.558277 -71.863674) (xy 124.460027 -71.80075)
			(xy 124.366353 -71.731198) (xy 124.2777 -71.655349) (xy 124.194491 -71.573565) (xy 124.117123 -71.486234)
			(xy 124.045965 -71.393774) (xy 123.981354 -71.296625) (xy 123.923601 -71.19525) (xy 123.872978 -71.090132)
			(xy 123.829729 -70.981772) (xy 123.794059 -70.870686) (xy 123.766137 -70.757404) (xy 123.746098 -70.642466)
			(xy 123.734036 -70.526419) (xy 123.730009 -70.409816) (xy 113.135598 -70.409816) (xy 113.138396 -70.424286)
			(xy 113.143284 -70.432676) (xy 113.165756 -70.468534) (xy 113.204494 -70.543777) (xy 113.235913 -70.622359)
			(xy 113.259727 -70.703569) (xy 113.275723 -70.786674) (xy 113.283756 -70.870922) (xy 113.283752 -70.955552)
			(xy 113.275713 -71.039799) (xy 113.25971 -71.122903) (xy 113.235888 -71.204111) (xy 113.204463 -71.28269)
			(xy 113.165719 -71.35793) (xy 113.143284 -71.393812) (xy 113.138369 -71.402184) (xy 113.134713 -71.421237)
			(xy 113.138396 -71.440286) (xy 113.143284 -71.448676) (xy 113.165712 -71.484561) (xy 113.204457 -71.559799)
			(xy 113.235882 -71.638377) (xy 113.259705 -71.719583) (xy 113.275709 -71.802684) (xy 113.28375 -71.88693)
			(xy 113.284254 -71.929244) (xy 113.283775 -71.970346) (xy 113.276187 -72.052199) (xy 113.261079 -72.133002)
			(xy 113.23858 -72.212067) (xy 113.208883 -72.288719) (xy 113.17224 -72.362304) (xy 113.128965 -72.432195)
			(xy 113.079425 -72.497794) (xy 113.024045 -72.558543) (xy 112.963296 -72.613924) (xy 112.897696 -72.663463)
			(xy 112.827806 -72.706739) (xy 112.754221 -72.743382) (xy 112.677569 -72.77308) (xy 112.598504 -72.795579)
			(xy 112.517701 -72.810687) (xy 112.435848 -72.818275) (xy 112.394746 -72.818752) (xy 112.352431 -72.818268)
			(xy 112.268182 -72.810233) (xy 112.185079 -72.794231) (xy 112.103871 -72.770407) (xy 112.025293 -72.738975)
			(xy 111.950057 -72.700222) (xy 111.914178 -72.677782) (xy 111.905789 -72.672899) (xy 111.886746 -72.669228)
			(xy 111.867703 -72.672899) (xy 111.859314 -72.677782) (xy 111.823432 -72.700215) (xy 111.748192 -72.738955)
			(xy 111.669614 -72.770375) (xy 111.588407 -72.794193) (xy 111.505305 -72.810192) (xy 111.42106 -72.818227)
			(xy 111.336432 -72.818227) (xy 111.252187 -72.810192) (xy 111.169085 -72.794193) (xy 111.087878 -72.770375)
			(xy 111.0093 -72.738955) (xy 110.93406 -72.700215) (xy 110.898178 -72.677782) (xy 110.889789 -72.672899)
			(xy 110.870746 -72.669228) (xy 110.851703 -72.672899) (xy 110.843314 -72.677782) (xy 110.807431 -72.700214)
			(xy 110.732192 -72.738958) (xy 110.653615 -72.770383) (xy 110.572408 -72.794205) (xy 110.489306 -72.810208)
			(xy 110.40506 -72.818248) (xy 110.362746 -72.818752) (xy 110.322099 -72.818316) (xy 110.241143 -72.810902)
			(xy 110.161204 -72.796122) (xy 110.082949 -72.7741) (xy 110.007033 -72.745021) (xy 109.934092 -72.709127)
			(xy 109.864736 -72.666719) (xy 109.799544 -72.618152) (xy 109.739062 -72.563831) (xy 109.683796 -72.504212)
			(xy 109.634209 -72.439793) (xy 109.590714 -72.371112) (xy 109.57179 -72.335136) (xy 109.56798 -72.328024)
			(xy 109.552232 -72.312276) (xy 109.52734 -72.300084) (xy 109.523276 -72.298052) (xy 109.45368 -72.277986)
			(xy 109.432852 -72.28078) (xy 109.423708 -72.286368) (xy 109.366385 -72.320737) (xy 109.248224 -72.383231)
			(xy 109.126483 -72.438429) (xy 109.001612 -72.486125) (xy 108.874074 -72.526143) (xy 108.744338 -72.558337)
			(xy 108.612886 -72.582585) (xy 108.480204 -72.5988) (xy 108.346781 -72.606921) (xy 108.279946 -72.607424)
			(xy 108.213028 -72.606945) (xy 108.079441 -72.598797) (xy 107.946597 -72.582534) (xy 107.814989 -72.558217)
			(xy 107.685104 -72.525935) (xy 107.557425 -72.48581) (xy 107.432425 -72.437988) (xy 107.310566 -72.382648)
			(xy 107.192302 -72.319994) (xy 107.078069 -72.25026) (xy 106.968292 -72.173703) (xy 106.863377 -72.090607)
			(xy 106.763714 -72.00128) (xy 106.669672 -71.906053) (xy 106.581599 -71.80528) (xy 106.499823 -71.699334)
			(xy 106.461814 -71.644256) (xy 106.45902 -71.640192) (xy 106.451654 -71.632826) (xy 106.444226 -71.626021)
			(xy 106.425648 -71.61828) (xy 106.415586 -71.61784) (xy 106.334306 -71.61784) (xy 106.324236 -71.618258)
			(xy 106.305637 -71.625983) (xy 106.298238 -71.632826) (xy 106.290872 -71.640192) (xy 106.288078 -71.644256)
			(xy 106.250083 -71.699344) (xy 106.168307 -71.80529) (xy 106.080234 -71.906064) (xy 105.986192 -72.00129)
			(xy 105.886528 -72.090617) (xy 105.781612 -72.173712) (xy 105.671834 -72.250268) (xy 105.5576 -72.320001)
			(xy 105.439334 -72.382652) (xy 105.317474 -72.43799) (xy 105.192472 -72.485808) (xy 105.064792 -72.52593)
			(xy 104.934906 -72.558207) (xy 104.803297 -72.582519) (xy 104.670452 -72.598776) (xy 104.536864 -72.606918)
			(xy 104.469946 -72.607424) (xy 104.403557 -72.606872) (xy 104.271021 -72.598858) (xy 104.139211 -72.582856)
			(xy 104.008607 -72.558924) (xy 103.879687 -72.527151) (xy 103.75292 -72.487651) (xy 103.628769 -72.44057)
			(xy 103.507688 -72.386078) (xy 103.390118 -72.324375) (xy 103.276488 -72.255686) (xy 103.167212 -72.180261)
			(xy 103.06269 -72.098376) (xy 102.963303 -72.010329) (xy 102.869414 -71.916442) (xy 102.781364 -71.817057)
			(xy 102.699476 -71.712538) (xy 102.624048 -71.603264) (xy 102.555355 -71.489636) (xy 102.493649 -71.372068)
			(xy 102.439154 -71.250988) (xy 102.392069 -71.126839) (xy 102.352566 -71.000073) (xy 102.320789 -70.871154)
			(xy 102.296854 -70.740551) (xy 102.280848 -70.608741) (xy 102.27283 -70.476205) (xy 102.272338 -70.409816)
			(xy 102.272338 -70.409562) (xy 102.272816 -70.34186) (xy 102.281167 -70.206714) (xy 102.297821 -70.072338)
			(xy 102.322716 -69.939242) (xy 102.355758 -69.807931) (xy 102.396821 -69.678904) (xy 102.445749 -69.552649)
			(xy 102.502357 -69.429645) (xy 102.566429 -69.31036) (xy 102.637724 -69.195246) (xy 102.71597 -69.084739)
			(xy 102.80087 -68.979258) (xy 102.892104 -68.879204) (xy 102.940358 -68.831714) (xy 102.947336 -68.824338)
			(xy 102.955245 -68.805655) (xy 102.95529 -68.785366) (xy 102.951788 -68.775834) (xy 102.913688 -68.683886)
			(xy 102.909878 -68.678806) (xy 102.902004 -68.668138) (xy 102.879906 -68.657216) (xy 102.867714 -68.65747)
			(xy 102.862888 -68.65747) (xy 102.850696 -68.657724) (xy 102.849934 -68.657724) (xy 102.810424 -68.65726)
			(xy 102.7318 -68.649353) (xy 102.654362 -68.633617) (xy 102.578888 -68.610208) (xy 102.506136 -68.579362)
			(xy 102.436838 -68.541388) (xy 102.371689 -68.496669) (xy 102.311343 -68.445653) (xy 102.256406 -68.388853)
			(xy 102.207431 -68.326839) (xy 102.16491 -68.260235) (xy 102.129268 -68.189708) (xy 102.100866 -68.115968)
			(xy 102.079987 -68.039756) (xy 102.066842 -67.961836) (xy 102.061562 -67.882992) (xy 101.637679 -67.882992)
			(xy 101.637341 -67.909749) (xy 101.629261 -67.989204) (xy 101.613184 -68.067434) (xy 101.589275 -68.143636)
			(xy 101.55778 -68.217029) (xy 101.519021 -68.286859) (xy 101.473397 -68.352409) (xy 101.421375 -68.413008)
			(xy 101.36349 -68.468032) (xy 101.300334 -68.516918) (xy 101.232557 -68.559164) (xy 101.160854 -68.594336)
			(xy 101.08596 -68.622073) (xy 101.008645 -68.642092) (xy 100.929701 -68.654185) (xy 100.849938 -68.658231)
			(xy 100.770175 -68.654185) (xy 100.691231 -68.642092) (xy 100.613916 -68.622073) (xy 100.539022 -68.594336)
			(xy 100.467319 -68.559164) (xy 100.399542 -68.516918) (xy 100.336386 -68.468032) (xy 100.278501 -68.413008)
			(xy 100.226479 -68.352409) (xy 100.180855 -68.286859) (xy 100.142096 -68.217029) (xy 100.110601 -68.143636)
			(xy 100.086692 -68.067434) (xy 100.070615 -67.989204) (xy 100.062535 -67.909749) (xy 99.637345 -67.909749)
			(xy 99.629265 -67.989204) (xy 99.613188 -68.067434) (xy 99.589279 -68.143636) (xy 99.557784 -68.217029)
			(xy 99.519025 -68.286859) (xy 99.473401 -68.352409) (xy 99.421379 -68.413008) (xy 99.363494 -68.468032)
			(xy 99.300338 -68.516918) (xy 99.232561 -68.559164) (xy 99.160858 -68.594336) (xy 99.085964 -68.622073)
			(xy 99.008649 -68.642092) (xy 98.929705 -68.654185) (xy 98.849942 -68.658231) (xy 98.770179 -68.654185)
			(xy 98.691235 -68.642092) (xy 98.61392 -68.622073) (xy 98.539026 -68.594336) (xy 98.467323 -68.559164)
			(xy 98.399546 -68.516918) (xy 98.33639 -68.468032) (xy 98.278505 -68.413008) (xy 98.226483 -68.352409)
			(xy 98.180859 -68.286859) (xy 98.1421 -68.217029) (xy 98.110605 -68.143636) (xy 98.086696 -68.067434)
			(xy 98.070619 -67.989204) (xy 98.062539 -67.909749) (xy 97.637349 -67.909749) (xy 97.629269 -67.989204)
			(xy 97.613192 -68.067434) (xy 97.589283 -68.143636) (xy 97.557788 -68.217029) (xy 97.519029 -68.286859)
			(xy 97.473405 -68.352409) (xy 97.421383 -68.413008) (xy 97.363498 -68.468032) (xy 97.300342 -68.516918)
			(xy 97.232565 -68.559164) (xy 97.160862 -68.594336) (xy 97.085968 -68.622073) (xy 97.008653 -68.642092)
			(xy 96.929709 -68.654185) (xy 96.849946 -68.658231) (xy 96.770183 -68.654185) (xy 96.691239 -68.642092)
			(xy 96.613924 -68.622073) (xy 96.53903 -68.594336) (xy 96.467327 -68.559164) (xy 96.39955 -68.516918)
			(xy 96.336394 -68.468032) (xy 96.278509 -68.413008) (xy 96.226487 -68.352409) (xy 96.180863 -68.286859)
			(xy 96.142104 -68.217029) (xy 96.110609 -68.143636) (xy 96.0867 -68.067434) (xy 96.070623 -67.989204)
			(xy 96.062543 -67.909749) (xy 95.637353 -67.909749) (xy 95.629273 -67.989204) (xy 95.613196 -68.067434)
			(xy 95.589287 -68.143636) (xy 95.557792 -68.217029) (xy 95.519033 -68.286859) (xy 95.473409 -68.352409)
			(xy 95.421387 -68.413008) (xy 95.363502 -68.468032) (xy 95.300346 -68.516918) (xy 95.232569 -68.559164)
			(xy 95.160866 -68.594336) (xy 95.085972 -68.622073) (xy 95.008657 -68.642092) (xy 94.929713 -68.654185)
			(xy 94.84995 -68.658231) (xy 94.770187 -68.654185) (xy 94.691243 -68.642092) (xy 94.613928 -68.622073)
			(xy 94.539034 -68.594336) (xy 94.467331 -68.559164) (xy 94.399554 -68.516918) (xy 94.336398 -68.468032)
			(xy 94.278513 -68.413008) (xy 94.226491 -68.352409) (xy 94.180867 -68.286859) (xy 94.142108 -68.217029)
			(xy 94.110613 -68.143636) (xy 94.086704 -68.067434) (xy 94.070627 -67.989204) (xy 94.062547 -67.909749)
			(xy 93.637357 -67.909749) (xy 93.629277 -67.989204) (xy 93.6132 -68.067434) (xy 93.589291 -68.143636)
			(xy 93.557796 -68.217029) (xy 93.519037 -68.286859) (xy 93.473413 -68.352409) (xy 93.421391 -68.413008)
			(xy 93.363506 -68.468032) (xy 93.30035 -68.516918) (xy 93.232573 -68.559164) (xy 93.16087 -68.594336)
			(xy 93.085976 -68.622073) (xy 93.008661 -68.642092) (xy 92.929717 -68.654185) (xy 92.849954 -68.658231)
			(xy 92.770191 -68.654185) (xy 92.691247 -68.642092) (xy 92.613932 -68.622073) (xy 92.539038 -68.594336)
			(xy 92.467335 -68.559164) (xy 92.399558 -68.516918) (xy 92.336402 -68.468032) (xy 92.278517 -68.413008)
			(xy 92.226495 -68.352409) (xy 92.180871 -68.286859) (xy 92.142112 -68.217029) (xy 92.110617 -68.143636)
			(xy 92.086708 -68.067434) (xy 92.070631 -67.989204) (xy 92.062551 -67.909749) (xy 91.637361 -67.909749)
			(xy 91.629281 -67.989204) (xy 91.613204 -68.067434) (xy 91.589295 -68.143636) (xy 91.5578 -68.217029)
			(xy 91.519041 -68.286859) (xy 91.473417 -68.352409) (xy 91.421395 -68.413008) (xy 91.36351 -68.468032)
			(xy 91.300354 -68.516918) (xy 91.232577 -68.559164) (xy 91.160874 -68.594336) (xy 91.08598 -68.622073)
			(xy 91.008665 -68.642092) (xy 90.929721 -68.654185) (xy 90.849958 -68.658231) (xy 90.770195 -68.654185)
			(xy 90.691251 -68.642092) (xy 90.613936 -68.622073) (xy 90.539042 -68.594336) (xy 90.467339 -68.559164)
			(xy 90.399562 -68.516918) (xy 90.336406 -68.468032) (xy 90.278521 -68.413008) (xy 90.226499 -68.352409)
			(xy 90.180875 -68.286859) (xy 90.142116 -68.217029) (xy 90.110621 -68.143636) (xy 90.086712 -68.067434)
			(xy 90.070635 -67.989204) (xy 90.062555 -67.909749) (xy 84.840771 -67.909749) (xy 82.340704 -70.409816)
			(xy 83.729835 -70.409816) (xy 83.733862 -70.293213) (xy 83.745924 -70.177166) (xy 83.765963 -70.062228)
			(xy 83.793885 -69.948946) (xy 83.829555 -69.83786) (xy 83.872804 -69.7295) (xy 83.923427 -69.624382)
			(xy 83.98118 -69.523007) (xy 84.045791 -69.425858) (xy 84.116949 -69.333398) (xy 84.194317 -69.246067)
			(xy 84.277526 -69.164283) (xy 84.366179 -69.088434) (xy 84.459853 -69.018882) (xy 84.558103 -68.955958)
			(xy 84.66046 -68.899962) (xy 84.766436 -68.851162) (xy 84.875527 -68.80979) (xy 84.987211 -68.776042)
			(xy 85.100958 -68.75008) (xy 85.216226 -68.732027) (xy 85.332464 -68.72197) (xy 85.449118 -68.719956)
			(xy 85.565634 -68.725995) (xy 85.681456 -68.740059) (xy 85.796031 -68.762079) (xy 85.908814 -68.791952)
			(xy 86.019268 -68.829534) (xy 86.126865 -68.874648) (xy 86.231094 -68.927077) (xy 86.331457 -68.986572)
			(xy 86.427476 -69.052849) (xy 86.518694 -69.125593) (xy 86.604676 -69.204457) (xy 86.685013 -69.289065)
			(xy 86.75932 -69.379014) (xy 86.827245 -69.473875) (xy 86.888464 -69.573196) (xy 86.942684 -69.676504)
			(xy 86.989648 -69.783307) (xy 87.029131 -69.893095) (xy 87.060946 -70.005346) (xy 87.084941 -70.119524)
			(xy 87.101001 -70.235086) (xy 87.10905 -70.35148) (xy 87.109554 -70.409816) (xy 87.539835 -70.409816)
			(xy 87.543862 -70.293213) (xy 87.555924 -70.177166) (xy 87.575963 -70.062228) (xy 87.603885 -69.948946)
			(xy 87.639555 -69.83786) (xy 87.682804 -69.7295) (xy 87.733427 -69.624382) (xy 87.79118 -69.523007)
			(xy 87.855791 -69.425858) (xy 87.926949 -69.333398) (xy 88.004317 -69.246067) (xy 88.087526 -69.164283)
			(xy 88.176179 -69.088434) (xy 88.269853 -69.018882) (xy 88.368103 -68.955958) (xy 88.47046 -68.899962)
			(xy 88.576436 -68.851162) (xy 88.685527 -68.80979) (xy 88.797211 -68.776042) (xy 88.910958 -68.75008)
			(xy 89.026226 -68.732027) (xy 89.142464 -68.72197) (xy 89.259118 -68.719956) (xy 89.375634 -68.725995)
			(xy 89.491456 -68.740059) (xy 89.606031 -68.762079) (xy 89.718814 -68.791952) (xy 89.829268 -68.829534)
			(xy 89.936865 -68.874648) (xy 90.041094 -68.927077) (xy 90.141457 -68.986572) (xy 90.237476 -69.052849)
			(xy 90.328694 -69.125593) (xy 90.414676 -69.204457) (xy 90.495013 -69.289065) (xy 90.56932 -69.379014)
			(xy 90.637245 -69.473875) (xy 90.698464 -69.573196) (xy 90.752684 -69.676504) (xy 90.799648 -69.783307)
			(xy 90.839131 -69.893095) (xy 90.870946 -70.005346) (xy 90.894941 -70.119524) (xy 90.911001 -70.235086)
			(xy 90.91905 -70.35148) (xy 90.919554 -70.409816) (xy 90.91905 -70.468152) (xy 90.911001 -70.584546)
			(xy 90.894941 -70.700108) (xy 90.870946 -70.814286) (xy 90.839131 -70.926537) (xy 90.799648 -71.036325)
			(xy 90.752684 -71.143128) (xy 90.698464 -71.246436) (xy 90.637245 -71.345757) (xy 90.56932 -71.440618)
			(xy 90.495013 -71.530567) (xy 90.414676 -71.615175) (xy 90.328694 -71.694039) (xy 90.237476 -71.766783)
			(xy 90.141457 -71.83306) (xy 90.041094 -71.892555) (xy 89.936865 -71.944984) (xy 89.829268 -71.990098)
			(xy 89.718814 -72.02768) (xy 89.606031 -72.057553) (xy 89.491456 -72.079573) (xy 89.375634 -72.093637)
			(xy 89.259118 -72.099676) (xy 89.142464 -72.097662) (xy 89.026226 -72.087605) (xy 88.910958 -72.069552)
			(xy 88.797211 -72.04359) (xy 88.685527 -72.009842) (xy 88.576436 -71.96847) (xy 88.47046 -71.91967)
			(xy 88.368103 -71.863674) (xy 88.269853 -71.80075) (xy 88.176179 -71.731198) (xy 88.087526 -71.655349)
			(xy 88.004317 -71.573565) (xy 87.926949 -71.486234) (xy 87.855791 -71.393774) (xy 87.79118 -71.296625)
			(xy 87.733427 -71.19525) (xy 87.682804 -71.090132) (xy 87.639555 -70.981772) (xy 87.603885 -70.870686)
			(xy 87.575963 -70.757404) (xy 87.555924 -70.642466) (xy 87.543862 -70.526419) (xy 87.539835 -70.409816)
			(xy 87.109554 -70.409816) (xy 87.10905 -70.468152) (xy 87.101001 -70.584546) (xy 87.084941 -70.700108)
			(xy 87.060946 -70.814286) (xy 87.029131 -70.926537) (xy 86.989648 -71.036325) (xy 86.942684 -71.143128)
			(xy 86.888464 -71.246436) (xy 86.827245 -71.345757) (xy 86.75932 -71.440618) (xy 86.685013 -71.530567)
			(xy 86.604676 -71.615175) (xy 86.518694 -71.694039) (xy 86.427476 -71.766783) (xy 86.331457 -71.83306)
			(xy 86.231094 -71.892555) (xy 86.126865 -71.944984) (xy 86.019268 -71.990098) (xy 85.908814 -72.02768)
			(xy 85.796031 -72.057553) (xy 85.681456 -72.079573) (xy 85.565634 -72.093637) (xy 85.449118 -72.099676)
			(xy 85.332464 -72.097662) (xy 85.216226 -72.087605) (xy 85.100958 -72.069552) (xy 84.987211 -72.04359)
			(xy 84.875527 -72.009842) (xy 84.766436 -71.96847) (xy 84.66046 -71.91967) (xy 84.558103 -71.863674)
			(xy 84.459853 -71.80075) (xy 84.366179 -71.731198) (xy 84.277526 -71.655349) (xy 84.194317 -71.573565)
			(xy 84.116949 -71.486234) (xy 84.045791 -71.393774) (xy 83.98118 -71.296625) (xy 83.923427 -71.19525)
			(xy 83.872804 -71.090132) (xy 83.829555 -70.981772) (xy 83.793885 -70.870686) (xy 83.765963 -70.757404)
			(xy 83.745924 -70.642466) (xy 83.733862 -70.526419) (xy 83.729835 -70.409816) (xy 82.340704 -70.409816)
			(xy 78.632812 -74.117708) (xy 78.625414 -74.124555) (xy 78.606816 -74.132293) (xy 78.596744 -74.132694)
			(xy 60.625482 -74.132694) (xy 60.615413 -74.132267) (xy 60.596814 -74.124548) (xy 60.589414 -74.117708)
			(xy 59.405266 -72.933306) (xy 59.398411 -72.925911) (xy 59.390664 -72.907312) (xy 59.39028 -72.897238)
			(xy 59.39028 -69.698362) (xy 59.389849 -69.688295) (xy 59.382123 -69.669703) (xy 59.375294 -69.662294)
			(xy 58.866786 -69.153786) (xy 58.859674 -69.14642) (xy 58.840878 -69.1388) (xy 51.075082 -69.1388)
			(xy 51.065013 -69.139227) (xy 51.046414 -69.146946) (xy 51.039014 -69.153786) (xy 50.91557 -69.27723)
			(xy 50.908204 -69.284342) (xy 50.900584 -69.303138) (xy 50.900584 -70.143624) (xy 50.910459 -70.209729)
			(xy 50.921017 -70.342981) (xy 50.921666 -70.409816) (xy 50.921173 -70.467587) (xy 50.913288 -70.582861)
			(xy 50.897555 -70.697327) (xy 50.874047 -70.810453) (xy 50.842874 -70.921711) (xy 50.804181 -71.030582)
			(xy 50.758149 -71.136559) (xy 50.704992 -71.239148) (xy 50.644958 -71.33787) (xy 50.578327 -71.432265)
			(xy 50.505409 -71.521892) (xy 50.426545 -71.606335) (xy 50.342102 -71.685199) (xy 50.252475 -71.758117)
			(xy 50.15808 -71.824748) (xy 50.059358 -71.884782) (xy 49.956769 -71.937939) (xy 49.850792 -71.983971)
			(xy 49.741921 -72.022664) (xy 49.630663 -72.053837) (xy 49.517537 -72.077345) (xy 49.403071 -72.093078)
			(xy 49.287797 -72.100963) (xy 49.172255 -72.100963) (xy 49.056981 -72.093078) (xy 48.942515 -72.077345)
			(xy 48.829389 -72.053837) (xy 48.718131 -72.022664) (xy 48.60926 -71.983971) (xy 48.503283 -71.937939)
			(xy 48.400694 -71.884782) (xy 48.301972 -71.824748) (xy 48.207577 -71.758117) (xy 48.11795 -71.685199)
			(xy 48.033507 -71.606335) (xy 47.954643 -71.521892) (xy 47.881725 -71.432265) (xy 47.815094 -71.33787)
			(xy 47.75506 -71.239148) (xy 47.701903 -71.136559) (xy 47.655871 -71.030582) (xy 47.617178 -70.921711)
			(xy 47.586005 -70.810453) (xy 47.562497 -70.697327) (xy 47.546764 -70.582861) (xy 47.538879 -70.467587)
			(xy 47.538386 -70.409816) (xy 47.538902 -70.350826) (xy 47.547128 -70.233132) (xy 47.563534 -70.116297)
			(xy 47.58804 -70.00089) (xy 47.620527 -69.88747) (xy 47.660838 -69.776589) (xy 47.708776 -69.668787)
			(xy 47.764109 -69.564586) (xy 47.826567 -69.464494) (xy 47.895847 -69.368996) (xy 47.971612 -69.278558)
			(xy 48.053494 -69.193618) (xy 48.141095 -69.114589) (xy 48.23399 -69.041856) (xy 48.331726 -68.975772)
			(xy 48.433829 -68.916658) (xy 48.539802 -68.864801) (xy 48.594264 -68.842128) (xy 48.601175 -68.835977)
			(xy 48.610442 -68.819981) (xy 48.613459 -68.801742) (xy 48.612044 -68.792598) (xy 48.592486 -68.695062)
			(xy 48.589627 -68.683697) (xy 48.575386 -68.66512) (xy 48.554405 -68.65474) (xy 48.542702 -68.654168)
			(xy 46.10735 -68.654168) (xy 46.09564 -68.654747) (xy 46.074633 -68.665098) (xy 46.060383 -68.683683)
			(xy 46.057566 -68.695062) (xy 46.038008 -68.792598) (xy 46.036231 -68.804162) (xy 46.042135 -68.826774)
			(xy 46.057427 -68.844447) (xy 46.06798 -68.849494) (xy 46.068234 -68.849494) (xy 46.122065 -68.872397)
			(xy 46.226745 -68.924652) (xy 46.327559 -68.984023) (xy 46.424024 -69.050227) (xy 46.515677 -69.122946)
			(xy 46.60208 -69.201831) (xy 46.682819 -69.286505) (xy 46.757506 -69.376562) (xy 46.825783 -69.47157)
			(xy 46.887325 -69.571074) (xy 46.941834 -69.674597) (xy 46.989052 -69.781644) (xy 47.02875 -69.8917)
			(xy 47.060739 -70.00424) (xy 47.084865 -70.118723) (xy 47.101014 -70.2346) (xy 47.109107 -70.351317)
			(xy 47.109634 -70.409816) (xy 47.109142 -70.467518) (xy 47.101266 -70.582653) (xy 47.085552 -70.696982)
			(xy 47.062073 -70.809972) (xy 47.030937 -70.921096) (xy 46.992291 -71.029837) (xy 46.946314 -71.135686)
			(xy 46.89322 -71.238152) (xy 46.833258 -71.336755) (xy 46.766707 -71.431037) (xy 46.693877 -71.520557)
			(xy 46.615108 -71.604898) (xy 46.530767 -71.683667) (xy 46.441247 -71.756497) (xy 46.346965 -71.823048)
			(xy 46.248362 -71.88301) (xy 46.145896 -71.936104) (xy 46.040047 -71.982081) (xy 45.931306 -72.020727)
			(xy 45.820182 -72.051863) (xy 45.707192 -72.075342) (xy 45.592863 -72.091056) (xy 45.477728 -72.098932)
			(xy 45.362324 -72.098932) (xy 45.247189 -72.091056) (xy 45.13286 -72.075342) (xy 45.01987 -72.051863)
			(xy 44.908746 -72.020727) (xy 44.800005 -71.982081) (xy 44.694156 -71.936104) (xy 44.59169 -71.88301)
			(xy 44.493087 -71.823048) (xy 44.398805 -71.756497) (xy 44.309285 -71.683667) (xy 44.224944 -71.604898)
			(xy 44.146175 -71.520557) (xy 44.073345 -71.431037) (xy 44.006794 -71.336755) (xy 43.946832 -71.238152)
			(xy 43.893738 -71.135686) (xy 43.847761 -71.029837) (xy 43.809115 -70.921096) (xy 43.777979 -70.809972)
			(xy 43.7545 -70.696982) (xy 43.738786 -70.582653) (xy 43.73091 -70.467518) (xy 43.730418 -70.409816)
			(xy 43.730915 -70.351323) (xy 43.739006 -70.234617) (xy 43.755151 -70.11875) (xy 43.779272 -70.004277)
			(xy 43.811254 -69.891747) (xy 43.850943 -69.781699) (xy 43.898149 -69.67466) (xy 43.952647 -69.571142)
			(xy 44.014174 -69.471643) (xy 44.082437 -69.376638) (xy 44.157109 -69.286582) (xy 44.23783 -69.201907)
			(xy 44.324216 -69.123019) (xy 44.415852 -69.050296) (xy 44.512299 -68.984085) (xy 44.613094 -68.924705)
			(xy 44.717756 -68.872439) (xy 44.771564 -68.849494) (xy 44.772072 -68.849494) (xy 44.78259 -68.8444)
			(xy 44.797858 -68.826739) (xy 44.803779 -68.804157) (xy 44.802044 -68.792598) (xy 44.782486 -68.695062)
			(xy 44.779627 -68.683697) (xy 44.765386 -68.66512) (xy 44.744405 -68.65474) (xy 44.732702 -68.654168)
			(xy 42.710354 -68.654168) (xy 42.691558 -68.661788) (xy 42.684446 -68.669154) (xy 42.102786 -69.250814)
			(xy 42.09542 -69.257926) (xy 42.0878 -69.276722) (xy 42.0878 -75.057) (xy 131.336032 -75.057) (xy 131.340103 -75.001378)
			(xy 131.352229 -74.946941) (xy 131.372152 -74.89485) (xy 131.399448 -74.846215) (xy 131.433534 -74.802072)
			(xy 131.473683 -74.763363) (xy 131.519041 -74.730912) (xy 131.568641 -74.705411) (xy 131.621425 -74.687404)
			(xy 131.676268 -74.677274) (xy 131.732002 -74.675237) (xy 131.787439 -74.681337) (xy 131.841396 -74.695443)
			(xy 131.892725 -74.717255) (xy 131.940331 -74.746309) (xy 131.983199 -74.781984) (xy 132.020416 -74.823521)
			(xy 132.051189 -74.870034) (xy 132.074861 -74.920531) (xy 132.090929 -74.973938) (xy 132.099049 -75.029114)
			(xy 132.099558 -75.057) (xy 175.997106 -75.057) (xy 176.001177 -75.001378) (xy 176.013303 -74.946941)
			(xy 176.033226 -74.89485) (xy 176.060522 -74.846215) (xy 176.094608 -74.802072) (xy 176.134757 -74.763363)
			(xy 176.180115 -74.730912) (xy 176.229715 -74.705411) (xy 176.282499 -74.687404) (xy 176.337342 -74.677274)
			(xy 176.393076 -74.675237) (xy 176.448513 -74.681337) (xy 176.50247 -74.695443) (xy 176.553799 -74.717255)
			(xy 176.601405 -74.746309) (xy 176.644273 -74.781984) (xy 176.663103 -74.803) (xy 183.513982 -74.803)
			(xy 183.518053 -74.747378) (xy 183.530179 -74.692941) (xy 183.550102 -74.64085) (xy 183.577398 -74.592215)
			(xy 183.611484 -74.548072) (xy 183.651633 -74.509363) (xy 183.696991 -74.476912) (xy 183.746591 -74.451411)
			(xy 183.799375 -74.433404) (xy 183.854218 -74.423274) (xy 183.909952 -74.421237) (xy 183.916886 -74.422)
			(xy 206.500728 -74.422) (xy 206.504801 -74.366341) (xy 206.516936 -74.311868) (xy 206.536872 -74.259742)
			(xy 206.564186 -74.211074) (xy 206.598294 -74.166902) (xy 206.638471 -74.128167) (xy 206.683859 -74.095695)
			(xy 206.733491 -74.070177) (xy 206.786311 -74.052158) (xy 206.84119 -74.042021) (xy 206.896961 -74.039983)
			(xy 206.952435 -74.046086) (xy 207.006428 -74.060202) (xy 207.057791 -74.082029) (xy 207.105429 -74.111102)
			(xy 207.148325 -74.146801) (xy 207.185567 -74.188365) (xy 207.216361 -74.234909) (xy 207.240049 -74.28544)
			(xy 207.256127 -74.338882) (xy 207.264253 -74.394096) (xy 207.264762 -74.422) (xy 207.264253 -74.449904)
			(xy 207.256127 -74.505118) (xy 207.240049 -74.55856) (xy 207.216361 -74.609091) (xy 207.185567 -74.655635)
			(xy 207.148325 -74.697199) (xy 207.105429 -74.732898) (xy 207.057791 -74.761971) (xy 207.006428 -74.783798)
			(xy 206.952435 -74.797914) (xy 206.896961 -74.804017) (xy 206.84119 -74.801979) (xy 206.786311 -74.791842)
			(xy 206.733491 -74.773823) (xy 206.683859 -74.748305) (xy 206.638471 -74.715833) (xy 206.598294 -74.677098)
			(xy 206.564186 -74.632926) (xy 206.536872 -74.584258) (xy 206.516936 -74.532132) (xy 206.504801 -74.477659)
			(xy 206.500728 -74.422) (xy 183.916886 -74.422) (xy 183.965389 -74.427337) (xy 184.019346 -74.441443)
			(xy 184.070675 -74.463255) (xy 184.118281 -74.492309) (xy 184.161149 -74.527984) (xy 184.198366 -74.569521)
			(xy 184.229139 -74.616034) (xy 184.252811 -74.666531) (xy 184.268879 -74.719938) (xy 184.276999 -74.775114)
			(xy 184.277508 -74.803) (xy 184.276999 -74.830886) (xy 184.268879 -74.886062) (xy 184.252811 -74.939469)
			(xy 184.229139 -74.989966) (xy 184.198366 -75.036479) (xy 184.161149 -75.078016) (xy 184.118281 -75.113691)
			(xy 184.070675 -75.142745) (xy 184.019346 -75.164557) (xy 183.965389 -75.178663) (xy 183.909952 -75.184763)
			(xy 183.854218 -75.182726) (xy 183.799375 -75.172596) (xy 183.746591 -75.154589) (xy 183.696991 -75.129088)
			(xy 183.651633 -75.096637) (xy 183.611484 -75.057928) (xy 183.577398 -75.013785) (xy 183.550102 -74.96515)
			(xy 183.530179 -74.913059) (xy 183.518053 -74.858622) (xy 183.513982 -74.803) (xy 176.663103 -74.803)
			(xy 176.68149 -74.823521) (xy 176.712263 -74.870034) (xy 176.735935 -74.920531) (xy 176.752003 -74.973938)
			(xy 176.760123 -75.029114) (xy 176.760632 -75.057) (xy 176.760123 -75.084886) (xy 176.752003 -75.140062)
			(xy 176.735935 -75.193469) (xy 176.712263 -75.243966) (xy 176.68149 -75.290479) (xy 176.644273 -75.332016)
			(xy 176.601405 -75.367691) (xy 176.553799 -75.396745) (xy 176.50247 -75.418557) (xy 176.448513 -75.432663)
			(xy 176.393076 -75.438763) (xy 176.337342 -75.436726) (xy 176.282499 -75.426596) (xy 176.229715 -75.408589)
			(xy 176.180115 -75.383088) (xy 176.134757 -75.350637) (xy 176.094608 -75.311928) (xy 176.060522 -75.267785)
			(xy 176.033226 -75.21915) (xy 176.013303 -75.167059) (xy 176.001177 -75.112622) (xy 175.997106 -75.057)
			(xy 132.099558 -75.057) (xy 132.099049 -75.084886) (xy 132.090929 -75.140062) (xy 132.074861 -75.193469)
			(xy 132.051189 -75.243966) (xy 132.020416 -75.290479) (xy 131.983199 -75.332016) (xy 131.940331 -75.367691)
			(xy 131.892725 -75.396745) (xy 131.841396 -75.418557) (xy 131.787439 -75.432663) (xy 131.732002 -75.438763)
			(xy 131.676268 -75.436726) (xy 131.621425 -75.426596) (xy 131.568641 -75.408589) (xy 131.519041 -75.383088)
			(xy 131.473683 -75.350637) (xy 131.433534 -75.311928) (xy 131.399448 -75.267785) (xy 131.372152 -75.21915)
			(xy 131.352229 -75.167059) (xy 131.340103 -75.112622) (xy 131.336032 -75.057) (xy 42.0878 -75.057)
			(xy 42.0878 -75.565) (xy 51.326032 -75.565) (xy 51.330103 -75.509378) (xy 51.342229 -75.454941) (xy 51.362152 -75.40285)
			(xy 51.389448 -75.354215) (xy 51.423534 -75.310072) (xy 51.463683 -75.271363) (xy 51.509041 -75.238912)
			(xy 51.558641 -75.213411) (xy 51.611425 -75.195404) (xy 51.666268 -75.185274) (xy 51.722002 -75.183237)
			(xy 51.777439 -75.189337) (xy 51.831396 -75.203443) (xy 51.882725 -75.225255) (xy 51.930331 -75.254309)
			(xy 51.973199 -75.289984) (xy 52.010416 -75.331521) (xy 52.041189 -75.378034) (xy 52.064861 -75.428531)
			(xy 52.080929 -75.481938) (xy 52.089049 -75.537114) (xy 52.089558 -75.565) (xy 52.089049 -75.592886)
			(xy 52.080929 -75.648062) (xy 52.064861 -75.701469) (xy 52.041189 -75.751966) (xy 52.010416 -75.798479)
			(xy 51.973199 -75.840016) (xy 51.930331 -75.875691) (xy 51.882725 -75.904745) (xy 51.831396 -75.926557)
			(xy 51.777439 -75.940663) (xy 51.722002 -75.946763) (xy 51.666268 -75.944726) (xy 51.611425 -75.934596)
			(xy 51.558641 -75.916589) (xy 51.509041 -75.891088) (xy 51.463683 -75.858637) (xy 51.423534 -75.819928)
			(xy 51.389448 -75.775785) (xy 51.362152 -75.72715) (xy 51.342229 -75.675059) (xy 51.330103 -75.620622)
			(xy 51.326032 -75.565) (xy 42.0878 -75.565) (xy 42.0878 -76.0984) (xy 171.341032 -76.0984) (xy 171.345103 -76.042778)
			(xy 171.357229 -75.988341) (xy 171.377152 -75.93625) (xy 171.404448 -75.887615) (xy 171.438534 -75.843472)
			(xy 171.478683 -75.804763) (xy 171.524041 -75.772312) (xy 171.573641 -75.746811) (xy 171.626425 -75.728804)
			(xy 171.681268 -75.718674) (xy 171.737002 -75.716637) (xy 171.792439 -75.722737) (xy 171.846396 -75.736843)
			(xy 171.897725 -75.758655) (xy 171.945331 -75.787709) (xy 171.988199 -75.823384) (xy 172.025416 -75.864921)
			(xy 172.056189 -75.911434) (xy 172.079861 -75.961931) (xy 172.095929 -76.015338) (xy 172.104049 -76.070514)
			(xy 172.104558 -76.0984) (xy 172.104049 -76.126286) (xy 172.095929 -76.181462) (xy 172.079861 -76.234869)
			(xy 172.056189 -76.285366) (xy 172.025416 -76.331879) (xy 171.988199 -76.373416) (xy 171.945331 -76.409091)
			(xy 171.897725 -76.438145) (xy 171.846396 -76.459957) (xy 171.792439 -76.474063) (xy 171.737002 -76.480163)
			(xy 171.681268 -76.478126) (xy 171.626425 -76.467996) (xy 171.573641 -76.449989) (xy 171.524041 -76.424488)
			(xy 171.478683 -76.392037) (xy 171.438534 -76.353328) (xy 171.404448 -76.309185) (xy 171.377152 -76.26055)
			(xy 171.357229 -76.208459) (xy 171.345103 -76.154022) (xy 171.341032 -76.0984) (xy 42.0878 -76.0984)
			(xy 42.0878 -77.288644) (xy 42.088265 -77.298519) (xy 42.095715 -77.316811) (xy 42.102278 -77.324204)
			(xy 43.405054 -78.62698) (xy 54.609097 -78.62698) (xy 54.611731 -78.54317) (xy 54.62224 -78.459981)
			(xy 54.640532 -78.37815) (xy 54.666443 -78.298403) (xy 54.699744 -78.221449) (xy 54.74014 -78.14797)
			(xy 54.787271 -78.078618) (xy 54.840719 -78.01401) (xy 54.90001 -77.954719) (xy 54.964618 -77.901271)
			(xy 55.03397 -77.85414) (xy 55.107449 -77.813744) (xy 55.184403 -77.780443) (xy 55.26415 -77.754532)
			(xy 55.345981 -77.73624) (xy 55.42917 -77.725731) (xy 55.51298 -77.723097) (xy 55.596665 -77.728362)
			(xy 55.679483 -77.741479) (xy 55.7607 -77.762332) (xy 55.839593 -77.790736) (xy 55.915463 -77.826438)
			(xy 55.987637 -77.869121) (xy 56.055474 -77.918407) (xy 56.118371 -77.973859) (xy 56.175771 -78.034983)
			(xy 56.227163 -78.101238) (xy 56.272093 -78.172036) (xy 56.31016 -78.246747) (xy 56.341028 -78.324709)
			(xy 56.364421 -78.405231) (xy 56.380133 -78.487596) (xy 56.388024 -78.571075) (xy 56.388508 -78.613)
			(xy 56.388508 -78.61427) (xy 56.38838 -78.626945) (xy 56.761847 -78.626945) (xy 56.764484 -78.543142)
			(xy 56.774995 -78.459959) (xy 56.793288 -78.378133) (xy 56.8192 -78.298393) (xy 56.852502 -78.221445)
			(xy 56.892897 -78.147972) (xy 56.940027 -78.078627) (xy 56.993473 -78.014025) (xy 57.052762 -77.95474)
			(xy 57.117367 -77.901297) (xy 57.186715 -77.85417) (xy 57.26019 -77.81378) (xy 57.33714 -77.780483)
			(xy 57.416882 -77.754575) (xy 57.498708 -77.736286) (xy 57.581892 -77.72578) (xy 57.665695 -77.723148)
			(xy 57.749375 -77.728414) (xy 57.832187 -77.741531) (xy 57.913398 -77.762384) (xy 57.992285 -77.790787)
			(xy 58.06815 -77.826487) (xy 58.140319 -77.869169) (xy 58.20815 -77.918452) (xy 58.271042 -77.9739)
			(xy 58.328438 -78.035021) (xy 58.379826 -78.101272) (xy 58.424752 -78.172065) (xy 58.462817 -78.246772)
			(xy 58.493682 -78.324729) (xy 58.517073 -78.405245) (xy 58.532784 -78.487605) (xy 58.540675 -78.571078)
			(xy 58.541158 -78.613) (xy 58.540647 -78.655348) (xy 59.048646 -78.655348) (xy 59.048646 -78.570652)
			(xy 59.056697 -78.486338) (xy 59.072726 -78.403172) (xy 59.096587 -78.321905) (xy 59.128066 -78.243275)
			(xy 59.166877 -78.167994) (xy 59.212667 -78.096742) (xy 59.265023 -78.030166) (xy 59.323471 -77.968868)
			(xy 59.387481 -77.913403) (xy 59.456473 -77.864274) (xy 59.529823 -77.821925) (xy 59.606866 -77.786741)
			(xy 59.686905 -77.759039) (xy 59.769214 -77.739071) (xy 59.853049 -77.727018) (xy 59.93765 -77.722988)
			(xy 60.022251 -77.727018) (xy 60.106086 -77.739071) (xy 60.188395 -77.759039) (xy 60.191166 -77.759998)
			(xy 61.96101 -77.759998) (xy 61.96101 -77.675302) (xy 61.969061 -77.590988) (xy 61.98509 -77.507822)
			(xy 62.008951 -77.426555) (xy 62.04043 -77.347925) (xy 62.079241 -77.272644) (xy 62.125031 -77.201392)
			(xy 62.177387 -77.134816) (xy 62.235835 -77.073518) (xy 62.299845 -77.018053) (xy 62.368837 -76.968924)
			(xy 62.442187 -76.926575) (xy 62.51923 -76.891391) (xy 62.599269 -76.863689) (xy 62.681578 -76.843721)
			(xy 62.765413 -76.831668) (xy 62.850014 -76.827638) (xy 62.934615 -76.831668) (xy 63.01845 -76.843721)
			(xy 63.100759 -76.863689) (xy 63.180798 -76.891391) (xy 63.257841 -76.926575) (xy 63.331191 -76.968924)
			(xy 63.400183 -77.018053) (xy 63.464193 -77.073518) (xy 63.522641 -77.134816) (xy 63.574997 -77.201392)
			(xy 63.620787 -77.272644) (xy 63.659598 -77.347925) (xy 63.691077 -77.426555) (xy 63.714938 -77.507822)
			(xy 63.730967 -77.590988) (xy 63.739018 -77.675302) (xy 63.739522 -77.71765) (xy 63.739018 -77.759998)
			(xy 90.804996 -77.759998) (xy 90.804996 -77.675302) (xy 90.813047 -77.590988) (xy 90.829076 -77.507822)
			(xy 90.852937 -77.426555) (xy 90.884416 -77.347925) (xy 90.923227 -77.272644) (xy 90.969017 -77.201392)
			(xy 91.021373 -77.134816) (xy 91.079821 -77.073518) (xy 91.143831 -77.018053) (xy 91.212823 -76.968924)
			(xy 91.286173 -76.926575) (xy 91.363216 -76.891391) (xy 91.443255 -76.863689) (xy 91.525564 -76.843721)
			(xy 91.609399 -76.831668) (xy 91.694 -76.827638) (xy 91.778601 -76.831668) (xy 91.862436 -76.843721)
			(xy 91.944745 -76.863689) (xy 92.024784 -76.891391) (xy 92.101827 -76.926575) (xy 92.175177 -76.968924)
			(xy 92.244169 -77.018053) (xy 92.308179 -77.073518) (xy 92.366627 -77.134816) (xy 92.418983 -77.201392)
			(xy 92.464773 -77.272644) (xy 92.503584 -77.347925) (xy 92.535063 -77.426555) (xy 92.558924 -77.507822)
			(xy 92.574953 -77.590988) (xy 92.583004 -77.675302) (xy 92.583508 -77.71765) (xy 92.583004 -77.759998)
			(xy 92.574953 -77.844312) (xy 92.558924 -77.927478) (xy 92.535063 -78.008745) (xy 92.503584 -78.087375)
			(xy 92.464773 -78.162656) (xy 92.418983 -78.233908) (xy 92.366627 -78.300484) (xy 92.308179 -78.361782)
			(xy 92.244169 -78.417247) (xy 92.175177 -78.466376) (xy 92.101827 -78.508725) (xy 92.024784 -78.543909)
			(xy 91.944745 -78.571611) (xy 91.862436 -78.591579) (xy 91.778601 -78.603632) (xy 91.694 -78.607663)
			(xy 91.609399 -78.603632) (xy 91.525564 -78.591579) (xy 91.443255 -78.571611) (xy 91.363216 -78.543909)
			(xy 91.286173 -78.508725) (xy 91.212823 -78.466376) (xy 91.143831 -78.417247) (xy 91.079821 -78.361782)
			(xy 91.021373 -78.300484) (xy 90.969017 -78.233908) (xy 90.923227 -78.162656) (xy 90.884416 -78.087375)
			(xy 90.852937 -78.008745) (xy 90.829076 -77.927478) (xy 90.813047 -77.844312) (xy 90.804996 -77.759998)
			(xy 63.739018 -77.759998) (xy 63.730967 -77.844312) (xy 63.714938 -77.927478) (xy 63.691077 -78.008745)
			(xy 63.659598 -78.087375) (xy 63.620787 -78.162656) (xy 63.574997 -78.233908) (xy 63.522641 -78.300484)
			(xy 63.464193 -78.361782) (xy 63.400183 -78.417247) (xy 63.331191 -78.466376) (xy 63.257841 -78.508725)
			(xy 63.180798 -78.543909) (xy 63.100759 -78.571611) (xy 63.01845 -78.591579) (xy 62.934615 -78.603632)
			(xy 62.850014 -78.607663) (xy 62.765413 -78.603632) (xy 62.681578 -78.591579) (xy 62.599269 -78.571611)
			(xy 62.51923 -78.543909) (xy 62.442187 -78.508725) (xy 62.368837 -78.466376) (xy 62.299845 -78.417247)
			(xy 62.235835 -78.361782) (xy 62.177387 -78.300484) (xy 62.125031 -78.233908) (xy 62.079241 -78.162656)
			(xy 62.04043 -78.087375) (xy 62.008951 -78.008745) (xy 61.98509 -77.927478) (xy 61.969061 -77.844312)
			(xy 61.96101 -77.759998) (xy 60.191166 -77.759998) (xy 60.268434 -77.786741) (xy 60.345477 -77.821925)
			(xy 60.418827 -77.864274) (xy 60.487819 -77.913403) (xy 60.551829 -77.968868) (xy 60.610277 -78.030166)
			(xy 60.662633 -78.096742) (xy 60.708423 -78.167994) (xy 60.747234 -78.243275) (xy 60.778713 -78.321905)
			(xy 60.802574 -78.403172) (xy 60.818603 -78.486338) (xy 60.826654 -78.570652) (xy 60.827158 -78.613)
			(xy 60.826654 -78.655348) (xy 94.487996 -78.655348) (xy 94.487996 -78.570652) (xy 94.496047 -78.486338)
			(xy 94.512076 -78.403172) (xy 94.535937 -78.321905) (xy 94.567416 -78.243275) (xy 94.606227 -78.167994)
			(xy 94.652017 -78.096742) (xy 94.704373 -78.030166) (xy 94.762821 -77.968868) (xy 94.826831 -77.913403)
			(xy 94.895823 -77.864274) (xy 94.969173 -77.821925) (xy 95.046216 -77.786741) (xy 95.126255 -77.759039)
			(xy 95.208564 -77.739071) (xy 95.292399 -77.727018) (xy 95.377 -77.722988) (xy 95.461601 -77.727018)
			(xy 95.545436 -77.739071) (xy 95.627745 -77.759039) (xy 95.707784 -77.786741) (xy 95.784827 -77.821925)
			(xy 95.858177 -77.864274) (xy 95.927169 -77.913403) (xy 95.991179 -77.968868) (xy 96.049627 -78.030166)
			(xy 96.101983 -78.096742) (xy 96.147773 -78.167994) (xy 96.186584 -78.243275) (xy 96.218063 -78.321905)
			(xy 96.241924 -78.403172) (xy 96.257953 -78.486338) (xy 96.266004 -78.570652) (xy 96.266508 -78.613)
			(xy 96.640142 -78.613) (xy 96.640646 -78.570652) (xy 96.648697 -78.486338) (xy 96.664726 -78.403172)
			(xy 96.688587 -78.321905) (xy 96.720066 -78.243275) (xy 96.758877 -78.167994) (xy 96.804667 -78.096742)
			(xy 96.857023 -78.030166) (xy 96.915471 -77.968868) (xy 96.979481 -77.913403) (xy 97.048473 -77.864274)
			(xy 97.121823 -77.821925) (xy 97.198866 -77.786741) (xy 97.278905 -77.759039) (xy 97.361214 -77.739071)
			(xy 97.445049 -77.727018) (xy 97.52965 -77.722988) (xy 97.614251 -77.727018) (xy 97.698086 -77.739071)
			(xy 97.780395 -77.759039) (xy 97.860434 -77.786741) (xy 97.937477 -77.821925) (xy 98.010827 -77.864274)
			(xy 98.079819 -77.913403) (xy 98.143829 -77.968868) (xy 98.202277 -78.030166) (xy 98.254633 -78.096742)
			(xy 98.300423 -78.167994) (xy 98.339234 -78.243275) (xy 98.370713 -78.321905) (xy 98.394574 -78.403172)
			(xy 98.410603 -78.486338) (xy 98.418654 -78.570652) (xy 98.419158 -78.613) (xy 98.418602 -78.655348)
			(xy 98.926646 -78.655348) (xy 98.926646 -78.570652) (xy 98.934697 -78.486338) (xy 98.950726 -78.403172)
			(xy 98.974587 -78.321905) (xy 99.006066 -78.243275) (xy 99.044877 -78.167994) (xy 99.090667 -78.096742)
			(xy 99.143023 -78.030166) (xy 99.201471 -77.968868) (xy 99.265481 -77.913403) (xy 99.334473 -77.864274)
			(xy 99.407823 -77.821925) (xy 99.484866 -77.786741) (xy 99.564905 -77.759039) (xy 99.647214 -77.739071)
			(xy 99.731049 -77.727018) (xy 99.81565 -77.722988) (xy 99.900251 -77.727018) (xy 99.984086 -77.739071)
			(xy 100.066395 -77.759039) (xy 100.069166 -77.759998) (xy 101.96093 -77.759998) (xy 101.96093 -77.675302)
			(xy 101.968981 -77.590988) (xy 101.98501 -77.507822) (xy 102.008871 -77.426555) (xy 102.04035 -77.347925)
			(xy 102.079161 -77.272644) (xy 102.124951 -77.201392) (xy 102.177307 -77.134816) (xy 102.235755 -77.073518)
			(xy 102.299765 -77.018053) (xy 102.368757 -76.968924) (xy 102.442107 -76.926575) (xy 102.51915 -76.891391)
			(xy 102.599189 -76.863689) (xy 102.681498 -76.843721) (xy 102.765333 -76.831668) (xy 102.849934 -76.827638)
			(xy 102.934535 -76.831668) (xy 103.01837 -76.843721) (xy 103.100679 -76.863689) (xy 103.180718 -76.891391)
			(xy 103.257761 -76.926575) (xy 103.331111 -76.968924) (xy 103.400103 -77.018053) (xy 103.464113 -77.073518)
			(xy 103.522561 -77.134816) (xy 103.574917 -77.201392) (xy 103.620707 -77.272644) (xy 103.659518 -77.347925)
			(xy 103.690997 -77.426555) (xy 103.714858 -77.507822) (xy 103.730887 -77.590988) (xy 103.738938 -77.675302)
			(xy 103.739442 -77.71765) (xy 103.738938 -77.759998) (xy 141.961104 -77.759998) (xy 141.961104 -77.675302)
			(xy 141.969155 -77.590988) (xy 141.985184 -77.507822) (xy 142.009045 -77.426555) (xy 142.040524 -77.347925)
			(xy 142.079335 -77.272644) (xy 142.125125 -77.201392) (xy 142.177481 -77.134816) (xy 142.235929 -77.073518)
			(xy 142.299939 -77.018053) (xy 142.368931 -76.968924) (xy 142.442281 -76.926575) (xy 142.519324 -76.891391)
			(xy 142.599363 -76.863689) (xy 142.681672 -76.843721) (xy 142.765507 -76.831668) (xy 142.850108 -76.827638)
			(xy 142.934709 -76.831668) (xy 143.018544 -76.843721) (xy 143.100853 -76.863689) (xy 143.180892 -76.891391)
			(xy 143.257935 -76.926575) (xy 143.331285 -76.968924) (xy 143.400277 -77.018053) (xy 143.464287 -77.073518)
			(xy 143.522735 -77.134816) (xy 143.575091 -77.201392) (xy 143.620881 -77.272644) (xy 143.659692 -77.347925)
			(xy 143.691171 -77.426555) (xy 143.715032 -77.507822) (xy 143.731061 -77.590988) (xy 143.739112 -77.675302)
			(xy 143.739616 -77.71765) (xy 143.739112 -77.759998) (xy 181.961278 -77.759998) (xy 181.961278 -77.675302)
			(xy 181.969329 -77.590988) (xy 181.985358 -77.507822) (xy 182.009219 -77.426555) (xy 182.040698 -77.347925)
			(xy 182.079509 -77.272644) (xy 182.125299 -77.201392) (xy 182.177655 -77.134816) (xy 182.236103 -77.073518)
			(xy 182.300113 -77.018053) (xy 182.369105 -76.968924) (xy 182.442455 -76.926575) (xy 182.519498 -76.891391)
			(xy 182.599537 -76.863689) (xy 182.681846 -76.843721) (xy 182.765681 -76.831668) (xy 182.850282 -76.827638)
			(xy 182.934883 -76.831668) (xy 182.958059 -76.835) (xy 212.088982 -76.835) (xy 212.093053 -76.779378)
			(xy 212.105179 -76.724941) (xy 212.125102 -76.67285) (xy 212.152398 -76.624215) (xy 212.186484 -76.580072)
			(xy 212.226633 -76.541363) (xy 212.271991 -76.508912) (xy 212.321591 -76.483411) (xy 212.374375 -76.465404)
			(xy 212.429218 -76.455274) (xy 212.484952 -76.453237) (xy 212.540389 -76.459337) (xy 212.594346 -76.473443)
			(xy 212.645675 -76.495255) (xy 212.693281 -76.524309) (xy 212.736149 -76.559984) (xy 212.773366 -76.601521)
			(xy 212.804139 -76.648034) (xy 212.827811 -76.698531) (xy 212.843879 -76.751938) (xy 212.851999 -76.807114)
			(xy 212.852508 -76.835) (xy 212.851999 -76.862886) (xy 212.843879 -76.918062) (xy 212.83066 -76.962)
			(xy 214.247982 -76.962) (xy 214.252053 -76.906378) (xy 214.264179 -76.851941) (xy 214.284102 -76.79985)
			(xy 214.311398 -76.751215) (xy 214.345484 -76.707072) (xy 214.385633 -76.668363) (xy 214.430991 -76.635912)
			(xy 214.480591 -76.610411) (xy 214.533375 -76.592404) (xy 214.588218 -76.582274) (xy 214.643952 -76.580237)
			(xy 214.699389 -76.586337) (xy 214.753346 -76.600443) (xy 214.804675 -76.622255) (xy 214.852281 -76.651309)
			(xy 214.895149 -76.686984) (xy 214.932366 -76.728521) (xy 214.963139 -76.775034) (xy 214.986811 -76.825531)
			(xy 215.002879 -76.878938) (xy 215.010999 -76.934114) (xy 215.011508 -76.962) (xy 215.010999 -76.989886)
			(xy 215.002879 -77.045062) (xy 214.98966 -77.089) (xy 216.279982 -77.089) (xy 216.284053 -77.033378)
			(xy 216.296179 -76.978941) (xy 216.316102 -76.92685) (xy 216.343398 -76.878215) (xy 216.377484 -76.834072)
			(xy 216.417633 -76.795363) (xy 216.462991 -76.762912) (xy 216.512591 -76.737411) (xy 216.565375 -76.719404)
			(xy 216.620218 -76.709274) (xy 216.675952 -76.707237) (xy 216.731389 -76.713337) (xy 216.785346 -76.727443)
			(xy 216.836675 -76.749255) (xy 216.884281 -76.778309) (xy 216.927149 -76.813984) (xy 216.964366 -76.855521)
			(xy 216.995139 -76.902034) (xy 217.018811 -76.952531) (xy 217.034879 -77.005938) (xy 217.042999 -77.061114)
			(xy 217.043508 -77.089) (xy 217.042999 -77.116886) (xy 217.034879 -77.172062) (xy 217.018811 -77.225469)
			(xy 216.995139 -77.275966) (xy 216.964366 -77.322479) (xy 216.927149 -77.364016) (xy 216.921881 -77.3684)
			(xy 218.464382 -77.3684) (xy 218.468453 -77.312778) (xy 218.480579 -77.258341) (xy 218.500502 -77.20625)
			(xy 218.527798 -77.157615) (xy 218.561884 -77.113472) (xy 218.602033 -77.074763) (xy 218.647391 -77.042312)
			(xy 218.696991 -77.016811) (xy 218.749775 -76.998804) (xy 218.804618 -76.988674) (xy 218.860352 -76.986637)
			(xy 218.915789 -76.992737) (xy 218.969746 -77.006843) (xy 219.021075 -77.028655) (xy 219.068681 -77.057709)
			(xy 219.111549 -77.093384) (xy 219.148766 -77.134921) (xy 219.179539 -77.181434) (xy 219.203211 -77.231931)
			(xy 219.219279 -77.285338) (xy 219.227399 -77.340514) (xy 219.227908 -77.3684) (xy 219.227399 -77.396286)
			(xy 219.219279 -77.451462) (xy 219.203211 -77.504869) (xy 219.179539 -77.555366) (xy 219.148766 -77.601879)
			(xy 219.111549 -77.643416) (xy 219.068681 -77.679091) (xy 219.021075 -77.708145) (xy 218.969746 -77.729957)
			(xy 218.915789 -77.744063) (xy 218.860352 -77.750163) (xy 218.804618 -77.748126) (xy 218.749775 -77.737996)
			(xy 218.696991 -77.719989) (xy 218.647391 -77.694488) (xy 218.602033 -77.662037) (xy 218.561884 -77.623328)
			(xy 218.527798 -77.579185) (xy 218.500502 -77.53055) (xy 218.480579 -77.478459) (xy 218.468453 -77.424022)
			(xy 218.464382 -77.3684) (xy 216.921881 -77.3684) (xy 216.884281 -77.399691) (xy 216.836675 -77.428745)
			(xy 216.785346 -77.450557) (xy 216.731389 -77.464663) (xy 216.675952 -77.470763) (xy 216.620218 -77.468726)
			(xy 216.565375 -77.458596) (xy 216.512591 -77.440589) (xy 216.462991 -77.415088) (xy 216.417633 -77.382637)
			(xy 216.377484 -77.343928) (xy 216.343398 -77.299785) (xy 216.316102 -77.25115) (xy 216.296179 -77.199059)
			(xy 216.284053 -77.144622) (xy 216.279982 -77.089) (xy 214.98966 -77.089) (xy 214.986811 -77.098469)
			(xy 214.963139 -77.148966) (xy 214.932366 -77.195479) (xy 214.895149 -77.237016) (xy 214.852281 -77.272691)
			(xy 214.804675 -77.301745) (xy 214.753346 -77.323557) (xy 214.699389 -77.337663) (xy 214.643952 -77.343763)
			(xy 214.588218 -77.341726) (xy 214.533375 -77.331596) (xy 214.480591 -77.313589) (xy 214.430991 -77.288088)
			(xy 214.385633 -77.255637) (xy 214.345484 -77.216928) (xy 214.311398 -77.172785) (xy 214.284102 -77.12415)
			(xy 214.264179 -77.072059) (xy 214.252053 -77.017622) (xy 214.247982 -76.962) (xy 212.83066 -76.962)
			(xy 212.827811 -76.971469) (xy 212.804139 -77.021966) (xy 212.773366 -77.068479) (xy 212.736149 -77.110016)
			(xy 212.693281 -77.145691) (xy 212.645675 -77.174745) (xy 212.594346 -77.196557) (xy 212.540389 -77.210663)
			(xy 212.484952 -77.216763) (xy 212.429218 -77.214726) (xy 212.374375 -77.204596) (xy 212.321591 -77.186589)
			(xy 212.271991 -77.161088) (xy 212.226633 -77.128637) (xy 212.186484 -77.089928) (xy 212.152398 -77.045785)
			(xy 212.125102 -76.99715) (xy 212.105179 -76.945059) (xy 212.093053 -76.890622) (xy 212.088982 -76.835)
			(xy 182.958059 -76.835) (xy 183.018718 -76.843721) (xy 183.101027 -76.863689) (xy 183.181066 -76.891391)
			(xy 183.258109 -76.926575) (xy 183.331459 -76.968924) (xy 183.400451 -77.018053) (xy 183.464461 -77.073518)
			(xy 183.522909 -77.134816) (xy 183.575265 -77.201392) (xy 183.621055 -77.272644) (xy 183.659866 -77.347925)
			(xy 183.691345 -77.426555) (xy 183.715206 -77.507822) (xy 183.731235 -77.590988) (xy 183.739286 -77.675302)
			(xy 183.73979 -77.71765) (xy 183.739286 -77.759998) (xy 183.731235 -77.844312) (xy 183.715206 -77.927478)
			(xy 183.691345 -78.008745) (xy 183.659866 -78.087375) (xy 183.621055 -78.162656) (xy 183.575265 -78.233908)
			(xy 183.522909 -78.300484) (xy 183.464461 -78.361782) (xy 183.400451 -78.417247) (xy 183.331459 -78.466376)
			(xy 183.258109 -78.508725) (xy 183.181066 -78.543909) (xy 183.101027 -78.571611) (xy 183.018718 -78.591579)
			(xy 182.934883 -78.603632) (xy 182.850282 -78.607663) (xy 182.765681 -78.603632) (xy 182.681846 -78.591579)
			(xy 182.599537 -78.571611) (xy 182.519498 -78.543909) (xy 182.442455 -78.508725) (xy 182.369105 -78.466376)
			(xy 182.300113 -78.417247) (xy 182.236103 -78.361782) (xy 182.177655 -78.300484) (xy 182.125299 -78.233908)
			(xy 182.079509 -78.162656) (xy 182.040698 -78.087375) (xy 182.009219 -78.008745) (xy 181.985358 -77.927478)
			(xy 181.969329 -77.844312) (xy 181.961278 -77.759998) (xy 143.739112 -77.759998) (xy 143.731061 -77.844312)
			(xy 143.715032 -77.927478) (xy 143.691171 -78.008745) (xy 143.659692 -78.087375) (xy 143.620881 -78.162656)
			(xy 143.575091 -78.233908) (xy 143.522735 -78.300484) (xy 143.464287 -78.361782) (xy 143.400277 -78.417247)
			(xy 143.331285 -78.466376) (xy 143.257935 -78.508725) (xy 143.180892 -78.543909) (xy 143.100853 -78.571611)
			(xy 143.018544 -78.591579) (xy 142.934709 -78.603632) (xy 142.850108 -78.607663) (xy 142.765507 -78.603632)
			(xy 142.681672 -78.591579) (xy 142.599363 -78.571611) (xy 142.519324 -78.543909) (xy 142.442281 -78.508725)
			(xy 142.368931 -78.466376) (xy 142.299939 -78.417247) (xy 142.235929 -78.361782) (xy 142.177481 -78.300484)
			(xy 142.125125 -78.233908) (xy 142.079335 -78.162656) (xy 142.040524 -78.087375) (xy 142.009045 -78.008745)
			(xy 141.985184 -77.927478) (xy 141.969155 -77.844312) (xy 141.961104 -77.759998) (xy 103.738938 -77.759998)
			(xy 103.730887 -77.844312) (xy 103.714858 -77.927478) (xy 103.690997 -78.008745) (xy 103.659518 -78.087375)
			(xy 103.620707 -78.162656) (xy 103.574917 -78.233908) (xy 103.522561 -78.300484) (xy 103.464113 -78.361782)
			(xy 103.400103 -78.417247) (xy 103.331111 -78.466376) (xy 103.257761 -78.508725) (xy 103.180718 -78.543909)
			(xy 103.100679 -78.571611) (xy 103.01837 -78.591579) (xy 102.934535 -78.603632) (xy 102.849934 -78.607663)
			(xy 102.765333 -78.603632) (xy 102.681498 -78.591579) (xy 102.599189 -78.571611) (xy 102.51915 -78.543909)
			(xy 102.442107 -78.508725) (xy 102.368757 -78.466376) (xy 102.299765 -78.417247) (xy 102.235755 -78.361782)
			(xy 102.177307 -78.300484) (xy 102.124951 -78.233908) (xy 102.079161 -78.162656) (xy 102.04035 -78.087375)
			(xy 102.008871 -78.008745) (xy 101.98501 -77.927478) (xy 101.968981 -77.844312) (xy 101.96093 -77.759998)
			(xy 100.069166 -77.759998) (xy 100.146434 -77.786741) (xy 100.223477 -77.821925) (xy 100.296827 -77.864274)
			(xy 100.365819 -77.913403) (xy 100.429829 -77.968868) (xy 100.488277 -78.030166) (xy 100.540633 -78.096742)
			(xy 100.586423 -78.167994) (xy 100.625234 -78.243275) (xy 100.656713 -78.321905) (xy 100.680574 -78.403172)
			(xy 100.696603 -78.486338) (xy 100.704654 -78.570652) (xy 100.705158 -78.613) (xy 100.704654 -78.655348)
			(xy 100.696603 -78.739662) (xy 100.680574 -78.822828) (xy 100.656713 -78.904095) (xy 100.65461 -78.909348)
			(xy 134.613646 -78.909348) (xy 134.613646 -78.824652) (xy 134.621697 -78.740338) (xy 134.637726 -78.657172)
			(xy 134.661587 -78.575905) (xy 134.693066 -78.497275) (xy 134.731877 -78.421994) (xy 134.777667 -78.350742)
			(xy 134.830023 -78.284166) (xy 134.888471 -78.222868) (xy 134.952481 -78.167403) (xy 135.021473 -78.118274)
			(xy 135.094823 -78.075925) (xy 135.171866 -78.040741) (xy 135.251905 -78.013039) (xy 135.334214 -77.993071)
			(xy 135.418049 -77.981018) (xy 135.50265 -77.976988) (xy 135.587251 -77.981018) (xy 135.671086 -77.993071)
			(xy 135.753395 -78.013039) (xy 135.833434 -78.040741) (xy 135.910477 -78.075925) (xy 135.983827 -78.118274)
			(xy 136.052819 -78.167403) (xy 136.116829 -78.222868) (xy 136.175277 -78.284166) (xy 136.227633 -78.350742)
			(xy 136.273423 -78.421994) (xy 136.312234 -78.497275) (xy 136.343713 -78.575905) (xy 136.367574 -78.657172)
			(xy 136.383603 -78.740338) (xy 136.391654 -78.824652) (xy 136.392158 -78.867) (xy 136.391654 -78.909348)
			(xy 136.383603 -78.993662) (xy 136.367574 -79.076828) (xy 136.343713 -79.158095) (xy 136.312234 -79.236725)
			(xy 136.273423 -79.312006) (xy 136.227633 -79.383258) (xy 136.175277 -79.449834) (xy 136.116829 -79.511132)
			(xy 136.052819 -79.566597) (xy 135.983827 -79.615726) (xy 135.910477 -79.658075) (xy 135.833434 -79.693259)
			(xy 135.753395 -79.720961) (xy 135.671086 -79.740929) (xy 135.587251 -79.752982) (xy 135.50265 -79.757013)
			(xy 135.418049 -79.752982) (xy 135.334214 -79.740929) (xy 135.251905 -79.720961) (xy 135.171866 -79.693259)
			(xy 135.094823 -79.658075) (xy 135.021473 -79.615726) (xy 134.952481 -79.566597) (xy 134.888471 -79.511132)
			(xy 134.830023 -79.449834) (xy 134.777667 -79.383258) (xy 134.731877 -79.312006) (xy 134.693066 -79.236725)
			(xy 134.661587 -79.158095) (xy 134.637726 -79.076828) (xy 134.621697 -78.993662) (xy 134.613646 -78.909348)
			(xy 100.65461 -78.909348) (xy 100.625234 -78.982725) (xy 100.586423 -79.058006) (xy 100.540633 -79.129258)
			(xy 100.488277 -79.195834) (xy 100.429829 -79.257132) (xy 100.365819 -79.312597) (xy 100.296827 -79.361726)
			(xy 100.223477 -79.404075) (xy 100.146434 -79.439259) (xy 100.066395 -79.466961) (xy 99.984086 -79.486929)
			(xy 99.900251 -79.498982) (xy 99.81565 -79.503013) (xy 99.731049 -79.498982) (xy 99.647214 -79.486929)
			(xy 99.564905 -79.466961) (xy 99.484866 -79.439259) (xy 99.407823 -79.404075) (xy 99.334473 -79.361726)
			(xy 99.265481 -79.312597) (xy 99.201471 -79.257132) (xy 99.143023 -79.195834) (xy 99.090667 -79.129258)
			(xy 99.044877 -79.058006) (xy 99.006066 -78.982725) (xy 98.974587 -78.904095) (xy 98.950726 -78.822828)
			(xy 98.934697 -78.739662) (xy 98.926646 -78.655348) (xy 98.418602 -78.655348) (xy 98.418593 -78.656023)
			(xy 98.410284 -78.741668) (xy 98.393743 -78.82611) (xy 98.369126 -78.908561) (xy 98.336662 -78.988249)
			(xy 98.296654 -79.064429) (xy 98.249477 -79.13639) (xy 98.195571 -79.203459) (xy 98.135441 -79.26501)
			(xy 98.069648 -79.320466) (xy 97.998808 -79.369309) (xy 97.923582 -79.411084) (xy 97.844674 -79.445399)
			(xy 97.76282 -79.471934) (xy 97.720912 -79.48168) (xy 97.717115 -79.482568) (xy 97.709842 -79.485374)
			(xy 97.706434 -79.487268) (xy 97.700084 -79.491078) (xy 97.693988 -79.497428) (xy 97.688146 -79.505048)
			(xy 97.651824 -79.562706) (xy 97.647506 -79.570326) (xy 97.645474 -79.577184) (xy 97.643696 -79.5909)
			(xy 97.643696 -79.604362) (xy 97.644966 -79.60995) (xy 97.649228 -79.630321) (xy 97.653806 -79.67169)
			(xy 97.65411 -79.6925) (xy 97.65411 -79.693008) (xy 97.653567 -79.7224) (xy 97.644471 -79.780477)
			(xy 97.626573 -79.836471) (xy 97.600296 -79.889057) (xy 97.566263 -79.936988) (xy 97.54616 -79.958438)
			(xy 97.539302 -79.965804) (xy 97.531936 -79.984092) (xy 97.531936 -80.074008) (xy 97.539048 -80.092042)
			(xy 97.545906 -80.099154) (xy 97.547938 -80.10144) (xy 97.54997 -80.103726) (xy 97.569413 -80.125022)
			(xy 97.60225 -80.172425) (xy 97.627573 -80.224232) (xy 97.644804 -80.279262) (xy 97.65355 -80.33626)
			(xy 97.65411 -80.365092) (xy 97.65411 -80.3656) (xy 136.681718 -80.3656) (xy 136.68223 -80.336683)
			(xy 136.690959 -80.279511) (xy 136.708218 -80.224312) (xy 136.733611 -80.17235) (xy 136.766556 -80.124816)
			(xy 136.806298 -80.0828) (xy 136.828784 -80.06461) (xy 136.837551 -80.057054) (xy 136.847728 -80.03629)
			(xy 136.848342 -80.024732) (xy 136.848342 -79.944468) (xy 136.847753 -79.932902) (xy 136.837573 -79.912129)
			(xy 136.828784 -79.90459) (xy 136.806292 -79.886409) (xy 136.766558 -79.844386) (xy 136.733621 -79.796849)
			(xy 136.708234 -79.744886) (xy 136.690979 -79.689687) (xy 136.682252 -79.632517) (xy 136.681718 -79.6036)
			(xy 136.68216 -79.576012) (xy 136.690096 -79.521409) (xy 136.705817 -79.468519) (xy 136.728995 -79.418447)
			(xy 136.759146 -79.372237) (xy 136.795641 -79.330853) (xy 136.837717 -79.29516) (xy 136.884498 -79.265902)
			(xy 136.909556 -79.25435) (xy 136.918192 -79.25054) (xy 136.931654 -79.237078) (xy 136.950958 -79.19466)
			(xy 136.951974 -79.186532) (xy 136.952624 -79.18057) (xy 136.951475 -79.168635) (xy 136.949688 -79.16291)
			(xy 136.949688 -79.162656) (xy 136.937579 -79.127075) (xy 136.918679 -79.054323) (xy 136.905979 -78.980238)
			(xy 136.89957 -78.905345) (xy 136.899142 -78.867762) (xy 136.899142 -78.867) (xy 136.899576 -78.825075)
			(xy 136.907466 -78.741598) (xy 136.923178 -78.659233) (xy 136.946571 -78.578713) (xy 136.977438 -78.500751)
			(xy 137.015504 -78.42604) (xy 137.060433 -78.355243) (xy 137.111824 -78.288989) (xy 137.169223 -78.227865)
			(xy 137.232119 -78.172413) (xy 137.299954 -78.123127) (xy 137.372126 -78.080443) (xy 137.447995 -78.04474)
			(xy 137.526888 -78.016336) (xy 137.608103 -77.995482) (xy 137.69092 -77.982364) (xy 137.774604 -77.977098)
			(xy 137.858412 -77.97973) (xy 137.941601 -77.990237) (xy 138.023431 -78.008527) (xy 138.103178 -78.034436)
			(xy 138.180132 -78.067735) (xy 138.253611 -78.108128) (xy 138.322963 -78.155257) (xy 138.387571 -78.208703)
			(xy 138.446864 -78.267992) (xy 138.500313 -78.332597) (xy 138.547446 -78.401946) (xy 138.587843 -78.475423)
			(xy 138.621146 -78.552375) (xy 138.64706 -78.63212) (xy 138.665354 -78.71395) (xy 138.675866 -78.797138)
			(xy 138.678503 -78.880946) (xy 138.676717 -78.909348) (xy 139.185646 -78.909348) (xy 139.185646 -78.824652)
			(xy 139.193697 -78.740338) (xy 139.209726 -78.657172) (xy 139.233587 -78.575905) (xy 139.265066 -78.497275)
			(xy 139.303877 -78.421994) (xy 139.349667 -78.350742) (xy 139.402023 -78.284166) (xy 139.460471 -78.222868)
			(xy 139.524481 -78.167403) (xy 139.593473 -78.118274) (xy 139.666823 -78.075925) (xy 139.743866 -78.040741)
			(xy 139.823905 -78.013039) (xy 139.906214 -77.993071) (xy 139.990049 -77.981018) (xy 140.07465 -77.976988)
			(xy 140.159251 -77.981018) (xy 140.243086 -77.993071) (xy 140.325395 -78.013039) (xy 140.405434 -78.040741)
			(xy 140.482477 -78.075925) (xy 140.555827 -78.118274) (xy 140.624819 -78.167403) (xy 140.688829 -78.222868)
			(xy 140.747277 -78.284166) (xy 140.799633 -78.350742) (xy 140.845423 -78.421994) (xy 140.884234 -78.497275)
			(xy 140.915713 -78.575905) (xy 140.939574 -78.657172) (xy 140.955603 -78.740338) (xy 140.963654 -78.824652)
			(xy 140.964158 -78.867) (xy 172.439328 -78.867) (xy 172.443401 -78.811341) (xy 172.455536 -78.756868)
			(xy 172.475472 -78.704742) (xy 172.502786 -78.656074) (xy 172.536894 -78.611902) (xy 172.577071 -78.573167)
			(xy 172.622459 -78.540695) (xy 172.672091 -78.515177) (xy 172.724911 -78.497158) (xy 172.77979 -78.487021)
			(xy 172.835561 -78.484983) (xy 172.891035 -78.491086) (xy 172.945028 -78.505202) (xy 172.996391 -78.527029)
			(xy 173.044029 -78.556102) (xy 173.086925 -78.591801) (xy 173.124167 -78.633365) (xy 173.154961 -78.679909)
			(xy 173.178649 -78.73044) (xy 173.194727 -78.783882) (xy 173.202853 -78.839096) (xy 173.203362 -78.867)
			(xy 173.202853 -78.894904) (xy 173.200727 -78.909348) (xy 174.61382 -78.909348) (xy 174.61382 -78.824652)
			(xy 174.621871 -78.740338) (xy 174.6379 -78.657172) (xy 174.661761 -78.575905) (xy 174.69324 -78.497275)
			(xy 174.732051 -78.421994) (xy 174.777841 -78.350742) (xy 174.830197 -78.284166) (xy 174.888645 -78.222868)
			(xy 174.952655 -78.167403) (xy 175.021647 -78.118274) (xy 175.094997 -78.075925) (xy 175.17204 -78.040741)
			(xy 175.252079 -78.013039) (xy 175.334388 -77.993071) (xy 175.418223 -77.981018) (xy 175.502824 -77.976988)
			(xy 175.587425 -77.981018) (xy 175.67126 -77.993071) (xy 175.753569 -78.013039) (xy 175.833608 -78.040741)
			(xy 175.910651 -78.075925) (xy 175.984001 -78.118274) (xy 176.052993 -78.167403) (xy 176.117003 -78.222868)
			(xy 176.175451 -78.284166) (xy 176.227807 -78.350742) (xy 176.273597 -78.421994) (xy 176.312408 -78.497275)
			(xy 176.343887 -78.575905) (xy 176.367748 -78.657172) (xy 176.383777 -78.740338) (xy 176.391828 -78.824652)
			(xy 176.392332 -78.867) (xy 176.391828 -78.909348) (xy 176.383777 -78.993662) (xy 176.367748 -79.076828)
			(xy 176.343887 -79.158095) (xy 176.312408 -79.236725) (xy 176.273597 -79.312006) (xy 176.227807 -79.383258)
			(xy 176.175451 -79.449834) (xy 176.117003 -79.511132) (xy 176.052993 -79.566597) (xy 176.00103 -79.6036)
			(xy 176.681892 -79.6036) (xy 176.682359 -79.577546) (xy 176.689446 -79.525923) (xy 176.703488 -79.475744)
			(xy 176.724225 -79.42794) (xy 176.75127 -79.383401) (xy 176.784122 -79.342955) (xy 176.82217 -79.307352)
			(xy 176.843182 -79.291942) (xy 176.85131 -79.286354) (xy 176.834068 -79.246733) (xy 176.805497 -79.165177)
			(xy 176.783886 -79.081507) (xy 176.769387 -78.996316) (xy 176.762103 -78.910208) (xy 176.761648 -78.867)
			(xy 176.762122 -78.821328) (xy 176.770233 -78.730344) (xy 176.786391 -78.640439) (xy 176.810468 -78.552325)
			(xy 176.842274 -78.466696) (xy 176.881558 -78.384231) (xy 176.92801 -78.305579) (xy 176.981262 -78.231362)
			(xy 177.040893 -78.162167) (xy 177.106434 -78.098541) (xy 177.177365 -78.040985) (xy 177.253126 -77.989955)
			(xy 177.33312 -77.945854) (xy 177.416713 -77.909031) (xy 177.503247 -77.879775) (xy 177.592036 -77.858319)
			(xy 177.682379 -77.844831) (xy 177.773563 -77.839419) (xy 177.864868 -77.842126) (xy 177.955572 -77.852928)
			(xy 178.044958 -77.871743) (xy 178.13232 -77.89842) (xy 178.216969 -77.932749) (xy 178.298235 -77.974459)
			(xy 178.375476 -78.02322) (xy 178.448083 -78.078647) (xy 178.515481 -78.140302) (xy 178.577138 -78.207699)
			(xy 178.632566 -78.280304) (xy 178.681329 -78.357544) (xy 178.723041 -78.438809) (xy 178.757372 -78.523457)
			(xy 178.784051 -78.610819) (xy 178.802868 -78.700205) (xy 178.813673 -78.790908) (xy 178.816381 -78.882213)
			(xy 178.814771 -78.909348) (xy 179.18582 -78.909348) (xy 179.18582 -78.824652) (xy 179.193871 -78.740338)
			(xy 179.2099 -78.657172) (xy 179.233761 -78.575905) (xy 179.26524 -78.497275) (xy 179.304051 -78.421994)
			(xy 179.349841 -78.350742) (xy 179.402197 -78.284166) (xy 179.460645 -78.222868) (xy 179.524655 -78.167403)
			(xy 179.593647 -78.118274) (xy 179.666997 -78.075925) (xy 179.74404 -78.040741) (xy 179.824079 -78.013039)
			(xy 179.906388 -77.993071) (xy 179.990223 -77.981018) (xy 180.074824 -77.976988) (xy 180.159425 -77.981018)
			(xy 180.24326 -77.993071) (xy 180.325569 -78.013039) (xy 180.405608 -78.040741) (xy 180.482651 -78.075925)
			(xy 180.556001 -78.118274) (xy 180.624993 -78.167403) (xy 180.689003 -78.222868) (xy 180.747451 -78.284166)
			(xy 180.799807 -78.350742) (xy 180.845597 -78.421994) (xy 180.884408 -78.497275) (xy 180.915887 -78.575905)
			(xy 180.939748 -78.657172) (xy 180.955777 -78.740338) (xy 180.963828 -78.824652) (xy 180.964332 -78.867)
			(xy 180.963828 -78.909348) (xy 180.955777 -78.993662) (xy 180.939748 -79.076828) (xy 180.915887 -79.158095)
			(xy 180.884408 -79.236725) (xy 180.845597 -79.312006) (xy 180.799807 -79.383258) (xy 180.747451 -79.449834)
			(xy 180.689003 -79.511132) (xy 180.624993 -79.566597) (xy 180.556001 -79.615726) (xy 180.482651 -79.658075)
			(xy 180.405608 -79.693259) (xy 180.325569 -79.720961) (xy 180.24326 -79.740929) (xy 180.159425 -79.752982)
			(xy 180.074824 -79.757013) (xy 179.990223 -79.752982) (xy 179.906388 -79.740929) (xy 179.824079 -79.720961)
			(xy 179.74404 -79.693259) (xy 179.666997 -79.658075) (xy 179.593647 -79.615726) (xy 179.524655 -79.566597)
			(xy 179.460645 -79.511132) (xy 179.402197 -79.449834) (xy 179.349841 -79.383258) (xy 179.304051 -79.312006)
			(xy 179.26524 -79.236725) (xy 179.233761 -79.158095) (xy 179.2099 -79.076828) (xy 179.193871 -78.993662)
			(xy 179.18582 -78.909348) (xy 178.814771 -78.909348) (xy 178.810971 -78.973397) (xy 178.797486 -79.063741)
			(xy 178.776032 -79.15253) (xy 178.746778 -79.239064) (xy 178.709956 -79.322659) (xy 178.665857 -79.402653)
			(xy 178.614829 -79.478416) (xy 178.557275 -79.549349) (xy 178.49365 -79.61489) (xy 178.424457 -79.674524)
			(xy 178.350242 -79.727777) (xy 178.271591 -79.77423) (xy 178.189126 -79.813516) (xy 178.103498 -79.845325)
			(xy 178.015384 -79.869404) (xy 177.92548 -79.885564) (xy 177.834496 -79.893677) (xy 177.788824 -79.894176)
			(xy 177.747173 -79.893746) (xy 177.664147 -79.886982) (xy 177.58194 -79.873521) (xy 177.501092 -79.853452)
			(xy 177.422134 -79.826906) (xy 177.383694 -79.810864) (xy 177.366229 -79.83675) (xy 177.324228 -79.882955)
			(xy 177.300128 -79.902812) (xy 177.297588 -79.904844) (xy 177.277423 -79.919999) (xy 177.233856 -79.945424)
			(xy 177.18732 -79.964891) (xy 177.138626 -79.97806) (xy 177.088622 -79.984702) (xy 177.0634 -79.985108)
			(xy 177.063146 -79.985108) (xy 177.034045 -79.98452) (xy 176.976531 -79.975599) (xy 176.921037 -79.958047)
			(xy 176.868853 -79.932271) (xy 176.844706 -79.91602) (xy 176.836324 -79.910178) (xy 176.829974 -79.905352)
			(xy 176.807346 -79.887173) (xy 176.767346 -79.845114) (xy 176.734178 -79.797481) (xy 176.708608 -79.745374)
			(xy 176.691227 -79.689995) (xy 176.682434 -79.632621) (xy 176.681892 -79.6036) (xy 176.00103 -79.6036)
			(xy 175.984001 -79.615726) (xy 175.910651 -79.658075) (xy 175.833608 -79.693259) (xy 175.753569 -79.720961)
			(xy 175.67126 -79.740929) (xy 175.587425 -79.752982) (xy 175.502824 -79.757013) (xy 175.418223 -79.752982)
			(xy 175.334388 -79.740929) (xy 175.252079 -79.720961) (xy 175.17204 -79.693259) (xy 175.094997 -79.658075)
			(xy 175.021647 -79.615726) (xy 174.952655 -79.566597) (xy 174.888645 -79.511132) (xy 174.830197 -79.449834)
			(xy 174.777841 -79.383258) (xy 174.732051 -79.312006) (xy 174.69324 -79.236725) (xy 174.661761 -79.158095)
			(xy 174.6379 -79.076828) (xy 174.621871 -78.993662) (xy 174.61382 -78.909348) (xy 173.200727 -78.909348)
			(xy 173.194727 -78.950118) (xy 173.178649 -79.00356) (xy 173.154961 -79.054091) (xy 173.124167 -79.100635)
			(xy 173.086925 -79.142199) (xy 173.044029 -79.177898) (xy 172.996391 -79.206971) (xy 172.945028 -79.228798)
			(xy 172.891035 -79.242914) (xy 172.835561 -79.249017) (xy 172.77979 -79.246979) (xy 172.724911 -79.236842)
			(xy 172.672091 -79.218823) (xy 172.622459 -79.193305) (xy 172.577071 -79.160833) (xy 172.536894 -79.122098)
			(xy 172.502786 -79.077926) (xy 172.475472 -79.029258) (xy 172.455536 -78.977132) (xy 172.443401 -78.922659)
			(xy 172.439328 -78.867) (xy 140.964158 -78.867) (xy 140.963654 -78.909348) (xy 140.955603 -78.993662)
			(xy 140.939574 -79.076828) (xy 140.915713 -79.158095) (xy 140.884234 -79.236725) (xy 140.845423 -79.312006)
			(xy 140.799633 -79.383258) (xy 140.747277 -79.449834) (xy 140.688829 -79.511132) (xy 140.624819 -79.566597)
			(xy 140.555827 -79.615726) (xy 140.482477 -79.658075) (xy 140.405434 -79.693259) (xy 140.325395 -79.720961)
			(xy 140.243086 -79.740929) (xy 140.159251 -79.752982) (xy 140.07465 -79.757013) (xy 139.990049 -79.752982)
			(xy 139.906214 -79.740929) (xy 139.823905 -79.720961) (xy 139.743866 -79.693259) (xy 139.666823 -79.658075)
			(xy 139.593473 -79.615726) (xy 139.524481 -79.566597) (xy 139.460471 -79.511132) (xy 139.402023 -79.449834)
			(xy 139.349667 -79.383258) (xy 139.303877 -79.312006) (xy 139.265066 -79.236725) (xy 139.233587 -79.158095)
			(xy 139.209726 -79.076828) (xy 139.193697 -78.993662) (xy 139.185646 -78.909348) (xy 138.676717 -78.909348)
			(xy 138.673241 -78.964631) (xy 138.660128 -79.047448) (xy 138.639278 -79.128665) (xy 138.610879 -79.207558)
			(xy 138.57518 -79.283429) (xy 138.532501 -79.355604) (xy 138.483218 -79.423442) (xy 138.42777 -79.486341)
			(xy 138.366649 -79.543743) (xy 138.300397 -79.595138) (xy 138.229603 -79.640071) (xy 138.154894 -79.678142)
			(xy 138.076935 -79.709013) (xy 137.996416 -79.73241) (xy 137.914052 -79.748127) (xy 137.830575 -79.756022)
			(xy 137.78865 -79.756508) (xy 137.740772 -79.755819) (xy 137.645579 -79.745441) (xy 137.55205 -79.724906)
			(xy 137.506456 -79.71028) (xy 137.506202 -79.71028) (xy 137.496804 -79.707232) (xy 137.487406 -79.70774)
			(xy 137.48255 -79.708098) (xy 137.473089 -79.710401) (xy 137.46861 -79.712312) (xy 137.439908 -79.725774)
			(xy 137.431677 -79.730037) (xy 137.418778 -79.743328) (xy 137.414762 -79.751682) (xy 137.414762 -79.751936)
			(xy 137.404938 -79.774186) (xy 137.380477 -79.816225) (xy 137.350877 -79.854818) (xy 137.316617 -79.889342)
			(xy 137.297668 -79.90459) (xy 137.28891 -79.912155) (xy 137.278726 -79.932912) (xy 137.27811 -79.944468)
			(xy 137.27811 -80.024732) (xy 137.278716 -80.036295) (xy 137.288885 -80.057067) (xy 137.297668 -80.06461)
			(xy 137.32015 -80.082803) (xy 137.359886 -80.124822) (xy 137.392827 -80.172356) (xy 137.418216 -80.224317)
			(xy 137.435472 -80.279514) (xy 137.4442 -80.336684) (xy 137.444734 -80.3656) (xy 137.444248 -80.392851)
			(xy 137.437211 -80.4418) (xy 199.388728 -80.4418) (xy 199.392801 -80.386141) (xy 199.404936 -80.331668)
			(xy 199.424872 -80.279542) (xy 199.452186 -80.230874) (xy 199.486294 -80.186702) (xy 199.526471 -80.147967)
			(xy 199.571859 -80.115495) (xy 199.621491 -80.089977) (xy 199.674311 -80.071958) (xy 199.72919 -80.061821)
			(xy 199.784961 -80.059783) (xy 199.840435 -80.065886) (xy 199.894428 -80.080002) (xy 199.945791 -80.101829)
			(xy 199.993429 -80.130902) (xy 200.036325 -80.166601) (xy 200.073567 -80.208165) (xy 200.104361 -80.254709)
			(xy 200.128049 -80.30524) (xy 200.144127 -80.358682) (xy 200.152253 -80.413896) (xy 200.152762 -80.4418)
			(xy 200.152253 -80.469704) (xy 200.144127 -80.524918) (xy 200.128049 -80.57836) (xy 200.104361 -80.628891)
			(xy 200.073567 -80.675435) (xy 200.036325 -80.716999) (xy 199.993429 -80.752698) (xy 199.945791 -80.781771)
			(xy 199.894428 -80.803598) (xy 199.840435 -80.817714) (xy 199.784961 -80.823817) (xy 199.72919 -80.821779)
			(xy 199.674311 -80.811642) (xy 199.621491 -80.793623) (xy 199.571859 -80.768105) (xy 199.526471 -80.735633)
			(xy 199.486294 -80.696898) (xy 199.452186 -80.652726) (xy 199.424872 -80.604058) (xy 199.404936 -80.551932)
			(xy 199.392801 -80.497459) (xy 199.388728 -80.4418) (xy 137.437211 -80.4418) (xy 137.436492 -80.446799)
			(xy 137.421137 -80.499094) (xy 137.398495 -80.548671) (xy 137.369029 -80.594521) (xy 137.333338 -80.635712)
			(xy 137.292147 -80.671403) (xy 137.246297 -80.700869) (xy 137.19672 -80.723511) (xy 137.144425 -80.738866)
			(xy 137.090477 -80.746622) (xy 137.035975 -80.746622) (xy 136.982027 -80.738866) (xy 136.929732 -80.723511)
			(xy 136.880155 -80.700869) (xy 136.834305 -80.671403) (xy 136.793114 -80.635712) (xy 136.757423 -80.594521)
			(xy 136.727957 -80.548671) (xy 136.705315 -80.499094) (xy 136.68996 -80.446799) (xy 136.682204 -80.392851)
			(xy 136.681718 -80.3656) (xy 97.65411 -80.3656) (xy 97.653624 -80.392851) (xy 97.645868 -80.446799)
			(xy 97.630513 -80.499094) (xy 97.607871 -80.548671) (xy 97.578405 -80.594521) (xy 97.542714 -80.635712)
			(xy 97.501523 -80.671403) (xy 97.455673 -80.700869) (xy 97.406096 -80.723511) (xy 97.353801 -80.738866)
			(xy 97.299853 -80.746622) (xy 97.245351 -80.746622) (xy 97.191403 -80.738866) (xy 97.139108 -80.723511)
			(xy 97.089531 -80.700869) (xy 97.043681 -80.671403) (xy 97.00249 -80.635712) (xy 96.966799 -80.594521)
			(xy 96.937333 -80.548671) (xy 96.914691 -80.499094) (xy 96.899336 -80.446799) (xy 96.89158 -80.392851)
			(xy 96.891094 -80.3656) (xy 96.891094 -80.365092) (xy 96.891636 -80.3357) (xy 96.900732 -80.277623)
			(xy 96.91863 -80.221628) (xy 96.944907 -80.169043) (xy 96.978941 -80.121112) (xy 96.999044 -80.099662)
			(xy 97.005902 -80.092296) (xy 97.013268 -80.074008) (xy 97.013268 -79.984092) (xy 97.006156 -79.966058)
			(xy 96.999298 -79.958946) (xy 96.997266 -79.95666) (xy 96.995234 -79.954374) (xy 96.975792 -79.933077)
			(xy 96.942955 -79.885675) (xy 96.917632 -79.833868) (xy 96.9004 -79.778838) (xy 96.891654 -79.72184)
			(xy 96.891094 -79.693008) (xy 96.891094 -79.6925) (xy 96.891567 -79.665767) (xy 96.899073 -79.612831)
			(xy 96.913885 -79.561458) (xy 96.935711 -79.51265) (xy 96.964127 -79.46736) (xy 96.98101 -79.446628)
			(xy 96.987614 -79.438754) (xy 96.99371 -79.419704) (xy 96.98609 -79.337662) (xy 96.985036 -79.328899)
			(xy 96.977606 -79.3129) (xy 96.971612 -79.30642) (xy 96.967294 -79.302102) (xy 96.965262 -79.300578)
			(xy 96.93187 -79.272433) (xy 96.870127 -79.210666) (xy 96.814734 -79.143147) (xy 96.766222 -79.070525)
			(xy 96.725059 -78.993499) (xy 96.691641 -78.912811) (xy 96.66629 -78.829237) (xy 96.649249 -78.743581)
			(xy 96.640682 -78.656667) (xy 96.640142 -78.613) (xy 96.266508 -78.613) (xy 96.266004 -78.655348)
			(xy 96.257953 -78.739662) (xy 96.241924 -78.822828) (xy 96.218063 -78.904095) (xy 96.186584 -78.982725)
			(xy 96.147773 -79.058006) (xy 96.101983 -79.129258) (xy 96.049627 -79.195834) (xy 95.991179 -79.257132)
			(xy 95.927169 -79.312597) (xy 95.858177 -79.361726) (xy 95.784827 -79.404075) (xy 95.707784 -79.439259)
			(xy 95.627745 -79.466961) (xy 95.545436 -79.486929) (xy 95.461601 -79.498982) (xy 95.377 -79.503013)
			(xy 95.292399 -79.498982) (xy 95.208564 -79.486929) (xy 95.126255 -79.466961) (xy 95.046216 -79.439259)
			(xy 94.969173 -79.404075) (xy 94.895823 -79.361726) (xy 94.826831 -79.312597) (xy 94.762821 -79.257132)
			(xy 94.704373 -79.195834) (xy 94.652017 -79.129258) (xy 94.606227 -79.058006) (xy 94.567416 -78.982725)
			(xy 94.535937 -78.904095) (xy 94.512076 -78.822828) (xy 94.496047 -78.739662) (xy 94.487996 -78.655348)
			(xy 60.826654 -78.655348) (xy 60.818603 -78.739662) (xy 60.802574 -78.822828) (xy 60.778713 -78.904095)
			(xy 60.747234 -78.982725) (xy 60.708423 -79.058006) (xy 60.662633 -79.129258) (xy 60.610277 -79.195834)
			(xy 60.551829 -79.257132) (xy 60.487819 -79.312597) (xy 60.418827 -79.361726) (xy 60.345477 -79.404075)
			(xy 60.268434 -79.439259) (xy 60.188395 -79.466961) (xy 60.106086 -79.486929) (xy 60.022251 -79.498982)
			(xy 59.93765 -79.503013) (xy 59.853049 -79.498982) (xy 59.769214 -79.486929) (xy 59.686905 -79.466961)
			(xy 59.606866 -79.439259) (xy 59.529823 -79.404075) (xy 59.456473 -79.361726) (xy 59.387481 -79.312597)
			(xy 59.323471 -79.257132) (xy 59.265023 -79.195834) (xy 59.212667 -79.129258) (xy 59.166877 -79.058006)
			(xy 59.128066 -78.982725) (xy 59.096587 -78.904095) (xy 59.072726 -78.822828) (xy 59.056697 -78.739662)
			(xy 59.048646 -78.655348) (xy 58.540647 -78.655348) (xy 58.540617 -78.657835) (xy 58.531594 -78.747051)
			(xy 58.51364 -78.834906) (xy 58.486938 -78.920509) (xy 58.451757 -79.00299) (xy 58.408456 -79.081513)
			(xy 58.383424 -79.118714) (xy 58.375456 -79.131031) (xy 58.366305 -79.158891) (xy 58.365448 -79.188202)
			(xy 58.372956 -79.216549) (xy 58.388209 -79.241594) (xy 58.409951 -79.261272) (xy 58.436388 -79.27396)
			(xy 58.465341 -79.278613) (xy 58.479944 -79.27721) (xy 58.491893 -79.275775) (xy 58.515915 -79.274252)
			(xy 58.52795 -79.274162) (xy 58.555208 -79.274601) (xy 58.609169 -79.282353) (xy 58.661478 -79.297706)
			(xy 58.711069 -79.320347) (xy 58.756934 -79.349815) (xy 58.798137 -79.385511) (xy 58.833841 -79.426707)
			(xy 58.863318 -79.472566) (xy 58.885969 -79.522153) (xy 58.901331 -79.574459) (xy 58.909093 -79.628419)
			(xy 58.909097 -79.682934) (xy 58.901341 -79.736895) (xy 58.885985 -79.789203) (xy 58.863341 -79.838793)
			(xy 58.833869 -79.884655) (xy 58.79817 -79.925856) (xy 58.756971 -79.961557) (xy 58.71111 -79.991031)
			(xy 58.661522 -80.013678) (xy 58.609215 -80.029037) (xy 58.555254 -80.036795) (xy 58.500739 -80.036795)
			(xy 58.446779 -80.029036) (xy 58.394472 -80.013676) (xy 58.344884 -79.991028) (xy 58.299023 -79.961553)
			(xy 58.257825 -79.925851) (xy 58.222127 -79.88465) (xy 58.192656 -79.838787) (xy 58.170013 -79.789197)
			(xy 58.154657 -79.736889) (xy 58.146903 -79.682928) (xy 58.146442 -79.65567) (xy 58.146956 -79.627097)
			(xy 58.155499 -79.570594) (xy 58.16346 -79.543148) (xy 58.167246 -79.528981) (xy 58.167602 -79.499676)
			(xy 58.159619 -79.471478) (xy 58.143953 -79.44671) (xy 58.121897 -79.427413) (xy 58.095267 -79.415177)
			(xy 58.066258 -79.411011) (xy 58.037261 -79.415258) (xy 58.02376 -79.420974) (xy 57.98874 -79.436664)
			(xy 57.916521 -79.462624) (xy 57.842334 -79.482271) (xy 57.766732 -79.49546) (xy 57.690276 -79.502092)
			(xy 57.651904 -79.502508) (xy 57.65165 -79.502508) (xy 57.609728 -79.501972) (xy 57.526255 -79.494077)
			(xy 57.443896 -79.478362) (xy 57.363382 -79.454965) (xy 57.285426 -79.424096) (xy 57.210722 -79.386027)
			(xy 57.139931 -79.341098) (xy 57.073683 -79.289705) (xy 57.012566 -79.232306) (xy 56.957121 -79.169411)
			(xy 56.907841 -79.101577) (xy 56.865164 -79.029406) (xy 56.829468 -78.953539) (xy 56.801069 -78.87465)
			(xy 56.780221 -78.793438) (xy 56.767108 -78.710625) (xy 56.761847 -78.626945) (xy 56.38838 -78.626945)
			(xy 56.388117 -78.653057) (xy 56.38139 -78.730338) (xy 56.367957 -78.80674) (xy 56.347922 -78.881682)
			(xy 56.321435 -78.954594) (xy 56.30545 -78.989936) (xy 56.300624 -79.000096) (xy 56.300624 -79.032862)
			(xy 56.300781 -79.037954) (xy 56.302821 -79.047934) (xy 56.304688 -79.052674) (xy 56.329326 -79.110078)
			(xy 56.332882 -79.118714) (xy 56.345582 -79.132176) (xy 56.360568 -79.139288) (xy 56.36387 -79.140304)
			(xy 56.38875 -79.149195) (xy 56.435997 -79.172844) (xy 56.479531 -79.202782) (xy 56.518521 -79.238437)
			(xy 56.552221 -79.279128) (xy 56.579988 -79.324078) (xy 56.601292 -79.372428) (xy 56.615724 -79.423253)
			(xy 56.62301 -79.475583) (xy 56.623458 -79.502) (xy 56.623045 -79.529255) (xy 56.615286 -79.58321)
			(xy 56.599928 -79.635512) (xy 56.577282 -79.685096) (xy 56.547809 -79.730951) (xy 56.51211 -79.772145)
			(xy 56.470911 -79.807839) (xy 56.425052 -79.837306) (xy 56.375465 -79.859945) (xy 56.323162 -79.875297)
			(xy 56.269205 -79.883048) (xy 56.24195 -79.883508) (xy 56.214591 -79.883126) (xy 56.160434 -79.875316)
			(xy 56.107949 -79.859848) (xy 56.058212 -79.837041) (xy 56.012243 -79.807361) (xy 55.970986 -79.771419)
			(xy 55.935288 -79.72995) (xy 55.905881 -79.683808) (xy 55.883367 -79.633937) (xy 55.86821 -79.581361)
			(xy 55.863998 -79.554324) (xy 55.862474 -79.543148) (xy 55.85079 -79.52486) (xy 55.776622 -79.4766)
			(xy 55.766941 -79.470987) (xy 55.744814 -79.467823) (xy 55.73395 -79.470504) (xy 55.732172 -79.471012)
			(xy 55.69411 -79.480952) (xy 55.616687 -79.494916) (xy 55.538335 -79.502001) (xy 55.499 -79.502508)
			(xy 55.457075 -79.502024) (xy 55.373596 -79.494133) (xy 55.291231 -79.478421) (xy 55.210709 -79.455028)
			(xy 55.132747 -79.42416) (xy 55.058036 -79.386093) (xy 54.987238 -79.341163) (xy 54.920983 -79.289771)
			(xy 54.859859 -79.232371) (xy 54.804407 -79.169474) (xy 54.755121 -79.101637) (xy 54.712438 -79.029463)
			(xy 54.676736 -78.953593) (xy 54.648332 -78.8747) (xy 54.627479 -78.793483) (xy 54.614362 -78.710665)
			(xy 54.609097 -78.62698) (xy 43.405054 -78.62698) (xy 44.915074 -80.137) (xy 53.700932 -80.137) (xy 53.705003 -80.081378)
			(xy 53.717129 -80.026941) (xy 53.737052 -79.97485) (xy 53.764348 -79.926215) (xy 53.798434 -79.882072)
			(xy 53.838583 -79.843363) (xy 53.883941 -79.810912) (xy 53.933541 -79.785411) (xy 53.986325 -79.767404)
			(xy 54.041168 -79.757274) (xy 54.096902 -79.755237) (xy 54.152339 -79.761337) (xy 54.206296 -79.775443)
			(xy 54.257625 -79.797255) (xy 54.305231 -79.826309) (xy 54.348099 -79.861984) (xy 54.385316 -79.903521)
			(xy 54.416089 -79.950034) (xy 54.439761 -80.000531) (xy 54.455829 -80.053938) (xy 54.463949 -80.109114)
			(xy 54.464458 -80.137) (xy 54.463949 -80.164886) (xy 54.455829 -80.220062) (xy 54.439761 -80.273469)
			(xy 54.416089 -80.323966) (xy 54.385316 -80.370479) (xy 54.348099 -80.412016) (xy 54.305231 -80.447691)
			(xy 54.257625 -80.476745) (xy 54.206296 -80.498557) (xy 54.152339 -80.512663) (xy 54.096902 -80.518763)
			(xy 54.041168 -80.516726) (xy 53.986325 -80.506596) (xy 53.933541 -80.488589) (xy 53.883941 -80.463088)
			(xy 53.838583 -80.430637) (xy 53.798434 -80.391928) (xy 53.764348 -80.347785) (xy 53.737052 -80.29915)
			(xy 53.717129 -80.247059) (xy 53.705003 -80.192622) (xy 53.700932 -80.137) (xy 44.915074 -80.137)
			(xy 47.609325 -82.831251) (xy 185.546978 -82.831251) (xy 185.546978 -82.776749) (xy 185.554734 -82.722801)
			(xy 185.570089 -82.670506) (xy 185.592731 -82.620929) (xy 185.622197 -82.575079) (xy 185.657888 -82.533888)
			(xy 185.699079 -82.498197) (xy 185.744929 -82.468731) (xy 185.794506 -82.446089) (xy 185.846801 -82.430734)
			(xy 185.900749 -82.422978) (xy 185.928 -82.422492) (xy 185.953665 -82.422884) (xy 186.004533 -82.42976)
			(xy 186.054017 -82.443401) (xy 186.101223 -82.46356) (xy 186.145296 -82.489873) (xy 186.185439 -82.521864)
			(xy 186.220924 -82.558952) (xy 186.236356 -82.579464) (xy 186.244795 -82.59024) (xy 186.266234 -82.607239)
			(xy 186.29141 -82.61795) (xy 186.318525 -82.621607) (xy 186.34564 -82.61795) (xy 186.370816 -82.607239)
			(xy 186.392255 -82.59024) (xy 186.400694 -82.579464) (xy 186.418801 -82.555609) (xy 186.461172 -82.513291)
			(xy 186.509637 -82.478114) (xy 186.563003 -82.450944) (xy 186.61996 -82.432449) (xy 186.679108 -82.423082)
			(xy 186.70905 -82.422492) (xy 186.736305 -82.422952) (xy 186.790262 -82.430703) (xy 186.842565 -82.446055)
			(xy 186.892152 -82.468694) (xy 186.938011 -82.498161) (xy 186.97921 -82.533855) (xy 187.014909 -82.575049)
			(xy 187.044382 -82.620904) (xy 187.067028 -82.670488) (xy 187.082386 -82.72279) (xy 187.090145 -82.776745)
			(xy 187.090145 -82.831255) (xy 187.082386 -82.88521) (xy 187.067028 -82.937512) (xy 187.044382 -82.987096)
			(xy 187.014909 -83.032951) (xy 186.97921 -83.074145) (xy 186.938011 -83.109839) (xy 186.892152 -83.139306)
			(xy 186.842565 -83.161945) (xy 186.790262 -83.177297) (xy 186.736305 -83.185048) (xy 186.70905 -83.185508)
			(xy 186.683386 -83.185079) (xy 186.63252 -83.178209) (xy 186.583037 -83.164574) (xy 186.535831 -83.144421)
			(xy 186.491758 -83.118114) (xy 186.451614 -83.086129) (xy 186.416127 -83.049045) (xy 186.400694 -83.028536)
			(xy 186.392282 -83.017716) (xy 186.370864 -83.000635) (xy 186.345673 -82.989867) (xy 186.318525 -82.98619)
			(xy 186.291377 -82.989867) (xy 186.266186 -83.000635) (xy 186.244768 -83.017716) (xy 186.236356 -83.028536)
			(xy 186.220934 -83.049053) (xy 186.185436 -83.086126) (xy 186.145287 -83.118104) (xy 186.101213 -83.144408)
			(xy 186.054008 -83.164564) (xy 186.004527 -83.178206) (xy 185.953664 -83.18509) (xy 185.928 -83.185508)
			(xy 185.900749 -83.185022) (xy 185.846801 -83.177266) (xy 185.794506 -83.161911) (xy 185.744929 -83.139269)
			(xy 185.699079 -83.109803) (xy 185.657888 -83.074112) (xy 185.622197 -83.032921) (xy 185.592731 -82.987071)
			(xy 185.570089 -82.937494) (xy 185.554734 -82.885199) (xy 185.546978 -82.831251) (xy 47.609325 -82.831251)
			(xy 47.684182 -82.906108) (xy 47.691586 -82.91294) (xy 47.710184 -82.920644) (xy 47.72025 -82.921094)
			(xy 149.59965 -82.921094) (xy 149.609716 -82.921526) (xy 149.628308 -82.929252) (xy 149.635718 -82.93608)
			(xy 152.070887 -85.371249) (xy 185.527978 -85.371249) (xy 185.527978 -85.316751) (xy 185.535733 -85.262808)
			(xy 185.551085 -85.210517) (xy 185.573723 -85.160943) (xy 185.603185 -85.115095) (xy 185.638871 -85.073906)
			(xy 185.680055 -85.038215) (xy 185.725899 -85.008747) (xy 185.77547 -84.986103) (xy 185.827759 -84.970743)
			(xy 185.881701 -84.962981) (xy 185.90895 -84.962492) (xy 185.935553 -84.962982) (xy 185.988244 -84.970357)
			(xy 186.039398 -84.984984) (xy 186.088023 -85.00658) (xy 186.133174 -85.034725) (xy 186.173974 -85.068873)
			(xy 186.209632 -85.108361) (xy 186.224926 -85.130132) (xy 186.23326 -85.141612) (xy 186.255004 -85.159816)
			(xy 186.280917 -85.171334) (xy 186.309 -85.175274) (xy 186.337083 -85.171334) (xy 186.362996 -85.159816)
			(xy 186.38474 -85.141612) (xy 186.393074 -85.130132) (xy 186.408371 -85.108363) (xy 186.444037 -85.068884)
			(xy 186.48484 -85.034741) (xy 186.52999 -85.006596) (xy 186.578611 -84.984993) (xy 186.629761 -84.970352)
			(xy 186.682448 -84.962956) (xy 186.70905 -84.962492) (xy 186.736305 -84.962952) (xy 186.790262 -84.970703)
			(xy 186.842565 -84.986055) (xy 186.892152 -85.008694) (xy 186.938011 -85.038161) (xy 186.97921 -85.073855)
			(xy 187.014909 -85.115049) (xy 187.044382 -85.160904) (xy 187.067028 -85.210488) (xy 187.082386 -85.26279)
			(xy 187.090145 -85.316745) (xy 187.090145 -85.371255) (xy 187.082386 -85.42521) (xy 187.067028 -85.477512)
			(xy 187.044382 -85.527096) (xy 187.014909 -85.572951) (xy 186.97921 -85.614145) (xy 186.938011 -85.649839)
			(xy 186.892152 -85.679306) (xy 186.842565 -85.701945) (xy 186.790262 -85.717297) (xy 186.736305 -85.725048)
			(xy 186.70905 -85.725508) (xy 186.682447 -85.725018) (xy 186.629756 -85.717643) (xy 186.578602 -85.703016)
			(xy 186.529977 -85.68142) (xy 186.484826 -85.653275) (xy 186.444026 -85.619127) (xy 186.408368 -85.579639)
			(xy 186.393074 -85.557868) (xy 186.38474 -85.546388) (xy 186.362996 -85.528184) (xy 186.337083 -85.516666)
			(xy 186.309 -85.512726) (xy 186.280917 -85.516666) (xy 186.255004 -85.528184) (xy 186.23326 -85.546388)
			(xy 186.224926 -85.557868) (xy 186.209629 -85.579637) (xy 186.173963 -85.619116) (xy 186.13316 -85.653259)
			(xy 186.08801 -85.681404) (xy 186.039389 -85.703007) (xy 185.988239 -85.717648) (xy 185.935552 -85.725044)
			(xy 185.90895 -85.725508) (xy 185.881701 -85.725019) (xy 185.827759 -85.717257) (xy 185.77547 -85.701897)
			(xy 185.725899 -85.679253) (xy 185.680055 -85.649785) (xy 185.638871 -85.614094) (xy 185.603185 -85.572905)
			(xy 185.573723 -85.527057) (xy 185.551085 -85.477483) (xy 185.535733 -85.425192) (xy 185.527978 -85.371249)
			(xy 152.070887 -85.371249) (xy 153.440638 -86.741) (xy 187.578492 -86.741) (xy 187.57895 -86.700413)
			(xy 187.586354 -86.619579) (xy 187.601091 -86.539755) (xy 187.62304 -86.461605) (xy 187.652017 -86.38578)
			(xy 187.687781 -86.31291) (xy 187.730035 -86.243602) (xy 187.778428 -86.178431) (xy 187.832557 -86.11794)
			(xy 187.891971 -86.062632) (xy 187.956177 -86.012966) (xy 188.024641 -85.969356) (xy 188.096793 -85.932165)
			(xy 188.134244 -85.916516) (xy 188.143896 -85.912706) (xy 188.153802 -85.9028) (xy 188.159647 -85.896448)
			(xy 188.167041 -85.880863) (xy 188.16828 -85.87232) (xy 188.168534 -85.870542) (xy 188.176154 -85.766148)
			(xy 188.162692 -85.740494) (xy 188.149738 -85.733128) (xy 188.113318 -85.711556) (xy 188.044396 -85.662403)
			(xy 187.980455 -85.606926) (xy 187.922073 -85.545625) (xy 187.869779 -85.479055) (xy 187.824045 -85.407818)
			(xy 187.785285 -85.332559) (xy 187.75385 -85.253958) (xy 187.730024 -85.172726) (xy 187.714022 -85.089599)
			(xy 187.70599 -85.005327) (xy 187.705492 -84.963) (xy 187.706028 -84.919829) (xy 187.714431 -84.833896)
			(xy 187.73112 -84.749181) (xy 187.755936 -84.666482) (xy 187.788647 -84.586575) (xy 187.828945 -84.510213)
			(xy 187.876451 -84.438114) (xy 187.930719 -84.370957) (xy 187.991236 -84.309372) (xy 188.024008 -84.281264)
			(xy 188.025786 -84.27974) (xy 188.030104 -84.275422) (xy 188.036657 -84.268021) (xy 188.044114 -84.249735)
			(xy 188.044582 -84.239862) (xy 188.044582 -84.16163) (xy 188.044024 -84.150484) (xy 188.034515 -84.130318)
			(xy 188.026294 -84.122768) (xy 187.993288 -84.094669) (xy 187.932349 -84.033014) (xy 187.877695 -83.965726)
			(xy 187.829844 -83.893441) (xy 187.789248 -83.816846) (xy 187.756295 -83.736666) (xy 187.731295 -83.653661)
			(xy 187.714485 -83.568618) (xy 187.706026 -83.482344) (xy 187.705492 -83.439) (xy 187.705995 -83.396685)
			(xy 187.714026 -83.312437) (xy 187.730024 -83.229334) (xy 187.753845 -83.148125) (xy 187.785272 -83.069548)
			(xy 187.824023 -82.994311) (xy 187.846462 -82.958432) (xy 187.851345 -82.950043) (xy 187.855017 -82.931)
			(xy 187.851345 -82.911957) (xy 187.846462 -82.903568) (xy 187.824016 -82.867694) (xy 187.785273 -82.792453)
			(xy 187.753849 -82.713874) (xy 187.73003 -82.632665) (xy 187.71403 -82.549562) (xy 187.705994 -82.465315)
			(xy 187.705492 -82.423) (xy 187.705996 -82.380652) (xy 187.714047 -82.296338) (xy 187.730076 -82.213172)
			(xy 187.753937 -82.131905) (xy 187.785416 -82.053275) (xy 187.824227 -81.977994) (xy 187.870017 -81.906742)
			(xy 187.922373 -81.840166) (xy 187.980821 -81.778868) (xy 188.044831 -81.723403) (xy 188.113823 -81.674274)
			(xy 188.187173 -81.631925) (xy 188.264216 -81.596741) (xy 188.344255 -81.569039) (xy 188.426564 -81.549071)
			(xy 188.510399 -81.537018) (xy 188.595 -81.532988) (xy 188.679601 -81.537018) (xy 188.763436 -81.549071)
			(xy 188.845745 -81.569039) (xy 188.925784 -81.596741) (xy 189.002827 -81.631925) (xy 189.076177 -81.674274)
			(xy 189.145169 -81.723403) (xy 189.209179 -81.778868) (xy 189.267627 -81.840166) (xy 189.319983 -81.906742)
			(xy 189.365773 -81.977994) (xy 189.404584 -82.053275) (xy 189.436063 -82.131905) (xy 189.459924 -82.213172)
			(xy 189.475953 -82.296338) (xy 189.484004 -82.380652) (xy 189.484508 -82.423) (xy 189.484005 -82.465315)
			(xy 189.475974 -82.549563) (xy 189.459976 -82.632666) (xy 189.436155 -82.713875) (xy 189.404728 -82.792452)
			(xy 189.365977 -82.867689) (xy 189.343538 -82.903568) (xy 189.338655 -82.911957) (xy 189.334983 -82.931)
			(xy 189.338655 -82.950043) (xy 189.343538 -82.958432) (xy 189.365984 -82.994306) (xy 189.375239 -83.01228)
			(xy 197.509382 -83.01228) (xy 197.513453 -82.956658) (xy 197.525579 -82.902221) (xy 197.545502 -82.85013)
			(xy 197.572798 -82.801495) (xy 197.606884 -82.757352) (xy 197.647033 -82.718643) (xy 197.692391 -82.686192)
			(xy 197.741991 -82.660691) (xy 197.794775 -82.642684) (xy 197.849618 -82.632554) (xy 197.905352 -82.630517)
			(xy 197.960789 -82.636617) (xy 198.014746 -82.650723) (xy 198.066075 -82.672535) (xy 198.113681 -82.701589)
			(xy 198.156549 -82.737264) (xy 198.193766 -82.778801) (xy 198.224539 -82.825314) (xy 198.248211 -82.875811)
			(xy 198.264279 -82.929218) (xy 198.272399 -82.984394) (xy 198.272908 -83.01228) (xy 198.272399 -83.040166)
			(xy 198.264279 -83.095342) (xy 198.248211 -83.148749) (xy 198.224539 -83.199246) (xy 198.193766 -83.245759)
			(xy 198.156549 -83.287296) (xy 198.113681 -83.322971) (xy 198.066075 -83.352025) (xy 198.014746 -83.373837)
			(xy 197.960789 -83.387943) (xy 197.905352 -83.394043) (xy 197.849618 -83.392006) (xy 197.794775 -83.381876)
			(xy 197.741991 -83.363869) (xy 197.692391 -83.338368) (xy 197.647033 -83.305917) (xy 197.606884 -83.267208)
			(xy 197.572798 -83.223065) (xy 197.545502 -83.17443) (xy 197.525579 -83.122339) (xy 197.513453 -83.067902)
			(xy 197.509382 -83.01228) (xy 189.375239 -83.01228) (xy 189.404727 -83.069547) (xy 189.436151 -83.148126)
			(xy 189.45997 -83.229335) (xy 189.47597 -83.312438) (xy 189.484006 -83.396685) (xy 189.484508 -83.439)
			(xy 189.483972 -83.482171) (xy 189.475569 -83.568104) (xy 189.45888 -83.652819) (xy 189.434064 -83.735518)
			(xy 189.401353 -83.815425) (xy 189.361055 -83.891787) (xy 189.313549 -83.963886) (xy 189.259281 -84.031043)
			(xy 189.198764 -84.092628) (xy 189.165992 -84.120736) (xy 189.164214 -84.12226) (xy 189.159896 -84.126578)
			(xy 189.153343 -84.133979) (xy 189.145886 -84.152265) (xy 189.145418 -84.162138) (xy 189.145418 -84.24037)
			(xy 189.145976 -84.251516) (xy 189.155485 -84.271682) (xy 189.163706 -84.279232) (xy 189.196712 -84.307331)
			(xy 189.257651 -84.368986) (xy 189.312305 -84.436274) (xy 189.360156 -84.508559) (xy 189.400752 -84.585154)
			(xy 189.433705 -84.665334) (xy 189.458705 -84.748339) (xy 189.475515 -84.833382) (xy 189.483974 -84.919656)
			(xy 189.484508 -84.963) (xy 189.48405 -85.003587) (xy 189.476646 -85.084421) (xy 189.461909 -85.164245)
			(xy 189.43996 -85.242395) (xy 189.410983 -85.31822) (xy 189.375219 -85.39109) (xy 189.332965 -85.460398)
			(xy 189.284572 -85.525569) (xy 189.230443 -85.58606) (xy 189.171029 -85.641368) (xy 189.106823 -85.691034)
			(xy 189.038359 -85.734644) (xy 188.966207 -85.771835) (xy 188.928756 -85.787484) (xy 188.919104 -85.791294)
			(xy 188.909198 -85.8012) (xy 188.903353 -85.807552) (xy 188.895959 -85.823137) (xy 188.89472 -85.83168)
			(xy 188.894466 -85.833458) (xy 188.886846 -85.937852) (xy 188.900308 -85.963506) (xy 188.913262 -85.970872)
			(xy 188.949682 -85.992444) (xy 189.018604 -86.041597) (xy 189.082545 -86.097074) (xy 189.140927 -86.158375)
			(xy 189.193221 -86.224945) (xy 189.238955 -86.296182) (xy 189.277715 -86.371441) (xy 189.30915 -86.450042)
			(xy 189.332976 -86.531274) (xy 189.348978 -86.614401) (xy 189.35701 -86.698673) (xy 189.357508 -86.741)
			(xy 189.357006 -86.78243) (xy 189.349285 -86.86493) (xy 189.33392 -86.946354) (xy 189.311044 -87.025994)
			(xy 189.280855 -87.103159) (xy 189.243616 -87.17718) (xy 189.199649 -87.247414) (xy 189.149337 -87.313252)
			(xy 189.093116 -87.374121) (xy 189.062614 -87.402162) (xy 189.050168 -87.414608) (xy 189.042548 -87.435182)
			(xy 189.051184 -87.539068) (xy 189.063376 -87.559388) (xy 189.073536 -87.565738) (xy 189.107469 -87.587962)
			(xy 189.171583 -87.63766) (xy 189.230908 -87.692988) (xy 189.284951 -87.753485) (xy 189.333263 -87.818649)
			(xy 189.375445 -87.88794) (xy 189.411145 -87.960783) (xy 189.440067 -88.036572) (xy 189.461971 -88.114679)
			(xy 189.476676 -88.194456) (xy 189.484059 -88.27524) (xy 189.484508 -88.3158) (xy 189.484025 -88.359135)
			(xy 189.475584 -88.445393) (xy 189.458792 -88.530421) (xy 189.433808 -88.613412) (xy 189.40087 -88.693579)
			(xy 189.360289 -88.770162) (xy 189.31245 -88.842433) (xy 189.257808 -88.909709) (xy 189.227714 -88.940894)
			(xy 189.221872 -88.946736) (xy 189.215014 -88.959944) (xy 189.21349 -88.967818) (xy 189.211204 -88.978994)
			(xy 189.211204 -89.050114) (xy 189.211646 -89.060085) (xy 189.219243 -89.078522) (xy 189.225936 -89.085928)
			(xy 189.256212 -89.117155) (xy 189.311221 -89.184533) (xy 189.359388 -89.256961) (xy 189.400251 -89.333747)
			(xy 189.43342 -89.414156) (xy 189.458579 -89.49742) (xy 189.475486 -89.582743) (xy 189.48398 -89.669309)
			(xy 189.484508 -89.7128) (xy 189.484004 -89.755148) (xy 189.480772 -89.789) (xy 191.133982 -89.789)
			(xy 191.138053 -89.733378) (xy 191.150179 -89.678941) (xy 191.170102 -89.62685) (xy 191.197398 -89.578215)
			(xy 191.231484 -89.534072) (xy 191.271633 -89.495363) (xy 191.316991 -89.462912) (xy 191.366591 -89.437411)
			(xy 191.419375 -89.419404) (xy 191.474218 -89.409274) (xy 191.529952 -89.407237) (xy 191.585389 -89.413337)
			(xy 191.639346 -89.427443) (xy 191.690675 -89.449255) (xy 191.738281 -89.478309) (xy 191.781149 -89.513984)
			(xy 191.818366 -89.555521) (xy 191.849139 -89.602034) (xy 191.872811 -89.652531) (xy 191.888879 -89.705938)
			(xy 191.896999 -89.761114) (xy 191.897508 -89.789) (xy 191.896999 -89.816886) (xy 191.888879 -89.872062)
			(xy 191.872811 -89.925469) (xy 191.849139 -89.975966) (xy 191.818366 -90.022479) (xy 191.781149 -90.064016)
			(xy 191.738281 -90.099691) (xy 191.690675 -90.128745) (xy 191.639346 -90.150557) (xy 191.585389 -90.164663)
			(xy 191.529952 -90.170763) (xy 191.474218 -90.168726) (xy 191.419375 -90.158596) (xy 191.366591 -90.140589)
			(xy 191.316991 -90.115088) (xy 191.271633 -90.082637) (xy 191.231484 -90.043928) (xy 191.197398 -89.999785)
			(xy 191.170102 -89.95115) (xy 191.150179 -89.899059) (xy 191.138053 -89.844622) (xy 191.133982 -89.789)
			(xy 189.480772 -89.789) (xy 189.475953 -89.839462) (xy 189.459924 -89.922628) (xy 189.436063 -90.003895)
			(xy 189.404584 -90.082525) (xy 189.365773 -90.157806) (xy 189.319983 -90.229058) (xy 189.267627 -90.295634)
			(xy 189.209179 -90.356932) (xy 189.145169 -90.412397) (xy 189.076177 -90.461526) (xy 189.002827 -90.503875)
			(xy 188.925784 -90.539059) (xy 188.845745 -90.566761) (xy 188.763436 -90.586729) (xy 188.679601 -90.598782)
			(xy 188.595 -90.602813) (xy 188.510399 -90.598782) (xy 188.426564 -90.586729) (xy 188.344255 -90.566761)
			(xy 188.264216 -90.539059) (xy 188.187173 -90.503875) (xy 188.113823 -90.461526) (xy 188.044831 -90.412397)
			(xy 187.980821 -90.356932) (xy 187.922373 -90.295634) (xy 187.870017 -90.229058) (xy 187.824227 -90.157806)
			(xy 187.785416 -90.082525) (xy 187.753937 -90.003895) (xy 187.730076 -89.922628) (xy 187.714047 -89.839462)
			(xy 187.705996 -89.755148) (xy 187.705492 -89.7128) (xy 187.705975 -89.669465) (xy 187.714416 -89.583207)
			(xy 187.731208 -89.498179) (xy 187.756192 -89.415188) (xy 187.78913 -89.335021) (xy 187.829711 -89.258438)
			(xy 187.87755 -89.186167) (xy 187.932192 -89.118891) (xy 187.962286 -89.087706) (xy 187.968128 -89.081864)
			(xy 187.974986 -89.068656) (xy 187.97651 -89.060782) (xy 187.978796 -89.049606) (xy 187.978796 -88.978486)
			(xy 187.978354 -88.968515) (xy 187.970757 -88.950078) (xy 187.964064 -88.942672) (xy 187.933788 -88.911445)
			(xy 187.878779 -88.844067) (xy 187.830612 -88.771639) (xy 187.789749 -88.694853) (xy 187.75658 -88.614444)
			(xy 187.731421 -88.53118) (xy 187.714514 -88.445857) (xy 187.70602 -88.359291) (xy 187.705492 -88.3158)
			(xy 187.705994 -88.27437) (xy 187.713715 -88.19187) (xy 187.72908 -88.110446) (xy 187.751956 -88.030806)
			(xy 187.782145 -87.953641) (xy 187.819384 -87.87962) (xy 187.863351 -87.809386) (xy 187.913663 -87.743548)
			(xy 187.969884 -87.682679) (xy 188.000386 -87.654638) (xy 188.012832 -87.642192) (xy 188.020452 -87.621618)
			(xy 188.011816 -87.517732) (xy 187.999624 -87.497412) (xy 187.989464 -87.491062) (xy 187.955531 -87.468838)
			(xy 187.891417 -87.41914) (xy 187.832092 -87.363812) (xy 187.778049 -87.303315) (xy 187.729737 -87.238151)
			(xy 187.687555 -87.16886) (xy 187.651855 -87.096017) (xy 187.622933 -87.020228) (xy 187.601029 -86.942121)
			(xy 187.586324 -86.862344) (xy 187.578941 -86.78156) (xy 187.578492 -86.741) (xy 153.440638 -86.741)
			(xy 156.234638 -89.535) (xy 176.884582 -89.535) (xy 176.888653 -89.479378) (xy 176.900779 -89.424941)
			(xy 176.920702 -89.37285) (xy 176.947998 -89.324215) (xy 176.982084 -89.280072) (xy 177.022233 -89.241363)
			(xy 177.067591 -89.208912) (xy 177.117191 -89.183411) (xy 177.169975 -89.165404) (xy 177.224818 -89.155274)
			(xy 177.280552 -89.153237) (xy 177.335989 -89.159337) (xy 177.389946 -89.173443) (xy 177.441275 -89.195255)
			(xy 177.488881 -89.224309) (xy 177.531749 -89.259984) (xy 177.568966 -89.301521) (xy 177.599739 -89.348034)
			(xy 177.623411 -89.398531) (xy 177.639479 -89.451938) (xy 177.647599 -89.507114) (xy 177.648108 -89.535)
			(xy 177.647599 -89.562886) (xy 177.639479 -89.618062) (xy 177.623411 -89.671469) (xy 177.599739 -89.721966)
			(xy 177.568966 -89.768479) (xy 177.531749 -89.810016) (xy 177.488881 -89.845691) (xy 177.441275 -89.874745)
			(xy 177.389946 -89.896557) (xy 177.335989 -89.910663) (xy 177.280552 -89.916763) (xy 177.224818 -89.914726)
			(xy 177.169975 -89.904596) (xy 177.117191 -89.886589) (xy 177.067591 -89.861088) (xy 177.022233 -89.828637)
			(xy 176.982084 -89.789928) (xy 176.947998 -89.745785) (xy 176.920702 -89.69715) (xy 176.900779 -89.645059)
			(xy 176.888653 -89.590622) (xy 176.884582 -89.535) (xy 156.234638 -89.535) (xy 157.453584 -90.753946)
			(xy 157.460985 -90.760785) (xy 157.479583 -90.768497) (xy 157.489652 -90.768932) (xy 177.398172 -90.768932)
			(xy 177.409726 -90.76831) (xy 177.430475 -90.758121) (xy 177.43805 -90.749374) (xy 177.494692 -90.67673)
			(xy 177.499518 -90.654124) (xy 177.49647 -90.64244) (xy 177.487832 -90.606767) (xy 177.475751 -90.534363)
			(xy 177.469678 -90.46121) (xy 177.469292 -90.424508) (xy 177.469292 -90.424) (xy 177.469796 -90.381652)
			(xy 177.477847 -90.297338) (xy 177.493876 -90.214172) (xy 177.517737 -90.132905) (xy 177.549216 -90.054275)
			(xy 177.588027 -89.978994) (xy 177.633817 -89.907742) (xy 177.686173 -89.841166) (xy 177.744621 -89.779868)
			(xy 177.808631 -89.724403) (xy 177.877623 -89.675274) (xy 177.950973 -89.632925) (xy 178.028016 -89.597741)
			(xy 178.108055 -89.570039) (xy 178.190364 -89.550071) (xy 178.274199 -89.538018) (xy 178.3588 -89.533988)
			(xy 178.443401 -89.538018) (xy 178.527236 -89.550071) (xy 178.609545 -89.570039) (xy 178.689584 -89.597741)
			(xy 178.766627 -89.632925) (xy 178.839977 -89.675274) (xy 178.908969 -89.724403) (xy 178.972979 -89.779868)
			(xy 179.031427 -89.841166) (xy 179.083783 -89.907742) (xy 179.129573 -89.978994) (xy 179.168384 -90.054275)
			(xy 179.199863 -90.132905) (xy 179.223724 -90.214172) (xy 179.239753 -90.297338) (xy 179.247804 -90.381652)
			(xy 179.248308 -90.424) (xy 179.248308 -90.424508) (xy 179.247922 -90.46121) (xy 179.241853 -90.534364)
			(xy 179.229773 -90.606768) (xy 179.22113 -90.64244) (xy 179.218082 -90.654124) (xy 179.222908 -90.67673)
			(xy 179.27955 -90.749374) (xy 179.287086 -90.758172) (xy 179.307859 -90.768369) (xy 179.319428 -90.768932)
			(xy 179.62499 -90.768932) (xy 179.633626 -90.76563) (xy 179.659601 -90.756334) (xy 179.713477 -90.744467)
			(xy 179.7685 -90.740484) (xy 179.823523 -90.744467) (xy 179.877399 -90.756334) (xy 179.903374 -90.76563)
			(xy 179.91201 -90.768932) (xy 191.032638 -90.768932) (xy 191.042603 -90.768452) (xy 191.061038 -90.760875)
			(xy 191.068452 -90.7542) (xy 191.119506 -90.7034) (xy 191.125883 -90.696455) (xy 191.133569 -90.679256)
			(xy 191.134492 -90.669872) (xy 191.134492 -90.667078) (xy 191.134979 -90.639828) (xy 191.142738 -90.585882)
			(xy 191.158095 -90.53359) (xy 191.180738 -90.484016) (xy 191.210205 -90.438168) (xy 191.245896 -90.396981)
			(xy 191.287086 -90.361291) (xy 191.332935 -90.331827) (xy 191.382511 -90.309188) (xy 191.434804 -90.293834)
			(xy 191.48875 -90.286078) (xy 191.516 -90.28557) (xy 191.54316 -90.286049) (xy 191.59693 -90.293753)
			(xy 191.649063 -90.309006) (xy 191.698507 -90.331498) (xy 191.74426 -90.360776) (xy 191.785399 -90.396247)
			(xy 191.821091 -90.437194) (xy 191.850614 -90.482789) (xy 191.873373 -90.532111) (xy 191.888906 -90.584162)
			(xy 191.896899 -90.637889) (xy 191.897508 -90.665046) (xy 191.897508 -90.667586) (xy 191.898016 -90.672412)
			(xy 191.899155 -90.680722) (xy 191.90602 -90.696015) (xy 191.911478 -90.702384) (xy 191.911986 -90.703146)
			(xy 191.963548 -90.7542) (xy 191.970955 -90.760892) (xy 191.989391 -90.768493) (xy 191.999362 -90.768932)
			(xy 198.425308 -90.768932) (xy 198.43369 -90.76817) (xy 198.441295 -90.766656) (xy 198.455128 -90.759668)
			(xy 198.460868 -90.754454) (xy 199.230996 -89.984326) (xy 199.237831 -89.976924) (xy 199.245539 -89.958325)
			(xy 199.245982 -89.948258) (xy 199.245982 -81.744312) (xy 199.246402 -81.73424) (xy 199.254112 -81.715631)
			(xy 199.260968 -81.708244) (xy 199.795384 -81.173828) (xy 199.802786 -81.166992) (xy 199.821384 -81.159283)
			(xy 199.831452 -81.158842) (xy 207.6958 -81.158842) (xy 207.705679 -81.158386) (xy 207.723986 -81.150952)
			(xy 207.73136 -81.144364) (xy 207.73771 -81.138014) (xy 207.793082 -81.059274) (xy 207.796638 -81.03489)
			(xy 207.792574 -81.02346) (xy 207.782779 -80.99328) (xy 207.772184 -80.930723) (xy 207.771492 -80.899)
			(xy 207.771978 -80.871749) (xy 207.779734 -80.817801) (xy 207.795089 -80.765506) (xy 207.817731 -80.715929)
			(xy 207.847197 -80.670079) (xy 207.882888 -80.628888) (xy 207.924079 -80.593197) (xy 207.969929 -80.563731)
			(xy 208.019506 -80.541089) (xy 208.071801 -80.525734) (xy 208.125749 -80.517978) (xy 208.153 -80.517492)
			(xy 208.186199 -80.518208) (xy 208.251595 -80.529702) (xy 208.283048 -80.540352) (xy 208.29143 -80.5434)
			(xy 210.993228 -80.5434) (xy 210.997235 -80.543328) (xy 211.005147 -80.542046) (xy 211.008976 -80.54086)
			(xy 211.03209 -80.532986) (xy 211.03844 -80.52816) (xy 211.063161 -80.510699) (xy 211.116968 -80.482991)
			(xy 211.174475 -80.46413) (xy 211.234239 -80.454587) (xy 211.2645 -80.453992) (xy 211.291751 -80.454478)
			(xy 211.345699 -80.462234) (xy 211.397994 -80.477589) (xy 211.447571 -80.500231) (xy 211.493421 -80.529697)
			(xy 211.534612 -80.565388) (xy 211.570303 -80.606579) (xy 211.599769 -80.652429) (xy 211.622411 -80.702006)
			(xy 211.637766 -80.754301) (xy 211.645522 -80.808249) (xy 211.646008 -80.8355) (xy 211.645393 -80.865784)
			(xy 211.635747 -80.925582) (xy 211.616762 -80.9831) (xy 211.603336 -81.010252) (xy 211.59724 -81.022444)
			(xy 211.598002 -81.048606) (xy 211.650326 -81.134458) (xy 211.655148 -81.141711) (xy 211.668652 -81.152693)
			(xy 211.685057 -81.158511) (xy 211.69376 -81.158842) (xy 212.670136 -81.158842) (xy 212.679026 -81.15808)
			(xy 212.695155 -81.155464) (xy 212.727712 -81.152662) (xy 212.74405 -81.152492) (xy 212.759356 -81.152623)
			(xy 212.789873 -81.15504) (xy 212.80501 -81.157318) (xy 212.813138 -81.158842) (xy 218.719146 -81.158842)
			(xy 218.727528 -81.15808) (xy 218.73513 -81.156561) (xy 218.748957 -81.149567) (xy 218.754706 -81.144364)
			(xy 219.618814 -80.280256) (xy 219.625663 -80.272859) (xy 219.633395 -80.25426) (xy 219.6338 -80.244188)
			(xy 219.6338 -79.94904) (xy 219.614242 -79.922624) (xy 219.597986 -79.917544) (xy 219.57232 -79.909173)
			(xy 219.523462 -79.886208) (xy 219.478328 -79.856586) (xy 219.437821 -79.820897) (xy 219.402749 -79.779856)
			(xy 219.373812 -79.73428) (xy 219.351588 -79.685081) (xy 219.33652 -79.63324) (xy 219.328911 -79.579793)
			(xy 219.328911 -79.525807) (xy 219.33652 -79.47236) (xy 219.351588 -79.420519) (xy 219.373812 -79.37132)
			(xy 219.402749 -79.325744) (xy 219.437821 -79.284703) (xy 219.478328 -79.249014) (xy 219.523462 -79.219392)
			(xy 219.57232 -79.196427) (xy 219.597986 -79.188056) (xy 219.59824 -79.188056) (xy 219.608386 -79.184361)
			(xy 219.624505 -79.170024) (xy 219.633309 -79.15033) (xy 219.6338 -79.139542) (xy 219.6338 -71.09333)
			(xy 219.634236 -71.083265) (xy 219.641968 -71.06468) (xy 219.648786 -71.057262) (xy 219.701618 -71.00443)
			(xy 219.709118 -70.996023) (xy 219.716657 -70.974821) (xy 219.714484 -70.952424) (xy 219.709238 -70.942454)
			(xy 219.689005 -70.907887) (xy 219.65413 -70.835777) (xy 219.625884 -70.760822) (xy 219.604497 -70.68363)
			(xy 219.590141 -70.604826) (xy 219.582935 -70.52505) (xy 219.582492 -70.485) (xy 219.583026 -70.441017)
			(xy 219.59171 -70.353481) (xy 219.608994 -70.26723) (xy 219.634707 -70.183106) (xy 219.6686 -70.101932)
			(xy 219.710341 -70.0245) (xy 219.759523 -69.951568) (xy 219.815664 -69.883846) (xy 219.878216 -69.821998)
			(xy 219.946569 -69.766628) (xy 220.020054 -69.718275) (xy 220.058742 -69.697346) (xy 220.060266 -69.696584)
			(xy 220.06507 -69.693736) (xy 220.073403 -69.686303) (xy 220.076776 -69.681852) (xy 220.09608 -69.65569)
			(xy 220.098366 -69.644768) (xy 220.10404 -69.61988) (xy 220.121114 -69.571773) (xy 220.144441 -69.526368)
			(xy 220.173605 -69.484473) (xy 220.208088 -69.446834) (xy 220.227398 -69.430138) (xy 220.229176 -69.428614)
			(xy 220.23324 -69.42455) (xy 220.23959 -69.418454) (xy 220.257116 -69.381878) (xy 220.257116 -69.319394)
			(xy 220.255846 -69.308218) (xy 220.253306 -69.297042) (xy 220.249496 -69.286374) (xy 220.23959 -69.265546)
			(xy 220.23324 -69.25945) (xy 220.229176 -69.255386) (xy 220.227398 -69.253862) (xy 220.206372 -69.235623)
			(xy 220.169311 -69.194096) (xy 220.138671 -69.14763) (xy 220.1151 -69.097207) (xy 220.099098 -69.043898)
			(xy 220.091004 -68.98883) (xy 220.090492 -68.961) (xy 220.090978 -68.933749) (xy 220.098734 -68.879801)
			(xy 220.114089 -68.827506) (xy 220.136731 -68.777929) (xy 220.166197 -68.732079) (xy 220.201888 -68.690888)
			(xy 220.243079 -68.655197) (xy 220.288929 -68.625731) (xy 220.338506 -68.603089) (xy 220.390801 -68.587734)
			(xy 220.444749 -68.579978) (xy 220.499251 -68.579978) (xy 220.553199 -68.587734) (xy 220.605494 -68.603089)
			(xy 220.655071 -68.625731) (xy 220.700921 -68.655197) (xy 220.742112 -68.690888) (xy 220.777803 -68.732079)
			(xy 220.807269 -68.777929) (xy 220.829911 -68.827506) (xy 220.845266 -68.879801) (xy 220.853022 -68.933749)
			(xy 220.853508 -68.961) (xy 220.853004 -68.98883) (xy 220.844918 -69.0439) (xy 220.828917 -69.097211)
			(xy 220.805341 -69.147632) (xy 220.774691 -69.194093) (xy 220.737616 -69.235608) (xy 220.716602 -69.253862)
			(xy 220.714824 -69.255386) (xy 220.71076 -69.25945) (xy 220.70441 -69.265546) (xy 220.69171 -69.291962)
			(xy 220.689452 -69.297137) (xy 220.687021 -69.308161) (xy 220.686884 -69.313806) (xy 220.686884 -69.370448)
			(xy 220.691964 -69.391784) (xy 220.69425 -69.396864) (xy 220.700092 -69.409564) (xy 220.702073 -69.413545)
			(xy 220.707183 -69.420824) (xy 220.710252 -69.424042) (xy 220.714824 -69.428614) (xy 220.716602 -69.430138)
			(xy 220.735953 -69.446793) (xy 220.770465 -69.48442) (xy 220.799644 -69.526317) (xy 220.822966 -69.571736)
			(xy 220.840015 -69.619862) (xy 220.845634 -69.644768) (xy 220.84792 -69.65569) (xy 220.867224 -69.681852)
			(xy 220.870597 -69.686303) (xy 220.878932 -69.693732) (xy 220.883734 -69.696584) (xy 220.885258 -69.697346)
			(xy 220.919177 -69.715607) (xy 220.984044 -69.757169) (xy 221.045075 -69.804184) (xy 221.073726 -69.829934)
			(xy 221.080584 -69.836284) (xy 221.114366 -69.85) (xy 222.990918 -69.85) (xy 222.9993 -69.849238)
			(xy 223.006906 -69.847725) (xy 223.020743 -69.840742) (xy 223.026478 -69.835522) (xy 223.632014 -69.229986)
			(xy 223.638868 -69.222591) (xy 223.64661 -69.203992) (xy 223.647 -69.193918) (xy 223.647 -59.417712)
			(xy 223.645222 -59.406536) (xy 223.64446 -59.403742) (xy 223.616407 -59.299629) (xy 223.567305 -59.089644)
			(xy 223.526269 -58.877935) (xy 223.493362 -58.664811) (xy 223.46863 -58.450585) (xy 223.452109 -58.235569)
			(xy 223.443825 -58.020079) (xy 223.443292 -57.912254) (xy 223.443786 -57.806871) (xy 223.451668 -57.596252)
			(xy 223.46742 -57.386075) (xy 223.491019 -57.176634) (xy 223.522433 -56.968222) (xy 223.561617 -56.76113)
			(xy 223.608517 -56.555649) (xy 223.663067 -56.352064) (xy 223.725191 -56.150661) (xy 223.794802 -55.951722)
			(xy 223.871802 -55.755525) (xy 223.956085 -55.562344) (xy 224.047532 -55.37245) (xy 224.146014 -55.186107)
			(xy 224.251396 -55.003577) (xy 224.363528 -54.825115) (xy 224.482255 -54.65097) (xy 224.60741 -54.481386)
			(xy 224.738818 -54.316601) (xy 224.876295 -54.156843) (xy 225.01965 -54.002338) (xy 225.168681 -53.853301)
			(xy 225.323181 -53.70994) (xy 225.482933 -53.572457) (xy 225.647713 -53.441042) (xy 225.817292 -53.315881)
			(xy 225.991432 -53.197147) (xy 226.16989 -53.085008) (xy 226.352416 -52.97962) (xy 226.538755 -52.88113)
			(xy 226.728646 -52.789676) (xy 226.921824 -52.705386) (xy 227.118018 -52.628378) (xy 227.316954 -52.558759)
			(xy 227.518354 -52.496627) (xy 227.721937 -52.442069) (xy 227.927417 -52.395161) (xy 228.134507 -52.355969)
			(xy 228.342918 -52.324547) (xy 228.552358 -52.30094) (xy 228.762534 -52.28518) (xy 228.973153 -52.27729)
			(xy 229.078536 -52.276756) (xy 255.981962 -52.276756) (xy 255.991837 -52.276289) (xy 256.010129 -52.268841)
			(xy 256.017522 -52.262278) (xy 256.931414 -51.348386) (xy 256.931922 -51.347878) (xy 256.938512 -51.3405)
			(xy 256.945979 -51.322201) (xy 256.9464 -51.312318) (xy 256.9464 -36.978082) (xy 256.946827 -36.968013)
			(xy 256.954546 -36.949414) (xy 256.961386 -36.942014) (xy 262.468614 -31.434786) (xy 262.476009 -31.427932)
			(xy 262.494608 -31.42019) (xy 262.504682 -31.4198) (xy 269.244318 -31.4198) (xy 269.254387 -31.420227)
			(xy 269.272986 -31.427946) (xy 269.280386 -31.434786) (xy 270.926814 -33.081214) (xy 270.927322 -33.081722)
			(xy 270.9347 -33.088312) (xy 270.952999 -33.095779) (xy 270.962882 -33.0962) (xy 272.5928 -33.0962)
			(xy 273.939 -31.75) (xy 280.416 -31.75) (xy 283.21 -28.956) (xy 287.8836 -28.956) (xy 292.906958 -33.979104)
			(xy 292.907466 -33.979612) (xy 292.914846 -33.986197) (xy 292.933146 -33.993649) (xy 292.943026 -33.99409)
			(xy 302.434752 -33.99409) (xy 302.444818 -33.994522) (xy 302.46341 -34.002249) (xy 302.47082 -34.009076)
			(xy 302.876966 -34.415222) (xy 302.879542 -34.417731) (xy 302.885278 -34.422067) (xy 302.888396 -34.423858)
			(xy 302.893984 -34.426906) (xy 302.900842 -34.428684) (xy 302.901096 -34.428684) (xy 302.907783 -34.430583)
			(xy 302.919891 -34.437402) (xy 302.924972 -34.442146) (xy 304.603658 -36.120832) (xy 304.610504 -36.12823)
			(xy 304.618233 -36.146829) (xy 304.618644 -36.1569) (xy 304.618644 -44.304966) (xy 306.278033 -44.304966)
			(xy 306.28204 -44.102216) (xy 306.294053 -43.899782) (xy 306.314054 -43.697981) (xy 306.342013 -43.497127)
			(xy 306.377884 -43.297535) (xy 306.421613 -43.099516) (xy 306.473131 -42.903379) (xy 306.532357 -42.709431)
			(xy 306.599199 -42.517973) (xy 306.673553 -42.329306) (xy 306.755302 -42.143724) (xy 306.84432 -41.961516)
			(xy 306.940466 -41.782967) (xy 307.043591 -41.608356) (xy 307.153534 -41.437956) (xy 307.270123 -41.272032)
			(xy 307.393176 -41.110843) (xy 307.522501 -40.954642) (xy 307.657896 -40.803672) (xy 307.799149 -40.658168)
			(xy 307.946041 -40.518359) (xy 308.098341 -40.384462) (xy 308.255812 -40.256687) (xy 308.418209 -40.135232)
			(xy 308.585276 -40.020288) (xy 308.756755 -39.912034) (xy 308.932376 -39.810639) (xy 309.111866 -39.716261)
			(xy 309.294944 -39.629049) (xy 309.481325 -39.549137) (xy 309.670718 -39.47665) (xy 309.862826 -39.411703)
			(xy 310.05735 -39.354395) (xy 310.253986 -39.304818) (xy 310.452428 -39.263047) (xy 310.652365 -39.229149)
			(xy 310.853484 -39.203177) (xy 311.055473 -39.18517) (xy 311.258016 -39.175157) (xy 311.460796 -39.173153)
			(xy 311.663497 -39.179163) (xy 311.865802 -39.193175) (xy 312.067396 -39.21517) (xy 312.267963 -39.245111)
			(xy 312.467191 -39.282952) (xy 312.664769 -39.328635) (xy 312.860387 -39.382088) (xy 313.053741 -39.443227)
			(xy 313.244529 -39.511958) (xy 313.432452 -39.588172) (xy 313.617218 -39.671751) (xy 313.798537 -39.762564)
			(xy 313.976128 -39.860469) (xy 314.149711 -39.965314) (xy 314.319017 -40.076935) (xy 314.483782 -40.195157)
			(xy 314.643747 -40.319797) (xy 314.798663 -40.450658) (xy 314.948288 -40.587538) (xy 315.092388 -40.730222)
			(xy 315.23074 -40.878488) (xy 315.363125 -41.032104) (xy 315.489339 -41.190829) (xy 315.609183 -41.354418)
			(xy 315.722471 -41.522613) (xy 315.829026 -41.695152) (xy 315.928681 -41.871767) (xy 316.021281 -42.05218)
			(xy 316.106681 -42.236111) (xy 316.184748 -42.423272) (xy 316.25536 -42.613372) (xy 316.318406 -42.806112)
			(xy 316.373789 -43.001193) (xy 316.421421 -43.19831) (xy 316.461229 -43.397154) (xy 316.493151 -43.597416)
			(xy 316.517135 -43.798782) (xy 316.533146 -44.000939) (xy 316.541157 -44.203571) (xy 316.541658 -44.304966)
			(xy 316.541157 -44.406361) (xy 316.533146 -44.608993) (xy 316.517135 -44.81115) (xy 316.493151 -45.012516)
			(xy 316.461229 -45.212778) (xy 316.421421 -45.411622) (xy 316.373789 -45.608739) (xy 316.318406 -45.80382)
			(xy 316.25536 -45.99656) (xy 316.184748 -46.18666) (xy 316.106681 -46.373821) (xy 316.021281 -46.557752)
			(xy 315.928681 -46.738165) (xy 315.829026 -46.91478) (xy 315.722471 -47.087319) (xy 315.609183 -47.255514)
			(xy 315.489339 -47.419103) (xy 315.363125 -47.577828) (xy 315.23074 -47.731444) (xy 315.092388 -47.87971)
			(xy 314.948288 -48.022394) (xy 314.798663 -48.159274) (xy 314.643747 -48.290135) (xy 314.483782 -48.414775)
			(xy 314.319017 -48.532997) (xy 314.149711 -48.644618) (xy 313.976128 -48.749463) (xy 313.798537 -48.847368)
			(xy 313.617218 -48.938181) (xy 313.432452 -49.02176) (xy 313.244529 -49.097974) (xy 313.053741 -49.166705)
			(xy 312.860387 -49.227844) (xy 312.664769 -49.281297) (xy 312.467191 -49.32698) (xy 312.267963 -49.364821)
			(xy 312.067396 -49.394762) (xy 311.865802 -49.416757) (xy 311.663497 -49.430769) (xy 311.460796 -49.436779)
			(xy 311.258016 -49.434775) (xy 311.055473 -49.424762) (xy 310.853484 -49.406755) (xy 310.652365 -49.380783)
			(xy 310.452428 -49.346885) (xy 310.253986 -49.305114) (xy 310.05735 -49.255537) (xy 309.862826 -49.198229)
			(xy 309.670718 -49.133282) (xy 309.481325 -49.060795) (xy 309.294944 -48.980883) (xy 309.111866 -48.893671)
			(xy 308.932376 -48.799293) (xy 308.756755 -48.697898) (xy 308.585276 -48.589644) (xy 308.418209 -48.4747)
			(xy 308.255812 -48.353245) (xy 308.098341 -48.22547) (xy 307.946041 -48.091573) (xy 307.799149 -47.951764)
			(xy 307.657896 -47.80626) (xy 307.522501 -47.65529) (xy 307.393176 -47.499089) (xy 307.270123 -47.3379)
			(xy 307.153534 -47.171976) (xy 307.043591 -47.001576) (xy 306.940466 -46.826965) (xy 306.84432 -46.648416)
			(xy 306.755302 -46.466208) (xy 306.673553 -46.280626) (xy 306.599199 -46.091959) (xy 306.532357 -45.900501)
			(xy 306.473131 -45.706553) (xy 306.421613 -45.510416) (xy 306.377884 -45.312397) (xy 306.342013 -45.112805)
			(xy 306.314054 -44.911951) (xy 306.294053 -44.71015) (xy 306.28204 -44.507716) (xy 306.278033 -44.304966)
			(xy 304.618644 -44.304966) (xy 304.618644 -48.916082) (xy 304.619083 -48.926145) (xy 304.626824 -48.944723)
			(xy 304.63363 -48.95215) (xy 309.45836 -53.77688) (xy 309.465198 -53.784281) (xy 309.47291 -53.80288)
			(xy 309.473346 -53.812948) (xy 309.473346 -69.040248) (xy 309.473779 -69.050313) (xy 309.481511 -69.068901)
			(xy 309.488332 -69.076316) (xy 310.651652 -70.239636) (xy 310.65905 -70.246481) (xy 310.677649 -70.254207)
			(xy 310.68772 -70.254622) (xy 320.23558 -70.254622) (xy 320.245643 -70.25506) (xy 320.264225 -70.262798)
			(xy 320.271648 -70.269608) (xy 322.910454 -72.908414) (xy 322.917303 -72.915811) (xy 322.92504 -72.93441)
			(xy 322.92544 -72.944482) (xy 322.92544 -122.678952) (xy 322.925006 -122.689017) (xy 322.917271 -122.707602)
			(xy 322.910454 -122.71502) (xy 320.92646 -124.699014) (xy 320.919064 -124.705864) (xy 320.900464 -124.713597)
			(xy 320.890392 -124.714) (xy 301.978822 -124.714) (xy 300.275752 -126.41707) (xy 300.275752 -131.79552)
			(xy 297.906948 -134.164324) (xy 297.829986 -134.164324) (xy 297.82259 -134.171176) (xy 297.803991 -134.178918)
			(xy 297.793918 -134.17931) (xy 279.596342 -134.17931) (xy 279.577546 -134.18693) (xy 279.570434 -134.194296)
			(xy 279.00376 -134.76097) (xy 278.996918 -134.768369) (xy 278.989199 -134.786968) (xy 278.988774 -134.797038)
			(xy 278.988774 -143.976344) (xy 278.989204 -143.986411) (xy 278.996927 -144.005007) (xy 279.00376 -144.012412)
			(xy 280.54681 -145.555462) (xy 280.554207 -145.562311) (xy 280.572806 -145.570048) (xy 280.582878 -145.570448)
			(xy 322.7959 -145.570448)
		)
		(stroke
			(width 0)
			(type solid)
		)
		(fill yes)
		(layer "In2.Cu")
		(net "GND")
	)
	(gr_poly
		(pts
			(arc
				(start 298.302172 -132.452364)
				(mid 298.321695 -132.448463)
				(end 298.33824 -132.437378)
			)
			(arc
				(start 299.240448 -131.53517)
				(mid 299.251559 -131.518636)
				(end 299.255434 -131.499102)
			)
			(xy 299.255434 -122.167396) (xy 299.252894 -122.156474)
			(arc
				(start 299.250354 -122.15114)
				(mid 299.221372 -122.069537)
				(end 299.211492 -121.9835)
			)
			(arc
				(start 299.211492 -121.9835)
				(mid 299.221323 -121.897451)
				(end 299.250354 -121.81586)
			)
			(xy 299.252894 -121.810526) (xy 299.255434 -121.799604) (xy 299.255434 -121.278396) (xy 299.252894 -121.267474)
			(arc
				(start 299.250354 -121.26214)
				(mid 299.221372 -121.180537)
				(end 299.211492 -121.0945)
			)
			(arc
				(start 299.211492 -121.0945)
				(mid 299.221323 -121.008451)
				(end 299.250354 -120.92686)
			)
			(xy 299.252894 -120.921526) (xy 299.255434 -120.910604) (xy 299.255434 -120.389396) (xy 299.252894 -120.378474)
			(arc
				(start 299.250354 -120.37314)
				(mid 299.221372 -120.291537)
				(end 299.211492 -120.2055)
			)
			(arc
				(start 299.211492 -120.2055)
				(mid 299.221323 -120.119451)
				(end 299.250354 -120.03786)
			)
			(xy 299.252894 -120.032526) (xy 299.255434 -120.021604) (xy 299.255434 -119.500396) (xy 299.252894 -119.489474)
			(arc
				(start 299.250354 -119.48414)
				(mid 299.221372 -119.402537)
				(end 299.211492 -119.3165)
			)
			(arc
				(start 299.211492 -119.3165)
				(mid 299.221323 -119.230451)
				(end 299.250354 -119.14886)
			)
			(xy 299.252894 -119.143526) (xy 299.255434 -119.132604)
			(arc
				(start 299.255434 -98.091244)
				(mid 299.251533 -98.071721)
				(end 299.240448 -98.055176)
			)
			(arc
				(start 298.075858 -96.890586)
				(mid 298.059324 -96.879475)
				(end 298.03979 -96.8756)
			)
			(arc
				(start 279.923494 -96.8756)
				(mid 279.903971 -96.879501)
				(end 279.887426 -96.890586)
			)
			(arc
				(start 278.722836 -98.055176)
				(mid 278.711725 -98.07171)
				(end 278.70785 -98.091244)
			)
			(arc
				(start 278.70785 -131.362958)
				(mid 278.711751 -131.382481)
				(end 278.722836 -131.399026)
			)
			(arc
				(start 279.761188 -132.437378)
				(mid 279.777722 -132.448489)
				(end 279.797256 -132.452364)
			)
		)
		(stroke
			(width 0)
			(type solid)
		)
		(fill yes)
		(layer "In3.Cu")
		(net "P52V_HS1_DRAIN_1")
	)
	(gr_poly
		(pts
			(arc
				(start 298.03979 -95.8596)
				(mid 298.059313 -95.855699)
				(end 298.075858 -95.844614)
			)
			(arc
				(start 299.240448 -94.680024)
				(mid 299.251559 -94.66349)
				(end 299.255434 -94.643956)
			)
			(arc
				(start 299.255434 -86.018878)
				(mid 299.25339 -86.004863)
				(end 299.24756 -85.991954)
			)
			(arc
				(start 299.24756 -85.991954)
				(mid 299.203848 -85.894376)
				(end 299.188886 -85.7885)
			)
			(arc
				(start 299.188886 -85.7885)
				(mid 299.203802 -85.682611)
				(end 299.24756 -85.585046)
			)
			(arc
				(start 299.24756 -85.585046)
				(mid 299.253395 -85.572139)
				(end 299.255434 -85.558122)
			)
			(arc
				(start 299.255434 -85.129878)
				(mid 299.25339 -85.115863)
				(end 299.24756 -85.102954)
			)
			(arc
				(start 299.24756 -85.102954)
				(mid 299.203848 -85.005376)
				(end 299.188886 -84.8995)
			)
			(arc
				(start 299.188886 -84.8995)
				(mid 299.203802 -84.793611)
				(end 299.24756 -84.696046)
			)
			(arc
				(start 299.24756 -84.696046)
				(mid 299.253395 -84.683139)
				(end 299.255434 -84.669122)
			)
			(arc
				(start 299.255434 -84.240878)
				(mid 299.25339 -84.226863)
				(end 299.24756 -84.213954)
			)
			(arc
				(start 299.24756 -84.213954)
				(mid 299.203848 -84.116376)
				(end 299.188886 -84.0105)
			)
			(arc
				(start 299.188886 -84.0105)
				(mid 299.203802 -83.904611)
				(end 299.24756 -83.807046)
			)
			(arc
				(start 299.24756 -83.807046)
				(mid 299.253395 -83.794139)
				(end 299.255434 -83.780122)
			)
			(arc
				(start 299.255434 -83.351878)
				(mid 299.25339 -83.337863)
				(end 299.24756 -83.324954)
			)
			(arc
				(start 299.24756 -83.324954)
				(mid 299.203848 -83.227376)
				(end 299.188886 -83.1215)
			)
			(arc
				(start 299.188886 -83.1215)
				(mid 299.203802 -83.015611)
				(end 299.24756 -82.918046)
			)
			(arc
				(start 299.24756 -82.918046)
				(mid 299.253395 -82.905139)
				(end 299.255434 -82.891122)
			)
			(xy 299.255434 -78.790546)
			(arc
				(start 299.254672 -78.786482)
				(mid 299.251029 -78.755972)
				(end 299.249846 -78.725268)
			)
			(arc
				(start 299.249846 -78.725268)
				(mid 299.251022 -78.694563)
				(end 299.254672 -78.664054)
			)
			(xy 299.255434 -78.65999) (xy 299.255434 -77.774546)
			(arc
				(start 299.254672 -77.770482)
				(mid 299.251029 -77.739972)
				(end 299.249846 -77.709268)
			)
			(arc
				(start 299.249846 -77.709268)
				(mid 299.251022 -77.678563)
				(end 299.254672 -77.648054)
			)
			(xy 299.255434 -77.64399)
			(arc
				(start 299.255434 -61.186822)
				(mid 299.251533 -61.167299)
				(end 299.240448 -61.150754)
			)
			(arc
				(start 298.329858 -60.240164)
				(mid 298.313324 -60.229053)
				(end 298.29379 -60.225178)
			)
			(arc
				(start 279.88006 -60.225178)
				(mid 279.860537 -60.229079)
				(end 279.843992 -60.240164)
			)
			(arc
				(start 278.722836 -61.36132)
				(mid 278.711725 -61.377854)
				(end 278.70785 -61.397388)
			)
			(arc
				(start 278.70785 -94.643956)
				(mid 278.711751 -94.663479)
				(end 278.722836 -94.680024)
			)
			(arc
				(start 279.887426 -95.844614)
				(mid 279.90396 -95.855725)
				(end 279.923494 -95.8596)
			)
		)
		(stroke
			(width 0)
			(type solid)
		)
		(fill yes)
		(layer "In3.Cu")
		(net "P52V_HS1_DRAIN_2")
	)
	(gr_poly
		(pts
			(xy 319.402206 -121.6914) (xy 319.412276 -121.690976) (xy 319.430879 -121.68326) (xy 319.438274 -121.676414)
			(xy 320.406014 -120.708674) (xy 320.412866 -120.701278) (xy 320.420604 -120.682679) (xy 320.421 -120.672606)
			(xy 320.421 -77.091794) (xy 320.420576 -77.081724) (xy 320.41286 -77.063121) (xy 320.406014 -77.055726)
			(xy 319.692274 -76.341986) (xy 319.684878 -76.335134) (xy 319.666279 -76.327396) (xy 319.656206 -76.327)
			(xy 308.6608 -76.327) (xy 308.62754 -76.326479) (xy 308.56159 -76.317791) (xy 308.497339 -76.300566)
			(xy 308.435888 -76.275097) (xy 308.378289 -76.241821) (xy 308.325529 -76.201308) (xy 308.301644 -76.178156)
			(xy 306.185824 -74.062336) (xy 306.178423 -74.055498) (xy 306.159824 -74.047785) (xy 306.149756 -74.04735)
			(xy 300.86427 -74.04735) (xy 300.854203 -74.04778) (xy 300.835612 -74.055508) (xy 300.828202 -74.062336)
			(xy 300.28642 -74.604118) (xy 300.279574 -74.611517) (xy 300.271843 -74.630115) (xy 300.271434 -74.640186)
			(xy 300.271434 -88.45423) (xy 300.271729 -88.462103) (xy 300.276515 -88.477104) (xy 300.280832 -88.483694)
			(xy 300.295759 -88.505354) (xy 300.32016 -88.551955) (xy 300.337926 -88.601467) (xy 300.348721 -88.652951)
			(xy 300.352339 -88.705429) (xy 300.348712 -88.757907) (xy 300.33791 -88.809389) (xy 300.320136 -88.858899)
			(xy 300.295729 -88.905496) (xy 300.280832 -88.927178) (xy 300.276501 -88.933762) (xy 300.271707 -88.948766)
			(xy 300.271434 -88.956642) (xy 300.271434 -101.454966) (xy 307.269651 -101.454966) (xy 307.273647 -101.2731)
			(xy 307.285627 -101.091585) (xy 307.305569 -100.910772) (xy 307.333434 -100.731009) (xy 307.369168 -100.552644)
			(xy 307.412701 -100.37602) (xy 307.463951 -100.201479) (xy 307.522818 -100.029357) (xy 307.589189 -99.859987)
			(xy 307.662935 -99.693696) (xy 307.743914 -99.530805) (xy 307.831969 -99.371628) (xy 307.926932 -99.216472)
			(xy 308.028617 -99.065637) (xy 308.13683 -98.919415) (xy 308.251362 -98.778086) (xy 308.37199 -98.641925)
			(xy 308.498483 -98.511193) (xy 308.630596 -98.386144) (xy 308.768074 -98.267018) (xy 308.910652 -98.154046)
			(xy 309.058055 -98.047446) (xy 309.209998 -97.947423) (xy 309.366187 -97.854171) (xy 309.526322 -97.767869)
			(xy 309.690093 -97.688684) (xy 309.857184 -97.616769) (xy 310.027272 -97.552263) (xy 310.20003 -97.495291)
			(xy 310.375124 -97.445961) (xy 310.552215 -97.40437) (xy 310.730962 -97.370597) (xy 310.91102 -97.344709)
			(xy 311.092042 -97.326754) (xy 311.273677 -97.316768) (xy 311.455576 -97.31477) (xy 311.637387 -97.320764)
			(xy 311.818759 -97.334737) (xy 311.999343 -97.356664) (xy 312.178789 -97.386502) (xy 312.356751 -97.424193)
			(xy 312.532886 -97.469664) (xy 312.706854 -97.522828) (xy 312.878318 -97.583582) (xy 313.046949 -97.651809)
			(xy 313.21242 -97.727377) (xy 313.374412 -97.81014) (xy 313.532612 -97.899939) (xy 313.686715 -97.9966)
			(xy 313.836424 -98.099937) (xy 313.981449 -98.209749) (xy 314.121511 -98.325826) (xy 314.256339 -98.447943)
			(xy 314.385673 -98.575864) (xy 314.509264 -98.709343) (xy 314.626872 -98.848121) (xy 314.738271 -98.991932)
			(xy 314.843246 -99.140496) (xy 314.941594 -99.293528) (xy 315.033125 -99.450733) (xy 315.117663 -99.611806)
			(xy 315.195044 -99.776437) (xy 315.265119 -99.944308) (xy 315.327753 -100.115095) (xy 315.382824 -100.288468)
			(xy 315.430228 -100.464093) (xy 315.469871 -100.64163) (xy 315.501678 -100.820737) (xy 315.525587 -101.001069)
			(xy 315.541552 -101.182277) (xy 315.549542 -101.364011) (xy 315.550042 -101.454966) (xy 315.549542 -101.545921)
			(xy 315.541552 -101.727655) (xy 315.525587 -101.908863) (xy 315.501678 -102.089195) (xy 315.469871 -102.268302)
			(xy 315.430228 -102.445839) (xy 315.382824 -102.621464) (xy 315.327753 -102.794837) (xy 315.265119 -102.965624)
			(xy 315.195044 -103.133495) (xy 315.117663 -103.298126) (xy 315.033125 -103.459199) (xy 314.941594 -103.616404)
			(xy 314.843246 -103.769436) (xy 314.738271 -103.918) (xy 314.626872 -104.061811) (xy 314.509264 -104.200589)
			(xy 314.385673 -104.334068) (xy 314.256339 -104.461989) (xy 314.121511 -104.584106) (xy 313.981449 -104.700183)
			(xy 313.836424 -104.809995) (xy 313.686715 -104.913332) (xy 313.532612 -105.009993) (xy 313.374412 -105.099792)
			(xy 313.21242 -105.182555) (xy 313.046949 -105.258123) (xy 312.878318 -105.32635) (xy 312.706854 -105.387104)
			(xy 312.532886 -105.440268) (xy 312.356751 -105.485739) (xy 312.178789 -105.52343) (xy 311.999343 -105.553268)
			(xy 311.818759 -105.575195) (xy 311.637387 -105.589168) (xy 311.455576 -105.595162) (xy 311.273677 -105.593164)
			(xy 311.092042 -105.583178) (xy 310.91102 -105.565223) (xy 310.730962 -105.539335) (xy 310.552215 -105.505562)
			(xy 310.375124 -105.463971) (xy 310.20003 -105.414641) (xy 310.027272 -105.357669) (xy 309.857184 -105.293163)
			(xy 309.690093 -105.221248) (xy 309.526322 -105.142063) (xy 309.366187 -105.055761) (xy 309.209998 -104.962509)
			(xy 309.058055 -104.862486) (xy 308.910652 -104.755886) (xy 308.768074 -104.642914) (xy 308.630596 -104.523788)
			(xy 308.498483 -104.398739) (xy 308.37199 -104.268007) (xy 308.251362 -104.131846) (xy 308.13683 -103.990517)
			(xy 308.028617 -103.844295) (xy 307.926932 -103.69346) (xy 307.831969 -103.538304) (xy 307.743914 -103.379127)
			(xy 307.662935 -103.216236) (xy 307.589189 -103.049945) (xy 307.522818 -102.880575) (xy 307.463951 -102.708453)
			(xy 307.412701 -102.533912) (xy 307.369168 -102.357288) (xy 307.333434 -102.178923) (xy 307.305569 -101.99916)
			(xy 307.285627 -101.818347) (xy 307.273647 -101.636832) (xy 307.269651 -101.454966) (xy 300.271434 -101.454966)
			(xy 300.271434 -120.646698) (xy 300.271857 -120.656768) (xy 300.279575 -120.67537) (xy 300.28642 -120.682766)
			(xy 301.280068 -121.676414) (xy 301.287466 -121.683259) (xy 301.306065 -121.690982) (xy 301.316136 -121.6914)
		)
		(stroke
			(width 0)
			(type solid)
		)
		(fill yes)
		(layer "In3.Cu")
		(net "P52V_1")
	)
	(gr_poly
		(pts
			(xy 326.00011 -166.271956) (xy 326.055917 -166.271446) (xy 326.167218 -166.263105) (xy 326.277585 -166.246469)
			(xy 326.386399 -166.221631) (xy 326.493054 -166.188731) (xy 326.596951 -166.147953) (xy 326.697511 -166.099525)
			(xy 326.79417 -166.043717) (xy 326.886389 -165.980841) (xy 326.973651 -165.91125) (xy 327.055468 -165.835332)
			(xy 327.131383 -165.753513) (xy 327.200971 -165.666249) (xy 327.263843 -165.574028) (xy 327.319648 -165.477367)
			(xy 327.368073 -165.376806) (xy 327.408848 -165.272907) (xy 327.441744 -165.166251) (xy 327.466578 -165.057436)
			(xy 327.48321 -164.947068) (xy 327.491548 -164.835767) (xy 327.492106 -164.77996) (xy 327.492106 -150.999952)
			(xy 327.491583 -150.944146) (xy 327.483238 -150.832846) (xy 327.4666 -150.722481) (xy 327.441761 -150.613668)
			(xy 327.408861 -150.507016) (xy 327.368082 -150.40312) (xy 327.319653 -150.302562) (xy 327.263845 -150.205904)
			(xy 327.20097 -150.113687) (xy 327.13138 -150.026426) (xy 327.055463 -149.94461) (xy 326.973645 -149.868695)
			(xy 326.886382 -149.799107) (xy 326.794164 -149.736235) (xy 326.697504 -149.680429) (xy 326.596945 -149.632003)
			(xy 326.493048 -149.591227) (xy 326.386395 -149.558329) (xy 326.277581 -149.533493) (xy 326.167216 -149.516857)
			(xy 326.055916 -149.508516) (xy 326.00011 -149.507956) (xy 154.399996 -149.507956) (xy 154.344188 -149.508478)
			(xy 154.232885 -149.516819) (xy 154.122517 -149.533454) (xy 154.0137 -149.558291) (xy 153.907043 -149.591189)
			(xy 153.803144 -149.631966) (xy 153.702581 -149.680394) (xy 153.605919 -149.7362) (xy 153.513698 -149.799075)
			(xy 153.426433 -149.868664) (xy 153.344612 -149.944581) (xy 153.268693 -150.026399) (xy 153.199101 -150.113662)
			(xy 153.136224 -150.205882) (xy 153.080414 -150.302543) (xy 153.031984 -150.403103) (xy 152.991204 -150.507002)
			(xy 152.958302 -150.613657) (xy 152.933462 -150.722474) (xy 152.916824 -150.832842) (xy 152.908479 -150.944144)
			(xy 152.908 -150.999952) (xy 152.908 -161.844536) (xy 155.304225 -161.844536) (xy 155.304225 -161.715396)
			(xy 155.312175 -161.586501) (xy 155.328045 -161.458341) (xy 155.351774 -161.3314) (xy 155.383273 -161.206161)
			(xy 155.422422 -161.083098) (xy 155.469073 -160.962679) (xy 155.523048 -160.84536) (xy 155.584143 -160.731586)
			(xy 155.652126 -160.621789) (xy 155.72674 -160.516386) (xy 155.807701 -160.415776) (xy 155.894701 -160.320341)
			(xy 155.987412 -160.230442) (xy 156.085482 -160.146421) (xy 156.188537 -160.068597) (xy 156.296188 -159.997265)
			(xy 156.408027 -159.932695) (xy 156.523628 -159.875133) (xy 156.642553 -159.824796) (xy 156.764352 -159.781876)
			(xy 156.888562 -159.746535) (xy 157.014711 -159.718908) (xy 157.142323 -159.699099) (xy 157.270912 -159.687183)
			(xy 157.39999 -159.683207) (xy 157.529068 -159.687183) (xy 157.657657 -159.699099) (xy 157.785269 -159.718908)
			(xy 157.911418 -159.746535) (xy 158.035628 -159.781876) (xy 158.157427 -159.824796) (xy 158.276352 -159.875133)
			(xy 158.391953 -159.932695) (xy 158.503792 -159.997265) (xy 158.611443 -160.068597) (xy 158.714498 -160.146421)
			(xy 158.812568 -160.230442) (xy 158.905279 -160.320341) (xy 158.992279 -160.415776) (xy 159.07324 -160.516386)
			(xy 159.147854 -160.621789) (xy 159.215837 -160.731586) (xy 159.276932 -160.84536) (xy 159.330907 -160.962679)
			(xy 159.377558 -161.083098) (xy 159.416707 -161.206161) (xy 159.448206 -161.3314) (xy 159.471935 -161.458341)
			(xy 159.487805 -161.586501) (xy 159.495755 -161.715396) (xy 159.496252 -161.779966) (xy 159.495755 -161.844536)
			(xy 320.904351 -161.844536) (xy 320.904351 -161.715396) (xy 320.912301 -161.586501) (xy 320.928171 -161.458341)
			(xy 320.9519 -161.3314) (xy 320.983399 -161.206161) (xy 321.022548 -161.083098) (xy 321.069199 -160.962679)
			(xy 321.123174 -160.84536) (xy 321.184269 -160.731586) (xy 321.252252 -160.621789) (xy 321.326866 -160.516386)
			(xy 321.407827 -160.415776) (xy 321.494827 -160.320341) (xy 321.587538 -160.230442) (xy 321.685608 -160.146421)
			(xy 321.788663 -160.068597) (xy 321.896314 -159.997265) (xy 322.008153 -159.932695) (xy 322.123754 -159.875133)
			(xy 322.242679 -159.824796) (xy 322.364478 -159.781876) (xy 322.488688 -159.746535) (xy 322.614837 -159.718908)
			(xy 322.742449 -159.699099) (xy 322.871038 -159.687183) (xy 323.000116 -159.683207) (xy 323.129194 -159.687183)
			(xy 323.257783 -159.699099) (xy 323.385395 -159.718908) (xy 323.511544 -159.746535) (xy 323.635754 -159.781876)
			(xy 323.757553 -159.824796) (xy 323.876478 -159.875133) (xy 323.992079 -159.932695) (xy 324.103918 -159.997265)
			(xy 324.211569 -160.068597) (xy 324.314624 -160.146421) (xy 324.412694 -160.230442) (xy 324.505405 -160.320341)
			(xy 324.592405 -160.415776) (xy 324.673366 -160.516386) (xy 324.74798 -160.621789) (xy 324.815963 -160.731586)
			(xy 324.877058 -160.84536) (xy 324.931033 -160.962679) (xy 324.977684 -161.083098) (xy 325.016833 -161.206161)
			(xy 325.048332 -161.3314) (xy 325.072061 -161.458341) (xy 325.087931 -161.586501) (xy 325.095881 -161.715396)
			(xy 325.096378 -161.779966) (xy 325.095881 -161.844536) (xy 325.087931 -161.973431) (xy 325.072061 -162.101591)
			(xy 325.048332 -162.228532) (xy 325.016833 -162.353771) (xy 324.977684 -162.476834) (xy 324.931033 -162.597253)
			(xy 324.877058 -162.714572) (xy 324.815963 -162.828346) (xy 324.74798 -162.938143) (xy 324.673366 -163.043546)
			(xy 324.592405 -163.144156) (xy 324.505405 -163.239591) (xy 324.412694 -163.32949) (xy 324.314624 -163.413511)
			(xy 324.211569 -163.491335) (xy 324.103918 -163.562667) (xy 323.992079 -163.627237) (xy 323.876478 -163.684799)
			(xy 323.757553 -163.735136) (xy 323.635754 -163.778056) (xy 323.511544 -163.813397) (xy 323.385395 -163.841024)
			(xy 323.257783 -163.860833) (xy 323.129194 -163.872749) (xy 323.000116 -163.876726) (xy 322.871038 -163.872749)
			(xy 322.742449 -163.860833) (xy 322.614837 -163.841024) (xy 322.488688 -163.813397) (xy 322.364478 -163.778056)
			(xy 322.242679 -163.735136) (xy 322.123754 -163.684799) (xy 322.008153 -163.627237) (xy 321.896314 -163.562667)
			(xy 321.788663 -163.491335) (xy 321.685608 -163.413511) (xy 321.587538 -163.32949) (xy 321.494827 -163.239591)
			(xy 321.407827 -163.144156) (xy 321.326866 -163.043546) (xy 321.252252 -162.938143) (xy 321.184269 -162.828346)
			(xy 321.123174 -162.714572) (xy 321.069199 -162.597253) (xy 321.022548 -162.476834) (xy 320.983399 -162.353771)
			(xy 320.9519 -162.228532) (xy 320.928171 -162.101591) (xy 320.912301 -161.973431) (xy 320.904351 -161.844536)
			(xy 159.495755 -161.844536) (xy 159.487805 -161.973431) (xy 159.471935 -162.101591) (xy 159.448206 -162.228532)
			(xy 159.416707 -162.353771) (xy 159.377558 -162.476834) (xy 159.330907 -162.597253) (xy 159.276932 -162.714572)
			(xy 159.215837 -162.828346) (xy 159.147854 -162.938143) (xy 159.07324 -163.043546) (xy 158.992279 -163.144156)
			(xy 158.905279 -163.239591) (xy 158.812568 -163.32949) (xy 158.714498 -163.413511) (xy 158.611443 -163.491335)
			(xy 158.503792 -163.562667) (xy 158.391953 -163.627237) (xy 158.276352 -163.684799) (xy 158.157427 -163.735136)
			(xy 158.035628 -163.778056) (xy 157.911418 -163.813397) (xy 157.785269 -163.841024) (xy 157.657657 -163.860833)
			(xy 157.529068 -163.872749) (xy 157.39999 -163.876726) (xy 157.270912 -163.872749) (xy 157.142323 -163.860833)
			(xy 157.014711 -163.841024) (xy 156.888562 -163.813397) (xy 156.764352 -163.778056) (xy 156.642553 -163.735136)
			(xy 156.523628 -163.684799) (xy 156.408027 -163.627237) (xy 156.296188 -163.562667) (xy 156.188537 -163.491335)
			(xy 156.085482 -163.413511) (xy 155.987412 -163.32949) (xy 155.894701 -163.239591) (xy 155.807701 -163.144156)
			(xy 155.72674 -163.043546) (xy 155.652126 -162.938143) (xy 155.584143 -162.828346) (xy 155.523048 -162.714572)
			(xy 155.469073 -162.597253) (xy 155.422422 -162.476834) (xy 155.383273 -162.353771) (xy 155.351774 -162.228532)
			(xy 155.328045 -162.101591) (xy 155.312175 -161.973431) (xy 155.304225 -161.844536) (xy 152.908 -161.844536)
			(xy 152.908 -164.77996) (xy 152.908508 -164.835769) (xy 152.916846 -164.947074) (xy 152.933479 -165.057444)
			(xy 152.958314 -165.166264) (xy 152.991211 -165.272922) (xy 153.031987 -165.376825) (xy 153.080414 -165.477389)
			(xy 153.13622 -165.574053) (xy 153.199095 -165.666277) (xy 153.268686 -165.753543) (xy 153.344603 -165.835366)
			(xy 153.426423 -165.911286) (xy 153.513688 -165.980879) (xy 153.605909 -166.043756) (xy 153.702572 -166.099566)
			(xy 153.803135 -166.147995) (xy 153.907036 -166.188775) (xy 154.013694 -166.221675) (xy 154.122512 -166.246513)
			(xy 154.232883 -166.263149) (xy 154.344187 -166.271491) (xy 154.399996 -166.271956)
		)
		(stroke
			(width 0)
			(type solid)
		)
		(fill yes)
		(layer "In3.Cu")
		(net "GND3")
	)
	(gr_poly
		(pts
			(xy 266.666472 -146.490944) (xy 323.000116 -146.490944) (xy 323.095449 -146.490445) (xy 323.285943 -146.482352)
			(xy 323.475923 -146.466182) (xy 323.665044 -146.441963) (xy 323.852968 -146.409739) (xy 324.039354 -146.369569)
			(xy 324.223868 -146.321525) (xy 324.406177 -146.265693) (xy 324.585951 -146.202173) (xy 324.762868 -146.131082)
			(xy 324.936608 -146.052545) (xy 325.106858 -145.966706) (xy 325.273312 -145.873718) (xy 325.43567 -145.77375)
			(xy 325.593638 -145.666981) (xy 325.746932 -145.553604) (xy 325.895277 -145.433823) (xy 326.038404 -145.307853)
			(xy 326.176056 -145.175923) (xy 326.307985 -145.03827) (xy 326.433952 -144.895142) (xy 326.553732 -144.746796)
			(xy 326.667107 -144.5935) (xy 326.773875 -144.435531) (xy 326.873841 -144.273173) (xy 326.966827 -144.106718)
			(xy 327.052665 -143.936467) (xy 327.1312 -143.762726) (xy 327.20229 -143.585808) (xy 327.265807 -143.406033)
			(xy 327.321637 -143.223724) (xy 327.36968 -143.03921) (xy 327.409848 -142.852823) (xy 327.44207 -142.664899)
			(xy 327.466287 -142.475777) (xy 327.482455 -142.285798) (xy 327.490546 -142.095303) (xy 327.49109 -141.99997)
			(xy 327.49109 -4.99999) (xy 327.490584 -4.904657) (xy 327.482491 -4.714162) (xy 327.466321 -4.524182)
			(xy 327.442103 -4.335059) (xy 327.40988 -4.147135) (xy 327.36971 -3.960748) (xy 327.321666 -3.776234)
			(xy 327.265834 -3.593925) (xy 327.202315 -3.414149) (xy 327.131224 -3.237232) (xy 327.052688 -3.063491)
			(xy 326.966849 -2.89324) (xy 326.873862 -2.726785) (xy 326.773894 -2.564427) (xy 326.667125 -2.406457)
			(xy 326.553748 -2.253162) (xy 326.433968 -2.104816) (xy 326.307999 -1.961688) (xy 326.176069 -1.824035)
			(xy 326.038416 -1.692105) (xy 325.895288 -1.566136) (xy 325.746943 -1.446355) (xy 325.593648 -1.332978)
			(xy 325.435678 -1.22621) (xy 325.27332 -1.126241) (xy 325.106866 -1.033254) (xy 324.936615 -0.947415)
			(xy 324.762874 -0.868878) (xy 324.585956 -0.797787) (xy 324.406181 -0.734268) (xy 324.223872 -0.678436)
			(xy 324.039358 -0.630391) (xy 323.852971 -0.590221) (xy 323.665046 -0.557998) (xy 323.475924 -0.533779)
			(xy 323.285944 -0.517609) (xy 323.095449 -0.509516) (xy 323.000116 -0.509016) (xy 4.99999 -0.509016)
			(xy 4.904657 -0.509522) (xy 4.714162 -0.517614) (xy 4.524182 -0.533784) (xy 4.335059 -0.558002) (xy 4.147135 -0.590225)
			(xy 3.960748 -0.630394) (xy 3.776233 -0.678438) (xy 3.593924 -0.73427) (xy 3.414149 -0.797788) (xy 3.237231 -0.86888)
			(xy 3.06349 -0.947415) (xy 2.893239 -1.033254) (xy 2.726784 -1.126242) (xy 2.564426 -1.22621) (xy 2.406456 -1.332978)
			(xy 2.253161 -1.446355) (xy 2.104815 -1.566136) (xy 1.961687 -1.692104) (xy 1.824034 -1.824034) (xy 1.692104 -1.961687)
			(xy 1.566136 -2.104815) (xy 1.446355 -2.253161) (xy 1.332978 -2.406456) (xy 1.22621 -2.564426) (xy 1.126242 -2.726784)
			(xy 1.033254 -2.893239) (xy 0.947415 -3.06349) (xy 0.86888 -3.237231) (xy 0.797788 -3.414149) (xy 0.73427 -3.593924)
			(xy 0.678438 -3.776233) (xy 0.630394 -3.960748) (xy 0.590225 -4.147135) (xy 0.558002 -4.335059) (xy 0.553544 -4.36987)
			(xy 242.877075 -4.36987) (xy 242.877075 -4.24073) (xy 242.885025 -4.111835) (xy 242.900895 -3.983675)
			(xy 242.924624 -3.856734) (xy 242.956123 -3.731495) (xy 242.995272 -3.608432) (xy 243.041923 -3.488013)
			(xy 243.095898 -3.370694) (xy 243.156993 -3.25692) (xy 243.224976 -3.147123) (xy 243.29959 -3.04172)
			(xy 243.380551 -2.94111) (xy 243.467551 -2.845675) (xy 243.560262 -2.755776) (xy 243.658332 -2.671755)
			(xy 243.761387 -2.593931) (xy 243.869038 -2.522599) (xy 243.980877 -2.458029) (xy 244.096478 -2.400467)
			(xy 244.215403 -2.35013) (xy 244.337202 -2.30721) (xy 244.461412 -2.271869) (xy 244.587561 -2.244242)
			(xy 244.715173 -2.224433) (xy 244.843762 -2.212517) (xy 244.97284 -2.208541) (xy 245.101918 -2.212517)
			(xy 245.230507 -2.224433) (xy 245.358119 -2.244242) (xy 245.484268 -2.271869) (xy 245.608478 -2.30721)
			(xy 245.730277 -2.35013) (xy 245.849202 -2.400467) (xy 245.964803 -2.458029) (xy 246.076642 -2.522599)
			(xy 246.184293 -2.593931) (xy 246.287348 -2.671755) (xy 246.385418 -2.755776) (xy 246.478129 -2.845675)
			(xy 246.565129 -2.94111) (xy 246.64609 -3.04172) (xy 246.720704 -3.147123) (xy 246.788687 -3.25692)
			(xy 246.849782 -3.370694) (xy 246.903757 -3.488013) (xy 246.950408 -3.608432) (xy 246.989557 -3.731495)
			(xy 247.021056 -3.856734) (xy 247.044785 -3.983675) (xy 247.060655 -4.111835) (xy 247.068605 -4.24073)
			(xy 247.069102 -4.3053) (xy 247.068605 -4.36987) (xy 247.060655 -4.498765) (xy 247.044785 -4.626925)
			(xy 247.021056 -4.753866) (xy 246.989557 -4.879105) (xy 246.950408 -5.002168) (xy 246.903757 -5.122587)
			(xy 246.849782 -5.239906) (xy 246.788687 -5.35368) (xy 246.720704 -5.463477) (xy 246.64609 -5.56888)
			(xy 246.565129 -5.66949) (xy 246.478129 -5.764925) (xy 246.385418 -5.854824) (xy 246.287348 -5.938845)
			(xy 246.184293 -6.016669) (xy 246.076642 -6.088001) (xy 245.964803 -6.152571) (xy 245.849202 -6.210133)
			(xy 245.730277 -6.26047) (xy 245.608478 -6.30339) (xy 245.484268 -6.338731) (xy 245.358119 -6.366358)
			(xy 245.230507 -6.386167) (xy 245.101918 -6.398083) (xy 244.97284 -6.40206) (xy 244.843762 -6.398083)
			(xy 244.715173 -6.386167) (xy 244.587561 -6.366358) (xy 244.461412 -6.338731) (xy 244.337202 -6.30339)
			(xy 244.215403 -6.26047) (xy 244.096478 -6.210133) (xy 243.980877 -6.152571) (xy 243.869038 -6.088001)
			(xy 243.761387 -6.016669) (xy 243.658332 -5.938845) (xy 243.560262 -5.854824) (xy 243.467551 -5.764925)
			(xy 243.380551 -5.66949) (xy 243.29959 -5.56888) (xy 243.224976 -5.463477) (xy 243.156993 -5.35368)
			(xy 243.095898 -5.239906) (xy 243.041923 -5.122587) (xy 242.995272 -5.002168) (xy 242.956123 -4.879105)
			(xy 242.924624 -4.753866) (xy 242.900895 -4.626925) (xy 242.885025 -4.498765) (xy 242.877075 -4.36987)
			(xy 0.553544 -4.36987) (xy 0.533784 -4.524182) (xy 0.517614 -4.714162) (xy 0.509522 -4.904657) (xy 0.509016 -4.99999)
			(xy 0.509016 -11.811) (xy 161.213292 -11.811) (xy 161.21368 -11.772716) (xy 161.220219 -11.696427)
			(xy 161.2333 -11.620985) (xy 161.252827 -11.546948) (xy 161.265362 -11.510772) (xy 161.268013 -11.502335)
			(xy 161.268013 -11.484665) (xy 161.265362 -11.476228) (xy 161.252837 -11.44005) (xy 161.233329 -11.36601)
			(xy 161.220249 -11.290569) (xy 161.213694 -11.214283) (xy 161.213292 -11.176) (xy 161.213787 -11.132867)
			(xy 161.222145 -11.047006) (xy 161.238773 -10.962358) (xy 161.263515 -10.879715) (xy 161.296139 -10.799856)
			(xy 161.336337 -10.723528) (xy 161.383734 -10.651448) (xy 161.437884 -10.584294) (xy 161.498278 -10.522696)
			(xy 161.564351 -10.467231) (xy 161.63548 -10.41842) (xy 161.711 -10.376723) (xy 161.7902 -10.342529)
			(xy 161.872338 -10.316161) (xy 161.956642 -10.297865) (xy 161.999422 -10.292334) (xy 162.010643 -10.290369)
			(xy 162.029893 -10.278242) (xy 162.036506 -10.268966) (xy 162.058636 -10.234762) (xy 162.108294 -10.170172)
			(xy 162.163649 -10.110392) (xy 162.224237 -10.055923) (xy 162.289549 -10.007219) (xy 162.35904 -9.964689)
			(xy 162.432128 -9.928689) (xy 162.508201 -9.899521) (xy 162.586621 -9.877428) (xy 162.666732 -9.862596)
			(xy 162.747864 -9.855149) (xy 162.7886 -9.854692) (xy 162.829702 -9.855167) (xy 162.911557 -9.862752)
			(xy 162.992362 -9.877857) (xy 163.071429 -9.900353) (xy 163.148083 -9.930049) (xy 163.22167 -9.966691)
			(xy 163.291562 -10.009966) (xy 163.357163 -10.059506) (xy 163.417913 -10.114887) (xy 163.473294 -10.175637)
			(xy 163.522834 -10.241238) (xy 163.566109 -10.31113) (xy 163.602751 -10.384717) (xy 163.632447 -10.461371)
			(xy 163.654943 -10.540438) (xy 163.670048 -10.621243) (xy 163.677633 -10.703098) (xy 163.678108 -10.7442)
			(xy 163.677552 -10.788906) (xy 163.668575 -10.877868) (xy 163.650722 -10.96548) (xy 163.624174 -11.050861)
			(xy 163.589197 -11.133148) (xy 163.546144 -11.211513) (xy 163.495449 -11.285166) (xy 163.437624 -11.353364)
			(xy 163.40582 -11.384788) (xy 163.397946 -11.392408) (xy 163.390072 -11.41222) (xy 163.393374 -11.509502)
			(xy 163.402772 -11.528806) (xy 163.411154 -11.535918) (xy 163.44386 -11.564051) (xy 163.50427 -11.625646)
			(xy 163.558433 -11.692801) (xy 163.605841 -11.764883) (xy 163.646049 -11.841217) (xy 163.678677 -11.921084)
			(xy 163.703421 -12.003735) (xy 163.720046 -12.088393) (xy 163.728399 -12.174262) (xy 163.728908 -12.2174)
			(xy 163.728433 -12.258502) (xy 163.720848 -12.340357) (xy 163.705743 -12.421162) (xy 163.683247 -12.500229)
			(xy 163.653551 -12.576883) (xy 163.616909 -12.65047) (xy 163.573634 -12.720362) (xy 163.524094 -12.785963)
			(xy 163.468713 -12.846713) (xy 163.407963 -12.902094) (xy 163.342362 -12.951634) (xy 163.27247 -12.994909)
			(xy 163.198883 -13.031551) (xy 163.122229 -13.061247) (xy 163.043162 -13.083743) (xy 162.962357 -13.098848)
			(xy 162.880502 -13.106433) (xy 162.8394 -13.106908) (xy 162.79634 -13.10644) (xy 162.710622 -13.098119)
			(xy 162.626109 -13.081554) (xy 162.543592 -13.056902) (xy 162.463843 -13.024392) (xy 162.387608 -12.984328)
			(xy 162.315601 -12.937087) (xy 162.248496 -12.883108) (xy 162.18692 -12.822899) (xy 162.131449 -12.757022)
			(xy 162.10661 -12.721844) (xy 162.099372 -12.712425) (xy 162.078566 -12.701028) (xy 162.066732 -12.7)
			(xy 162.02424 -12.697737) (xy 161.939934 -12.686166) (xy 161.857118 -12.666598) (xy 161.776548 -12.639212)
			(xy 161.698961 -12.604258) (xy 161.625066 -12.562056) (xy 161.555538 -12.512991) (xy 161.491013 -12.457512)
			(xy 161.432079 -12.396125) (xy 161.379276 -12.329392) (xy 161.333087 -12.257922) (xy 161.293932 -12.182368)
			(xy 161.26217 -12.103421) (xy 161.23809 -12.021802) (xy 161.221914 -11.938257) (xy 161.213789 -11.853548)
			(xy 161.213292 -11.811) (xy 0.509016 -11.811) (xy 0.509016 -16.070072) (xy 0.509506 -16.139948) (xy 0.517342 -16.279481)
			(xy 0.53299 -16.418355) (xy 0.556399 -16.556133) (xy 0.587497 -16.692382) (xy 0.626186 -16.826673)
			(xy 0.672343 -16.958583) (xy 0.725824 -17.087698) (xy 0.78646 -17.21361) (xy 0.854061 -17.335925)
			(xy 0.928414 -17.454257) (xy 1.009285 -17.568234) (xy 1.09642 -17.677497) (xy 1.189543 -17.781703)
			(xy 1.288363 -17.880523) (xy 1.392569 -17.973646) (xy 1.501832 -18.060781) (xy 1.615809 -18.141652)
			(xy 1.734141 -18.216005) (xy 1.856456 -18.283606) (xy 1.982368 -18.344242) (xy 2.111483 -18.397723)
			(xy 2.243393 -18.44388) (xy 2.377684 -18.482569) (xy 2.513933 -18.513667) (xy 2.651711 -18.537076)
			(xy 2.790585 -18.552724) (xy 2.930118 -18.56056) (xy 2.999994 -18.56105) (xy 9.600184 -18.56105)
			(xy 9.644215 -18.561509) (xy 9.731942 -18.569171) (xy 9.818668 -18.584451) (xy 9.903731 -18.607233)
			(xy 9.986485 -18.637344) (xy 10.066298 -18.674554) (xy 10.142564 -18.71858) (xy 10.214702 -18.769087)
			(xy 10.282162 -18.825691) (xy 10.344431 -18.88796) (xy 10.401034 -18.95542) (xy 10.451541 -19.027557)
			(xy 10.495567 -19.103823) (xy 10.532777 -19.183637) (xy 10.562888 -19.266391) (xy 10.58567 -19.351454)
			(xy 10.60095 -19.43818) (xy 10.608611 -19.525907) (xy 10.609072 -19.569938) (xy 10.609072 -20.997361)
			(xy 276.478742 -20.997361) (xy 276.478742 -20.912639) (xy 276.486795 -20.828302) (xy 276.502829 -20.745112)
			(xy 276.526697 -20.663822) (xy 276.558185 -20.58517) (xy 276.597007 -20.509867) (xy 276.64281 -20.438595)
			(xy 276.695181 -20.371999) (xy 276.753646 -20.310684) (xy 276.817674 -20.255203) (xy 276.886686 -20.20606)
			(xy 276.960056 -20.1637) (xy 277.037121 -20.128505) (xy 277.117183 -20.100796) (xy 277.199516 -20.080822)
			(xy 277.283375 -20.068765) (xy 277.368 -20.064734) (xy 277.452625 -20.068765) (xy 277.536484 -20.080822)
			(xy 277.618817 -20.100796) (xy 277.698879 -20.128505) (xy 277.775944 -20.1637) (xy 277.849314 -20.20606)
			(xy 277.918326 -20.255203) (xy 277.982354 -20.310684) (xy 278.040819 -20.371999) (xy 278.09319 -20.438595)
			(xy 278.138993 -20.509867) (xy 278.177815 -20.58517) (xy 278.209303 -20.663822) (xy 278.233171 -20.745112)
			(xy 278.249205 -20.828302) (xy 278.257258 -20.912639) (xy 278.257762 -20.955) (xy 278.257258 -20.997361)
			(xy 278.249205 -21.081698) (xy 278.233171 -21.164888) (xy 278.209303 -21.246178) (xy 278.177815 -21.32483)
			(xy 278.138993 -21.400133) (xy 278.09319 -21.471405) (xy 278.040819 -21.538001) (xy 277.982354 -21.599316)
			(xy 277.918326 -21.654797) (xy 277.849314 -21.70394) (xy 277.775944 -21.7463) (xy 277.698879 -21.781495)
			(xy 277.618817 -21.809204) (xy 277.536484 -21.829178) (xy 277.452625 -21.841235) (xy 277.368 -21.845267)
			(xy 277.283375 -21.841235) (xy 277.199516 -21.829178) (xy 277.117183 -21.809204) (xy 277.037121 -21.781495)
			(xy 276.960056 -21.7463) (xy 276.886686 -21.70394) (xy 276.817674 -21.654797) (xy 276.753646 -21.599316)
			(xy 276.695181 -21.538001) (xy 276.64281 -21.471405) (xy 276.597007 -21.400133) (xy 276.558185 -21.32483)
			(xy 276.526697 -21.246178) (xy 276.502829 -21.164888) (xy 276.486795 -21.081698) (xy 276.478742 -20.997361)
			(xy 10.609072 -20.997361) (xy 10.609072 -25.329903) (xy 12.90965 -25.329903) (xy 12.913613 -25.189472)
			(xy 12.925487 -25.049488) (xy 12.945237 -24.910397) (xy 12.972799 -24.77264) (xy 13.008084 -24.636657)
			(xy 13.050982 -24.50288) (xy 13.101355 -24.371734) (xy 13.159043 -24.243638) (xy 13.223863 -24.118999)
			(xy 13.295608 -23.998213) (xy 13.374049 -23.881665) (xy 13.458938 -23.769726) (xy 13.550004 -23.662752)
			(xy 13.646958 -23.561083) (xy 13.74949 -23.465043) (xy 13.857275 -23.374937) (xy 13.969969 -23.291053)
			(xy 14.087214 -23.213657) (xy 14.208637 -23.142996) (xy 14.333851 -23.079294) (xy 14.462458 -23.022755)
			(xy 14.594049 -22.973557) (xy 14.728204 -22.931858) (xy 14.864498 -22.89779) (xy 15.002496 -22.871462)
			(xy 15.141758 -22.852958) (xy 15.281843 -22.842336) (xy 15.422304 -22.83963) (xy 15.562693 -22.844849)
			(xy 15.702565 -22.857976) (xy 15.841475 -22.87897) (xy 15.978979 -22.907763) (xy 16.114641 -22.944264)
			(xy 16.248029 -22.988357) (xy 16.378718 -23.039902) (xy 16.506293 -23.098734) (xy 16.630347 -23.164666)
			(xy 16.750486 -23.237489) (xy 16.866328 -23.316971) (xy 16.977503 -23.402858) (xy 17.083658 -23.494878)
			(xy 17.184455 -23.592737) (xy 17.232376 -23.644098) (xy 17.241266 -23.65375) (xy 17.264888 -23.661878)
			(xy 17.3736 -23.645368) (xy 17.393666 -23.630382) (xy 17.399 -23.618698) (xy 17.438143 -23.536826)
			(xy 17.522872 -23.376323) (xy 17.614769 -23.219815) (xy 17.713645 -23.067619) (xy 17.819299 -22.920048)
			(xy 17.931515 -22.777404) (xy 18.050063 -22.639976) (xy 18.174701 -22.508047) (xy 18.305175 -22.381886)
			(xy 18.441218 -22.261751) (xy 18.582551 -22.147887) (xy 18.728885 -22.040528) (xy 18.879923 -21.939892)
			(xy 19.035355 -21.846185) (xy 19.194863 -21.759599) (xy 19.358121 -21.68031) (xy 19.524796 -21.608481)
			(xy 19.694548 -21.544259) (xy 19.867028 -21.487775) (xy 20.041885 -21.439144) (xy 20.218761 -21.398465)
			(xy 20.397295 -21.365823) (xy 20.577122 -21.341282) (xy 20.757875 -21.324895) (xy 20.939183 -21.316693)
			(xy 21.02993 -21.316188) (xy 21.120001 -21.316693) (xy 21.299962 -21.324775) (xy 21.479379 -21.340923)
			(xy 21.657891 -21.365104) (xy 21.835139 -21.39727) (xy 22.010765 -21.437355) (xy 22.184415 -21.48528)
			(xy 22.355741 -21.540947) (xy 22.524396 -21.604244) (xy 22.690042 -21.675045) (xy 22.852345 -21.753206)
			(xy 23.010977 -21.838569) (xy 23.16562 -21.930964) (xy 23.315962 -22.030204) (xy 23.461701 -22.136089)
			(xy 23.602542 -22.248406) (xy 23.738202 -22.366929) (xy 23.868408 -22.491418) (xy 23.992897 -22.621624)
			(xy 24.11142 -22.757284) (xy 24.223737 -22.898125) (xy 24.329622 -23.043864) (xy 24.428862 -23.194206)
			(xy 24.521257 -23.348849) (xy 24.60662 -23.507481) (xy 24.684781 -23.669784) (xy 24.755582 -23.83543)
			(xy 24.818879 -24.004085) (xy 24.874546 -24.175411) (xy 24.922471 -24.349061) (xy 24.962556 -24.524687)
			(xy 24.994722 -24.701935) (xy 25.018903 -24.880447) (xy 25.035051 -25.059864) (xy 25.043133 -25.239825)
			(xy 25.043133 -25.329896) (xy 25.159471 -25.329896) (xy 25.16346 -25.188998) (xy 25.175414 -25.048551)
			(xy 25.195294 -24.909006) (xy 25.223037 -24.770809) (xy 25.258555 -24.634403) (xy 25.301732 -24.500224)
			(xy 25.352432 -24.368704) (xy 25.410492 -24.240262) (xy 25.475724 -24.115311) (xy 25.547922 -23.99425)
			(xy 25.626853 -23.877468) (xy 25.712264 -23.765339) (xy 25.803883 -23.658221) (xy 25.901415 -23.556458)
			(xy 26.004547 -23.460376) (xy 26.112951 -23.370283) (xy 26.226278 -23.286466) (xy 26.344165 -23.209196)
			(xy 26.466235 -23.138719) (xy 26.592097 -23.07526) (xy 26.721347 -23.019025) (xy 26.853572 -22.970191)
			(xy 26.988348 -22.928916) (xy 27.125243 -22.895333) (xy 27.263819 -22.869548) (xy 27.403632 -22.851644)
			(xy 27.544234 -22.841679) (xy 27.685174 -22.839684) (xy 27.826002 -22.845667) (xy 27.966265 -22.859607)
			(xy 28.105515 -22.88146) (xy 28.243306 -22.911156) (xy 28.379196 -22.9486) (xy 28.51275 -22.993672)
			(xy 28.64354 -23.046228) (xy 28.73385 -23.0886) (xy 271.702788 -23.0886) (xy 271.706818 -23.003999)
			(xy 271.718871 -22.920164) (xy 271.738839 -22.837855) (xy 271.766541 -22.757816) (xy 271.801725 -22.680773)
			(xy 271.844074 -22.607423) (xy 271.893203 -22.538431) (xy 271.948668 -22.474421) (xy 272.009966 -22.415973)
			(xy 272.076542 -22.363617) (xy 272.147794 -22.317827) (xy 272.223075 -22.279016) (xy 272.301705 -22.247537)
			(xy 272.382972 -22.223676) (xy 272.466138 -22.207647) (xy 272.550452 -22.199596) (xy 272.5928 -22.199092)
			(xy 272.635108 -22.199589) (xy 272.719344 -22.207592) (xy 272.80244 -22.223553) (xy 272.883646 -22.24733)
			(xy 272.962229 -22.278706) (xy 273.037479 -22.317399) (xy 273.073368 -22.339808) (xy 273.081757 -22.344691)
			(xy 273.1008 -22.348362) (xy 273.119843 -22.344691) (xy 273.128232 -22.339808) (xy 273.164109 -22.317376)
			(xy 273.239354 -22.278665) (xy 273.317937 -22.247279) (xy 273.399147 -22.223503) (xy 273.482249 -22.20755)
			(xy 273.56649 -22.199566) (xy 273.6088 -22.199092) (xy 273.651148 -22.199596) (xy 273.735462 -22.207647)
			(xy 273.818628 -22.223676) (xy 273.899895 -22.247537) (xy 273.978525 -22.279016) (xy 274.053806 -22.317827)
			(xy 274.125058 -22.363617) (xy 274.191634 -22.415973) (xy 274.252932 -22.474421) (xy 274.308397 -22.538431)
			(xy 274.357526 -22.607423) (xy 274.399875 -22.680773) (xy 274.435059 -22.757816) (xy 274.462761 -22.837855)
			(xy 274.482729 -22.920164) (xy 274.494782 -23.003999) (xy 274.498813 -23.0886) (xy 274.494782 -23.173201)
			(xy 274.482729 -23.257036) (xy 274.462761 -23.339345) (xy 274.435059 -23.419384) (xy 274.399875 -23.496427)
			(xy 274.357526 -23.569777) (xy 274.308397 -23.638769) (xy 274.252932 -23.702779) (xy 274.191634 -23.761227)
			(xy 274.125058 -23.813583) (xy 274.053806 -23.859373) (xy 273.978525 -23.898184) (xy 273.899895 -23.929663)
			(xy 273.818628 -23.953524) (xy 273.735462 -23.969553) (xy 273.651148 -23.977604) (xy 273.6088 -23.978108)
			(xy 273.566492 -23.977611) (xy 273.482256 -23.969608) (xy 273.39916 -23.953647) (xy 273.317954 -23.92987)
			(xy 273.239371 -23.898494) (xy 273.164121 -23.859801) (xy 273.128232 -23.837392) (xy 273.119843 -23.832509)
			(xy 273.1008 -23.828838) (xy 273.081757 -23.832509) (xy 273.073368 -23.837392) (xy 273.037491 -23.859824)
			(xy 272.962246 -23.898535) (xy 272.883663 -23.929921) (xy 272.802453 -23.953697) (xy 272.719351 -23.96965)
			(xy 272.63511 -23.977634) (xy 272.5928 -23.978108) (xy 272.550452 -23.977604) (xy 272.466138 -23.969553)
			(xy 272.382972 -23.953524) (xy 272.301705 -23.929663) (xy 272.223075 -23.898184) (xy 272.147794 -23.859373)
			(xy 272.076542 -23.813583) (xy 272.009966 -23.761227) (xy 271.948668 -23.702779) (xy 271.893203 -23.638769)
			(xy 271.844074 -23.569777) (xy 271.801725 -23.496427) (xy 271.766541 -23.419384) (xy 271.738839 -23.339345)
			(xy 271.718871 -23.257036) (xy 271.706818 -23.173201) (xy 271.702788 -23.0886) (xy 28.73385 -23.0886)
			(xy 28.771147 -23.106099) (xy 28.895163 -23.173094) (xy 29.015189 -23.246997) (xy 29.130843 -23.327573)
			(xy 29.241752 -23.414562) (xy 29.347563 -23.507687) (xy 29.447935 -23.606649) (xy 29.542548 -23.711131)
			(xy 29.631099 -23.820799) (xy 29.713303 -23.935301) (xy 29.788897 -24.05427) (xy 29.85764 -24.177325)
			(xy 29.919311 -24.304072) (xy 29.973712 -24.434105) (xy 30.02067 -24.567008) (xy 30.060033 -24.702354)
			(xy 30.091676 -24.839711) (xy 30.115498 -24.978638) (xy 30.131421 -25.11869) (xy 30.139396 -25.259419)
			(xy 30.139894 -25.329896) (xy 30.139396 -25.400373) (xy 30.131421 -25.541102) (xy 30.125683 -25.59157)
			(xy 42.354235 -25.59157) (xy 42.354235 -25.46243) (xy 42.362185 -25.333535) (xy 42.378055 -25.205375)
			(xy 42.401784 -25.078434) (xy 42.433283 -24.953195) (xy 42.472432 -24.830132) (xy 42.519083 -24.709713)
			(xy 42.573058 -24.592394) (xy 42.634153 -24.47862) (xy 42.702136 -24.368823) (xy 42.77675 -24.26342)
			(xy 42.857711 -24.16281) (xy 42.944711 -24.067375) (xy 43.037422 -23.977476) (xy 43.135492 -23.893455)
			(xy 43.238547 -23.815631) (xy 43.346198 -23.744299) (xy 43.458037 -23.679729) (xy 43.573638 -23.622167)
			(xy 43.692563 -23.57183) (xy 43.814362 -23.52891) (xy 43.938572 -23.493569) (xy 44.064721 -23.465942)
			(xy 44.192333 -23.446133) (xy 44.320922 -23.434217) (xy 44.45 -23.430241) (xy 44.579078 -23.434217)
			(xy 44.707667 -23.446133) (xy 44.835279 -23.465942) (xy 44.961428 -23.493569) (xy 45.085638 -23.52891)
			(xy 45.207437 -23.57183) (xy 45.326362 -23.622167) (xy 45.441963 -23.679729) (xy 45.553802 -23.744299)
			(xy 45.661453 -23.815631) (xy 45.764508 -23.893455) (xy 45.862578 -23.977476) (xy 45.955289 -24.067375)
			(xy 46.042289 -24.16281) (xy 46.12325 -24.26342) (xy 46.197864 -24.368823) (xy 46.265847 -24.47862)
			(xy 46.326942 -24.592394) (xy 46.380917 -24.709713) (xy 46.427568 -24.830132) (xy 46.466717 -24.953195)
			(xy 46.498216 -25.078434) (xy 46.521945 -25.205375) (xy 46.537815 -25.333535) (xy 46.545765 -25.46243)
			(xy 46.546262 -25.527) (xy 46.545765 -25.59157) (xy 46.537815 -25.720465) (xy 46.521945 -25.848625)
			(xy 46.498216 -25.975566) (xy 46.466717 -26.100805) (xy 46.427568 -26.223868) (xy 46.380917 -26.344287)
			(xy 46.326942 -26.461606) (xy 46.265847 -26.57538) (xy 46.197864 -26.685177) (xy 46.12325 -26.79058)
			(xy 46.042289 -26.89119) (xy 45.955289 -26.986625) (xy 45.862578 -27.076524) (xy 45.764508 -27.160545)
			(xy 45.661453 -27.238369) (xy 45.553802 -27.309701) (xy 45.441963 -27.374271) (xy 45.326362 -27.431833)
			(xy 45.207437 -27.48217) (xy 45.085638 -27.52509) (xy 44.961428 -27.560431) (xy 44.835279 -27.588058)
			(xy 44.707667 -27.607867) (xy 44.579078 -27.619783) (xy 44.45 -27.62376) (xy 44.320922 -27.619783)
			(xy 44.192333 -27.607867) (xy 44.064721 -27.588058) (xy 43.938572 -27.560431) (xy 43.814362 -27.52509)
			(xy 43.692563 -27.48217) (xy 43.573638 -27.431833) (xy 43.458037 -27.374271) (xy 43.346198 -27.309701)
			(xy 43.238547 -27.238369) (xy 43.135492 -27.160545) (xy 43.037422 -27.076524) (xy 42.944711 -26.986625)
			(xy 42.857711 -26.89119) (xy 42.77675 -26.79058) (xy 42.702136 -26.685177) (xy 42.634153 -26.57538)
			(xy 42.573058 -26.461606) (xy 42.519083 -26.344287) (xy 42.472432 -26.223868) (xy 42.433283 -26.100805)
			(xy 42.401784 -25.975566) (xy 42.378055 -25.848625) (xy 42.362185 -25.720465) (xy 42.354235 -25.59157)
			(xy 30.125683 -25.59157) (xy 30.115498 -25.681154) (xy 30.091676 -25.820081) (xy 30.060033 -25.957438)
			(xy 30.02067 -26.092784) (xy 29.973712 -26.225687) (xy 29.919311 -26.35572) (xy 29.85764 -26.482467)
			(xy 29.788897 -26.605522) (xy 29.713303 -26.724491) (xy 29.631099 -26.838993) (xy 29.542548 -26.948661)
			(xy 29.447935 -27.053143) (xy 29.347563 -27.152105) (xy 29.241752 -27.24523) (xy 29.130843 -27.332219)
			(xy 29.015189 -27.412795) (xy 28.895163 -27.486698) (xy 28.771147 -27.553693) (xy 28.64354 -27.613564)
			(xy 28.51275 -27.66612) (xy 28.379196 -27.711192) (xy 28.243306 -27.748636) (xy 28.105515 -27.778332)
			(xy 27.966265 -27.800185) (xy 27.826002 -27.814125) (xy 27.685174 -27.820108) (xy 27.544234 -27.818113)
			(xy 27.403632 -27.808148) (xy 27.263819 -27.790244) (xy 27.125243 -27.764459) (xy 26.988348 -27.730876)
			(xy 26.853572 -27.689601) (xy 26.721347 -27.640767) (xy 26.592097 -27.584532) (xy 26.466235 -27.521073)
			(xy 26.344165 -27.450596) (xy 26.226278 -27.373326) (xy 26.112951 -27.289509) (xy 26.004547 -27.199416)
			(xy 25.901415 -27.103334) (xy 25.803883 -27.001571) (xy 25.712264 -26.894453) (xy 25.626853 -26.782324)
			(xy 25.547922 -26.665542) (xy 25.475724 -26.544481) (xy 25.410492 -26.41953) (xy 25.352432 -26.291088)
			(xy 25.301732 -26.159568) (xy 25.258555 -26.025389) (xy 25.223037 -25.888983) (xy 25.195294 -25.750786)
			(xy 25.175414 -25.611241) (xy 25.16346 -25.470794) (xy 25.159471 -25.329896) (xy 25.043133 -25.329896)
			(xy 25.043133 -25.419967) (xy 25.035051 -25.599928) (xy 25.018903 -25.779345) (xy 24.994722 -25.957857)
			(xy 24.962556 -26.135105) (xy 24.922471 -26.310731) (xy 24.874546 -26.484381) (xy 24.818879 -26.655707)
			(xy 24.755582 -26.824362) (xy 24.684781 -26.990008) (xy 24.60662 -27.152311) (xy 24.521257 -27.310943)
			(xy 24.428862 -27.465586) (xy 24.329622 -27.615928) (xy 24.223737 -27.761667) (xy 24.11142 -27.902508)
			(xy 23.992897 -28.038168) (xy 23.868408 -28.168374) (xy 23.738202 -28.292863) (xy 23.602542 -28.411386)
			(xy 23.461701 -28.523703) (xy 23.315962 -28.629588) (xy 23.16562 -28.728828) (xy 23.010977 -28.821223)
			(xy 22.852345 -28.906586) (xy 22.690042 -28.984747) (xy 22.524396 -29.055548) (xy 22.355741 -29.118845)
			(xy 22.184415 -29.174512) (xy 22.010765 -29.222437) (xy 21.835139 -29.262522) (xy 21.657891 -29.294688)
			(xy 21.479379 -29.318869) (xy 21.299962 -29.335017) (xy 21.120001 -29.343099) (xy 21.02993 -29.343604)
			(xy 20.939184 -29.343097) (xy 20.757877 -29.334889) (xy 20.577127 -29.318497) (xy 20.397302 -29.293952)
			(xy 20.21877 -29.261305) (xy 20.041895 -29.220623) (xy 19.867041 -29.171989) (xy 19.694562 -29.115502)
			(xy 19.524813 -29.051278) (xy 19.35814 -28.979448) (xy 19.194884 -28.900158) (xy 19.035377 -28.813572)
			(xy 18.879947 -28.719865) (xy 18.728911 -28.61923) (xy 18.582577 -28.511871) (xy 18.441244 -28.398009)
			(xy 18.305202 -28.277876) (xy 18.174728 -28.151717) (xy 18.050089 -28.01979) (xy 17.93154 -27.882366)
			(xy 17.819322 -27.739724) (xy 17.713666 -27.592156) (xy 17.614787 -27.439964) (xy 17.522887 -27.283459)
			(xy 17.438154 -27.12296) (xy 17.399 -27.041094) (xy 17.393666 -27.02941) (xy 17.3736 -27.014424)
			(xy 17.264888 -26.997914) (xy 17.241266 -27.006042) (xy 17.232376 -27.015694) (xy 17.184459 -27.067059)
			(xy 17.083662 -27.164918) (xy 16.977507 -27.256938) (xy 16.866332 -27.342826) (xy 16.750491 -27.422308)
			(xy 16.630352 -27.495131) (xy 16.506298 -27.561063) (xy 16.378724 -27.619896) (xy 16.248035 -27.671441)
			(xy 16.114647 -27.715534) (xy 15.978985 -27.752036) (xy 15.841481 -27.780829) (xy 15.702571 -27.801823)
			(xy 15.562699 -27.814951) (xy 15.42231 -27.82017) (xy 15.281849 -27.817465) (xy 15.141764 -27.806843)
			(xy 15.002501 -27.788339) (xy 14.864504 -27.762011) (xy 14.72821 -27.727944) (xy 14.594054 -27.686245)
			(xy 14.462464 -27.637048) (xy 14.333856 -27.580508) (xy 14.208642 -27.516807) (xy 14.087219 -27.446146)
			(xy 13.969974 -27.36875) (xy 13.857279 -27.284866) (xy 13.749494 -27.194761) (xy 13.646962 -27.098721)
			(xy 13.550008 -26.997053) (xy 13.458942 -26.890079) (xy 13.374053 -26.77814) (xy 13.295611 -26.661592)
			(xy 13.223866 -26.540806) (xy 13.159046 -26.416167) (xy 13.101357 -26.288071) (xy 13.050984 -26.156926)
			(xy 13.008086 -26.023149) (xy 12.9728 -25.887166) (xy 12.945238 -25.749409) (xy 12.925488 -25.610318)
			(xy 12.913613 -25.470334) (xy 12.90965 -25.329903) (xy 10.609072 -25.329903) (xy 10.609072 -31.070042)
			(xy 10.608582 -31.114068) (xy 10.600889 -31.201783) (xy 10.585583 -31.288494) (xy 10.562781 -31.373542)
			(xy 10.532655 -31.456279) (xy 10.495435 -31.536078) (xy 10.451404 -31.61233) (xy 10.400897 -31.684456)
			(xy 10.344298 -31.751907) (xy 10.282038 -31.81417) (xy 10.214589 -31.870772) (xy 10.142465 -31.921282)
			(xy 10.066215 -31.965316) (xy 9.986418 -32.002539) (xy 9.903682 -32.032668) (xy 9.818635 -32.055474)
			(xy 9.731924 -32.070783) (xy 9.64421 -32.07848) (xy 9.600184 -32.07893) (xy 2.999994 -32.07893) (xy 2.930118 -32.07942)
			(xy 2.790585 -32.087256) (xy 2.651711 -32.102904) (xy 2.513933 -32.126313) (xy 2.377684 -32.157411)
			(xy 2.243393 -32.1961) (xy 2.111483 -32.242257) (xy 1.982368 -32.295738) (xy 1.856456 -32.356374)
			(xy 1.734141 -32.423975) (xy 1.615809 -32.498328) (xy 1.501832 -32.579199) (xy 1.392569 -32.666334)
			(xy 1.288363 -32.759457) (xy 1.189543 -32.858277) (xy 1.09642 -32.962483) (xy 1.04643 -33.025168)
			(xy 59.677545 -33.025168) (xy 59.677545 -32.854812) (xy 59.68553 -32.684644) (xy 59.701482 -32.515037)
			(xy 59.725367 -32.346365) (xy 59.757131 -32.178997) (xy 59.796706 -32.013302) (xy 59.844003 -31.849644)
			(xy 59.89892 -31.688383) (xy 59.961335 -31.529873) (xy 60.031111 -31.374463) (xy 60.108094 -31.222495)
			(xy 60.192116 -31.074301) (xy 60.282992 -30.930209) (xy 60.380522 -30.790535) (xy 60.484492 -30.655586)
			(xy 60.594673 -30.525658) (xy 60.710822 -30.401038) (xy 60.832686 -30.281999) (xy 60.959994 -30.168803)
			(xy 61.092469 -30.061698) (xy 61.229819 -29.960921) (xy 61.371741 -29.866692) (xy 61.517923 -29.779219)
			(xy 61.668046 -29.698694) (xy 61.821777 -29.625294) (xy 61.97878 -29.55918) (xy 62.13871 -29.500498)
			(xy 62.301214 -29.449377) (xy 62.465935 -29.405929) (xy 62.632513 -29.37025) (xy 62.800579 -29.342418)
			(xy 62.969765 -29.322494) (xy 63.139699 -29.310522) (xy 63.310008 -29.306529) (xy 63.480317 -29.310522)
			(xy 63.650251 -29.322494) (xy 63.819437 -29.342418) (xy 63.987503 -29.37025) (xy 64.154081 -29.405929)
			(xy 64.318802 -29.449377) (xy 64.481306 -29.500498) (xy 64.641236 -29.55918) (xy 64.798239 -29.625294)
			(xy 64.95197 -29.698694) (xy 65.102093 -29.779219) (xy 65.248275 -29.866692) (xy 65.390197 -29.960921)
			(xy 65.527547 -30.061698) (xy 65.660022 -30.168803) (xy 65.78733 -30.281999) (xy 65.909194 -30.401038)
			(xy 66.025343 -30.525658) (xy 66.135524 -30.655586) (xy 66.239494 -30.790535) (xy 66.337024 -30.930209)
			(xy 66.4279 -31.074301) (xy 66.511922 -31.222495) (xy 66.588905 -31.374463) (xy 66.658681 -31.529873)
			(xy 66.721096 -31.688383) (xy 66.776013 -31.849644) (xy 66.82331 -32.013302) (xy 66.862885 -32.178997)
			(xy 66.894649 -32.346365) (xy 66.918534 -32.515037) (xy 66.934486 -32.684644) (xy 66.942471 -32.854812)
			(xy 66.94297 -32.93999) (xy 66.942471 -33.025168) (xy 66.934486 -33.195336) (xy 66.918534 -33.364943)
			(xy 66.894649 -33.533615) (xy 66.862885 -33.700983) (xy 66.82331 -33.866678) (xy 66.776013 -34.030336)
			(xy 66.721096 -34.191597) (xy 66.658681 -34.350107) (xy 66.588905 -34.505517) (xy 66.511922 -34.657485)
			(xy 66.4279 -34.805679) (xy 66.337024 -34.949771) (xy 66.239494 -35.089445) (xy 66.135524 -35.224394)
			(xy 66.025343 -35.354322) (xy 65.909194 -35.478942) (xy 65.78733 -35.597981) (xy 65.660022 -35.711177)
			(xy 65.527547 -35.818282) (xy 65.390197 -35.919059) (xy 65.248275 -36.013288) (xy 65.102093 -36.100761)
			(xy 64.95197 -36.181286) (xy 64.798239 -36.254686) (xy 64.641236 -36.3208) (xy 64.481306 -36.379482)
			(xy 64.318802 -36.430603) (xy 64.154081 -36.474051) (xy 63.987503 -36.50973) (xy 63.819437 -36.537562)
			(xy 63.650251 -36.557486) (xy 63.480317 -36.569458) (xy 63.310008 -36.573452) (xy 63.139699 -36.569458)
			(xy 62.969765 -36.557486) (xy 62.800579 -36.537562) (xy 62.632513 -36.50973) (xy 62.465935 -36.474051)
			(xy 62.301214 -36.430603) (xy 62.13871 -36.379482) (xy 61.97878 -36.3208) (xy 61.821777 -36.254686)
			(xy 61.668046 -36.181286) (xy 61.517923 -36.100761) (xy 61.371741 -36.013288) (xy 61.229819 -35.919059)
			(xy 61.092469 -35.818282) (xy 60.959994 -35.711177) (xy 60.832686 -35.597981) (xy 60.710822 -35.478942)
			(xy 60.594673 -35.354322) (xy 60.484492 -35.224394) (xy 60.380522 -35.089445) (xy 60.282992 -34.949771)
			(xy 60.192116 -34.805679) (xy 60.108094 -34.657485) (xy 60.031111 -34.505517) (xy 59.961335 -34.350107)
			(xy 59.89892 -34.191597) (xy 59.844003 -34.030336) (xy 59.796706 -33.866678) (xy 59.757131 -33.700983)
			(xy 59.725367 -33.533615) (xy 59.701482 -33.364943) (xy 59.68553 -33.195336) (xy 59.677545 -33.025168)
			(xy 1.04643 -33.025168) (xy 1.009285 -33.071746) (xy 0.928414 -33.185723) (xy 0.854061 -33.304055)
			(xy 0.78646 -33.42637) (xy 0.725824 -33.552282) (xy 0.672343 -33.681397) (xy 0.626186 -33.813307)
			(xy 0.587497 -33.947598) (xy 0.556399 -34.083847) (xy 0.53299 -34.221625) (xy 0.517342 -34.360499)
			(xy 0.509506 -34.500032) (xy 0.509016 -34.569908) (xy 0.509016 -38.019995) (xy 100.644968 -38.019995)
			(xy 100.648872 -37.915504) (xy 100.660563 -37.811596) (xy 100.679974 -37.708849) (xy 100.706998 -37.607838)
			(xy 100.741484 -37.509125) (xy 100.783239 -37.41326) (xy 100.832032 -37.320778) (xy 100.887589 -37.232195)
			(xy 100.949602 -37.148005) (xy 101.017724 -37.068676) (xy 101.091575 -36.994652) (xy 101.170744 -36.926345)
			(xy 101.254789 -36.864136) (xy 101.298756 -36.835842) (xy 101.309932 -36.82873) (xy 101.322378 -36.806378)
			(xy 101.322378 -36.693602) (xy 101.309932 -36.67125) (xy 101.298756 -36.664138) (xy 101.25478 -36.635858)
			(xy 101.170735 -36.573648) (xy 101.091567 -36.505341) (xy 101.017716 -36.431316) (xy 100.949595 -36.351987)
			(xy 100.887583 -36.267796) (xy 100.832027 -36.179212) (xy 100.783235 -36.08673) (xy 100.74148 -35.990865)
			(xy 100.706995 -35.892152) (xy 100.679971 -35.79114) (xy 100.660561 -35.688394) (xy 100.648871 -35.584486)
			(xy 100.644968 -35.479995) (xy 100.648872 -35.375504) (xy 100.660563 -35.271596) (xy 100.679974 -35.168849)
			(xy 100.706998 -35.067838) (xy 100.741484 -34.969125) (xy 100.783239 -34.87326) (xy 100.832032 -34.780778)
			(xy 100.887589 -34.692195) (xy 100.949602 -34.608005) (xy 101.017724 -34.528676) (xy 101.091575 -34.454652)
			(xy 101.170744 -34.386345) (xy 101.254789 -34.324136) (xy 101.298756 -34.295842) (xy 101.309932 -34.28873)
			(xy 101.322378 -34.266378) (xy 101.322378 -34.153602) (xy 101.309932 -34.13125) (xy 101.298756 -34.124138)
			(xy 101.253105 -34.094744) (xy 101.166014 -34.02989) (xy 101.084209 -33.958484) (xy 101.008183 -33.880954)
			(xy 100.938393 -33.797766) (xy 100.875258 -33.70942) (xy 100.819159 -33.616449) (xy 100.770431 -33.51941)
			(xy 100.72937 -33.418887) (xy 100.69622 -33.315485) (xy 100.671182 -33.209825) (xy 100.654406 -33.102543)
			(xy 100.645993 -32.994283) (xy 100.645468 -32.93999) (xy 100.645985 -32.887639) (xy 100.653809 -32.783228)
			(xy 100.669413 -32.679695) (xy 100.692709 -32.577616) (xy 100.723568 -32.477564) (xy 100.761816 -32.380097)
			(xy 100.807239 -32.28576) (xy 100.859585 -32.195082) (xy 100.91856 -32.108567) (xy 100.983834 -32.026702)
			(xy 101.055043 -31.949942) (xy 101.131788 -31.878718) (xy 101.213641 -31.813427) (xy 101.300143 -31.754435)
			(xy 101.390811 -31.702071) (xy 101.485138 -31.656629) (xy 101.582598 -31.618361) (xy 101.682644 -31.587482)
			(xy 101.784717 -31.564166) (xy 101.888248 -31.548541) (xy 101.992657 -31.540696) (xy 102.045008 -31.540196)
			(xy 102.099308 -31.540684) (xy 102.207582 -31.549102) (xy 102.314878 -31.565887) (xy 102.42055 -31.590938)
			(xy 102.523962 -31.624104) (xy 102.624493 -31.665187) (xy 102.721537 -31.713937) (xy 102.81451 -31.770063)
			(xy 102.902853 -31.833226) (xy 102.986035 -31.903047) (xy 103.063555 -31.979105) (xy 103.134946 -32.060943)
			(xy 103.199779 -32.148068) (xy 103.229156 -32.193738) (xy 103.236268 -32.204914) (xy 103.25862 -32.21736)
			(xy 103.371396 -32.21736) (xy 103.393748 -32.204914) (xy 103.40086 -32.193738) (xy 103.430248 -32.148075)
			(xy 103.49508 -32.060952) (xy 103.566471 -31.979116) (xy 103.643991 -31.903059) (xy 103.727172 -31.83324)
			(xy 103.815514 -31.770078) (xy 103.908487 -31.713954) (xy 104.00553 -31.665205) (xy 104.106059 -31.624125)
			(xy 104.20947 -31.59096) (xy 104.315141 -31.56591) (xy 104.422436 -31.549126) (xy 104.530708 -31.540709)
			(xy 104.585008 -31.540196) (xy 104.637364 -31.54063) (xy 104.741784 -31.548457) (xy 104.845326 -31.564066)
			(xy 104.947413 -31.58737) (xy 105.047472 -31.618239) (xy 105.144944 -31.6565) (xy 105.239283 -31.701939)
			(xy 105.329963 -31.754302) (xy 105.416476 -31.813296) (xy 105.498337 -31.878591) (xy 105.57509 -31.949821)
			(xy 105.646304 -32.026588) (xy 105.711581 -32.108464) (xy 105.770557 -32.194989) (xy 105.8229 -32.28568)
			(xy 105.868319 -32.38003) (xy 105.906559 -32.47751) (xy 105.937407 -32.577575) (xy 105.960689 -32.679667)
			(xy 105.976277 -32.783212) (xy 105.984081 -32.887634) (xy 105.984548 -32.93999) (xy 105.984054 -32.994284)
			(xy 105.975641 -33.102545) (xy 105.958864 -33.209828) (xy 105.933825 -33.315489) (xy 105.900673 -33.418892)
			(xy 105.859609 -33.519415) (xy 105.810879 -33.616455) (xy 105.754776 -33.709426) (xy 105.691638 -33.797771)
			(xy 105.621844 -33.880957) (xy 105.545813 -33.958486) (xy 105.464005 -34.029889) (xy 105.376909 -34.094739)
			(xy 105.33126 -34.124138) (xy 105.320084 -34.13125) (xy 105.307638 -34.153602) (xy 105.307638 -34.266378)
			(xy 105.320084 -34.28873) (xy 105.33126 -34.295842) (xy 105.37522 -34.324148) (xy 105.459268 -34.386354)
			(xy 105.538441 -34.454658) (xy 105.612295 -34.52868) (xy 105.68042 -34.608006) (xy 105.742436 -34.692195)
			(xy 105.797996 -34.780777) (xy 105.846791 -34.873258) (xy 105.888549 -34.969123) (xy 105.923037 -35.067836)
			(xy 105.950062 -35.168848) (xy 105.969475 -35.271594) (xy 105.981166 -35.375503) (xy 105.98507 -35.479995)
			(xy 105.981167 -35.584486) (xy 105.969476 -35.688395) (xy 105.950065 -35.791142) (xy 105.92304 -35.892154)
			(xy 105.888553 -35.990867) (xy 105.846796 -36.086732) (xy 105.798001 -36.179214) (xy 105.742442 -36.267796)
			(xy 105.680427 -36.351986) (xy 105.612303 -36.431313) (xy 105.538449 -36.505335) (xy 105.459277 -36.57364)
			(xy 105.375229 -36.635846) (xy 105.33126 -36.664138) (xy 105.320084 -36.67125) (xy 105.307638 -36.693602)
			(xy 105.307638 -36.806378) (xy 105.320084 -36.82873) (xy 105.33126 -36.835842) (xy 105.37522 -36.864148)
			(xy 105.459268 -36.926354) (xy 105.538441 -36.994658) (xy 105.612295 -37.06868) (xy 105.68042 -37.148006)
			(xy 105.742436 -37.232195) (xy 105.797996 -37.320777) (xy 105.846791 -37.413258) (xy 105.888549 -37.509123)
			(xy 105.923037 -37.607836) (xy 105.950062 -37.708848) (xy 105.969475 -37.811594) (xy 105.981166 -37.915503)
			(xy 105.98507 -38.019995) (xy 109.534968 -38.019995) (xy 109.538872 -37.915504) (xy 109.550563 -37.811596)
			(xy 109.569974 -37.708849) (xy 109.596998 -37.607838) (xy 109.631484 -37.509125) (xy 109.673239 -37.41326)
			(xy 109.722032 -37.320778) (xy 109.777589 -37.232195) (xy 109.839602 -37.148005) (xy 109.907724 -37.068676)
			(xy 109.981575 -36.994652) (xy 110.060744 -36.926345) (xy 110.144789 -36.864136) (xy 110.188756 -36.835842)
			(xy 110.199932 -36.82873) (xy 110.212378 -36.806378) (xy 110.212378 -36.693602) (xy 110.199932 -36.67125)
			(xy 110.188756 -36.664138) (xy 110.14478 -36.635858) (xy 110.060735 -36.573648) (xy 109.981567 -36.505341)
			(xy 109.907716 -36.431316) (xy 109.839595 -36.351987) (xy 109.777583 -36.267796) (xy 109.722027 -36.179212)
			(xy 109.673235 -36.08673) (xy 109.63148 -35.990865) (xy 109.596995 -35.892152) (xy 109.569971 -35.79114)
			(xy 109.550561 -35.688394) (xy 109.538871 -35.584486) (xy 109.534968 -35.479995) (xy 109.538872 -35.375504)
			(xy 109.550563 -35.271596) (xy 109.569974 -35.168849) (xy 109.596998 -35.067838) (xy 109.631484 -34.969125)
			(xy 109.673239 -34.87326) (xy 109.722032 -34.780778) (xy 109.777589 -34.692195) (xy 109.839602 -34.608005)
			(xy 109.907724 -34.528676) (xy 109.981575 -34.454652) (xy 110.060744 -34.386345) (xy 110.144789 -34.324136)
			(xy 110.188756 -34.295842) (xy 110.199932 -34.28873) (xy 110.212378 -34.266378) (xy 110.212378 -34.153602)
			(xy 110.199932 -34.13125) (xy 110.188756 -34.124138) (xy 110.143105 -34.094744) (xy 110.056014 -34.02989)
			(xy 109.974209 -33.958484) (xy 109.898183 -33.880954) (xy 109.828393 -33.797766) (xy 109.765258 -33.70942)
			(xy 109.709159 -33.616449) (xy 109.660431 -33.51941) (xy 109.61937 -33.418887) (xy 109.58622 -33.315485)
			(xy 109.561182 -33.209825) (xy 109.544406 -33.102543) (xy 109.535993 -32.994283) (xy 109.535468 -32.93999)
			(xy 109.535985 -32.887639) (xy 109.543809 -32.783228) (xy 109.559413 -32.679695) (xy 109.582709 -32.577616)
			(xy 109.613568 -32.477564) (xy 109.651816 -32.380097) (xy 109.697239 -32.28576) (xy 109.749585 -32.195082)
			(xy 109.80856 -32.108567) (xy 109.873834 -32.026702) (xy 109.945043 -31.949942) (xy 110.021788 -31.878718)
			(xy 110.103641 -31.813427) (xy 110.190143 -31.754435) (xy 110.280811 -31.702071) (xy 110.375138 -31.656629)
			(xy 110.472598 -31.618361) (xy 110.572644 -31.587482) (xy 110.674717 -31.564166) (xy 110.778248 -31.548541)
			(xy 110.882657 -31.540696) (xy 110.935008 -31.540196) (xy 110.989308 -31.540684) (xy 111.097582 -31.549102)
			(xy 111.204878 -31.565887) (xy 111.31055 -31.590938) (xy 111.413962 -31.624104) (xy 111.514493 -31.665187)
			(xy 111.611537 -31.713937) (xy 111.70451 -31.770063) (xy 111.792853 -31.833226) (xy 111.876035 -31.903047)
			(xy 111.953555 -31.979105) (xy 112.024946 -32.060943) (xy 112.089779 -32.148068) (xy 112.119156 -32.193738)
			(xy 112.126268 -32.204914) (xy 112.14862 -32.21736) (xy 112.261396 -32.21736) (xy 112.283748 -32.204914)
			(xy 112.29086 -32.193738) (xy 112.320248 -32.148075) (xy 112.38508 -32.060952) (xy 112.456471 -31.979116)
			(xy 112.533991 -31.903059) (xy 112.617172 -31.83324) (xy 112.705514 -31.770078) (xy 112.798487 -31.713954)
			(xy 112.89553 -31.665205) (xy 112.996059 -31.624125) (xy 113.09947 -31.59096) (xy 113.205141 -31.56591)
			(xy 113.312436 -31.549126) (xy 113.420708 -31.540709) (xy 113.475008 -31.540196) (xy 113.527364 -31.54063)
			(xy 113.631784 -31.548457) (xy 113.735326 -31.564066) (xy 113.837413 -31.58737) (xy 113.937472 -31.618239)
			(xy 114.034944 -31.6565) (xy 114.129283 -31.701939) (xy 114.219963 -31.754302) (xy 114.306476 -31.813296)
			(xy 114.388337 -31.878591) (xy 114.46509 -31.949821) (xy 114.536304 -32.026588) (xy 114.601581 -32.108464)
			(xy 114.660557 -32.194989) (xy 114.7129 -32.28568) (xy 114.758319 -32.38003) (xy 114.796559 -32.47751)
			(xy 114.827407 -32.577575) (xy 114.850689 -32.679667) (xy 114.866277 -32.783212) (xy 114.874081 -32.887634)
			(xy 114.874548 -32.93999) (xy 114.874054 -32.994284) (xy 114.865641 -33.102545) (xy 114.848864 -33.209828)
			(xy 114.823825 -33.315489) (xy 114.790673 -33.418892) (xy 114.749609 -33.519415) (xy 114.700879 -33.616455)
			(xy 114.644776 -33.709426) (xy 114.581638 -33.797771) (xy 114.511844 -33.880957) (xy 114.435813 -33.958486)
			(xy 114.354005 -34.029889) (xy 114.266909 -34.094739) (xy 114.22126 -34.124138) (xy 114.210084 -34.13125)
			(xy 114.197638 -34.153602) (xy 114.197638 -34.266378) (xy 114.210084 -34.28873) (xy 114.22126 -34.295842)
			(xy 114.26522 -34.324148) (xy 114.349268 -34.386354) (xy 114.428441 -34.454658) (xy 114.502295 -34.52868)
			(xy 114.57042 -34.608006) (xy 114.632436 -34.692195) (xy 114.687996 -34.780777) (xy 114.736791 -34.873258)
			(xy 114.778549 -34.969123) (xy 114.813037 -35.067836) (xy 114.840062 -35.168848) (xy 114.859475 -35.271594)
			(xy 114.871166 -35.375503) (xy 114.87507 -35.479995) (xy 114.871167 -35.584486) (xy 114.859476 -35.688395)
			(xy 114.840065 -35.791142) (xy 114.81304 -35.892154) (xy 114.778553 -35.990867) (xy 114.736796 -36.086732)
			(xy 114.688001 -36.179214) (xy 114.632442 -36.267796) (xy 114.570427 -36.351986) (xy 114.502303 -36.431313)
			(xy 114.428449 -36.505335) (xy 114.349277 -36.57364) (xy 114.265229 -36.635846) (xy 114.22126 -36.664138)
			(xy 114.210084 -36.67125) (xy 114.197638 -36.693602) (xy 114.197638 -36.806378) (xy 114.210084 -36.82873)
			(xy 114.22126 -36.835842) (xy 114.26522 -36.864148) (xy 114.349268 -36.926354) (xy 114.428441 -36.994658)
			(xy 114.502295 -37.06868) (xy 114.57042 -37.148006) (xy 114.632436 -37.232195) (xy 114.687996 -37.320777)
			(xy 114.736791 -37.413258) (xy 114.778549 -37.509123) (xy 114.813037 -37.607836) (xy 114.840062 -37.708848)
			(xy 114.859475 -37.811594) (xy 114.871166 -37.915503) (xy 114.87507 -38.019995) (xy 118.424968 -38.019995)
			(xy 118.428872 -37.915504) (xy 118.440563 -37.811596) (xy 118.459974 -37.708849) (xy 118.486998 -37.607838)
			(xy 118.521484 -37.509125) (xy 118.563239 -37.41326) (xy 118.612032 -37.320778) (xy 118.667589 -37.232195)
			(xy 118.729602 -37.148005) (xy 118.797724 -37.068676) (xy 118.871575 -36.994652) (xy 118.950744 -36.926345)
			(xy 119.034789 -36.864136) (xy 119.078756 -36.835842) (xy 119.089932 -36.82873) (xy 119.102378 -36.806378)
			(xy 119.102378 -36.693602) (xy 119.089932 -36.67125) (xy 119.078756 -36.664138) (xy 119.03478 -36.635858)
			(xy 118.950735 -36.573648) (xy 118.871567 -36.505341) (xy 118.797716 -36.431316) (xy 118.729595 -36.351987)
			(xy 118.667583 -36.267796) (xy 118.612027 -36.179212) (xy 118.563235 -36.08673) (xy 118.52148 -35.990865)
			(xy 118.486995 -35.892152) (xy 118.459971 -35.79114) (xy 118.440561 -35.688394) (xy 118.428871 -35.584486)
			(xy 118.424968 -35.479995) (xy 118.428872 -35.375504) (xy 118.440563 -35.271596) (xy 118.459974 -35.168849)
			(xy 118.486998 -35.067838) (xy 118.521484 -34.969125) (xy 118.563239 -34.87326) (xy 118.612032 -34.780778)
			(xy 118.667589 -34.692195) (xy 118.729602 -34.608005) (xy 118.797724 -34.528676) (xy 118.871575 -34.454652)
			(xy 118.950744 -34.386345) (xy 119.034789 -34.324136) (xy 119.078756 -34.295842) (xy 119.089932 -34.28873)
			(xy 119.102378 -34.266378) (xy 119.102378 -34.153602) (xy 119.089932 -34.13125) (xy 119.078756 -34.124138)
			(xy 119.033105 -34.094744) (xy 118.946014 -34.02989) (xy 118.864209 -33.958484) (xy 118.788183 -33.880954)
			(xy 118.718393 -33.797766) (xy 118.655258 -33.70942) (xy 118.599159 -33.616449) (xy 118.550431 -33.51941)
			(xy 118.50937 -33.418887) (xy 118.47622 -33.315485) (xy 118.451182 -33.209825) (xy 118.434406 -33.102543)
			(xy 118.425993 -32.994283) (xy 118.425468 -32.93999) (xy 118.425985 -32.887639) (xy 118.433809 -32.783228)
			(xy 118.449413 -32.679695) (xy 118.472709 -32.577616) (xy 118.503568 -32.477564) (xy 118.541816 -32.380097)
			(xy 118.587239 -32.28576) (xy 118.639585 -32.195082) (xy 118.69856 -32.108567) (xy 118.763834 -32.026702)
			(xy 118.835043 -31.949942) (xy 118.911788 -31.878718) (xy 118.993641 -31.813427) (xy 119.080143 -31.754435)
			(xy 119.170811 -31.702071) (xy 119.265138 -31.656629) (xy 119.362598 -31.618361) (xy 119.462644 -31.587482)
			(xy 119.564717 -31.564166) (xy 119.668248 -31.548541) (xy 119.772657 -31.540696) (xy 119.825008 -31.540196)
			(xy 119.879308 -31.540684) (xy 119.987582 -31.549102) (xy 120.094878 -31.565887) (xy 120.20055 -31.590938)
			(xy 120.303962 -31.624104) (xy 120.404493 -31.665187) (xy 120.501537 -31.713937) (xy 120.59451 -31.770063)
			(xy 120.682853 -31.833226) (xy 120.766035 -31.903047) (xy 120.843555 -31.979105) (xy 120.914946 -32.060943)
			(xy 120.979779 -32.148068) (xy 121.009156 -32.193738) (xy 121.016268 -32.204914) (xy 121.03862 -32.21736)
			(xy 121.151396 -32.21736) (xy 121.173748 -32.204914) (xy 121.18086 -32.193738) (xy 121.210248 -32.148075)
			(xy 121.27508 -32.060952) (xy 121.346471 -31.979116) (xy 121.423991 -31.903059) (xy 121.507172 -31.83324)
			(xy 121.595514 -31.770078) (xy 121.688487 -31.713954) (xy 121.78553 -31.665205) (xy 121.886059 -31.624125)
			(xy 121.98947 -31.59096) (xy 122.095141 -31.56591) (xy 122.202436 -31.549126) (xy 122.310708 -31.540709)
			(xy 122.365008 -31.540196) (xy 122.417364 -31.54063) (xy 122.521784 -31.548457) (xy 122.625326 -31.564066)
			(xy 122.727413 -31.58737) (xy 122.827472 -31.618239) (xy 122.924944 -31.6565) (xy 123.019283 -31.701939)
			(xy 123.109963 -31.754302) (xy 123.196476 -31.813296) (xy 123.278337 -31.878591) (xy 123.35509 -31.949821)
			(xy 123.426304 -32.026588) (xy 123.491581 -32.108464) (xy 123.550557 -32.194989) (xy 123.6029 -32.28568)
			(xy 123.648319 -32.38003) (xy 123.686559 -32.47751) (xy 123.717407 -32.577575) (xy 123.740689 -32.679667)
			(xy 123.756277 -32.783212) (xy 123.764081 -32.887634) (xy 123.764548 -32.93999) (xy 123.764054 -32.994284)
			(xy 123.761654 -33.025168) (xy 130.797545 -33.025168) (xy 130.797545 -32.854812) (xy 130.80553 -32.684644)
			(xy 130.821482 -32.515037) (xy 130.845367 -32.346365) (xy 130.877131 -32.178997) (xy 130.916706 -32.013302)
			(xy 130.964003 -31.849644) (xy 131.01892 -31.688383) (xy 131.081335 -31.529873) (xy 131.151111 -31.374463)
			(xy 131.228094 -31.222495) (xy 131.312116 -31.074301) (xy 131.402992 -30.930209) (xy 131.500522 -30.790535)
			(xy 131.604492 -30.655586) (xy 131.714673 -30.525658) (xy 131.830822 -30.401038) (xy 131.952686 -30.281999)
			(xy 132.079994 -30.168803) (xy 132.212469 -30.061698) (xy 132.349819 -29.960921) (xy 132.491741 -29.866692)
			(xy 132.637923 -29.779219) (xy 132.788046 -29.698694) (xy 132.941777 -29.625294) (xy 133.09878 -29.55918)
			(xy 133.25871 -29.500498) (xy 133.421214 -29.449377) (xy 133.585935 -29.405929) (xy 133.752513 -29.37025)
			(xy 133.920579 -29.342418) (xy 134.089765 -29.322494) (xy 134.259699 -29.310522) (xy 134.430008 -29.306529)
			(xy 134.600317 -29.310522) (xy 134.770251 -29.322494) (xy 134.939437 -29.342418) (xy 135.107503 -29.37025)
			(xy 135.274081 -29.405929) (xy 135.438802 -29.449377) (xy 135.601306 -29.500498) (xy 135.761236 -29.55918)
			(xy 135.918239 -29.625294) (xy 136.07197 -29.698694) (xy 136.222093 -29.779219) (xy 136.368275 -29.866692)
			(xy 136.510197 -29.960921) (xy 136.647547 -30.061698) (xy 136.780022 -30.168803) (xy 136.90733 -30.281999)
			(xy 137.029194 -30.401038) (xy 137.145343 -30.525658) (xy 137.255524 -30.655586) (xy 137.359494 -30.790535)
			(xy 137.457024 -30.930209) (xy 137.5479 -31.074301) (xy 137.631922 -31.222495) (xy 137.708905 -31.374463)
			(xy 137.778681 -31.529873) (xy 137.841096 -31.688383) (xy 137.896013 -31.849644) (xy 137.94331 -32.013302)
			(xy 137.982885 -32.178997) (xy 138.014649 -32.346365) (xy 138.038534 -32.515037) (xy 138.054486 -32.684644)
			(xy 138.062471 -32.854812) (xy 138.06297 -32.93999) (xy 138.062471 -33.025168) (xy 138.054486 -33.195336)
			(xy 138.038534 -33.364943) (xy 138.014649 -33.533615) (xy 137.982885 -33.700983) (xy 137.94331 -33.866678)
			(xy 137.896013 -34.030336) (xy 137.841096 -34.191597) (xy 137.778681 -34.350107) (xy 137.708905 -34.505517)
			(xy 137.631922 -34.657485) (xy 137.5479 -34.805679) (xy 137.457024 -34.949771) (xy 137.359494 -35.089445)
			(xy 137.255524 -35.224394) (xy 137.145343 -35.354322) (xy 137.029194 -35.478942) (xy 136.90733 -35.597981)
			(xy 136.780022 -35.711177) (xy 136.647547 -35.818282) (xy 136.510197 -35.919059) (xy 136.368275 -36.013288)
			(xy 136.222093 -36.100761) (xy 136.07197 -36.181286) (xy 135.918239 -36.254686) (xy 135.761236 -36.3208)
			(xy 135.601306 -36.379482) (xy 135.438802 -36.430603) (xy 135.274081 -36.474051) (xy 135.107503 -36.50973)
			(xy 134.939437 -36.537562) (xy 134.770251 -36.557486) (xy 134.600317 -36.569458) (xy 134.430008 -36.573452)
			(xy 134.259699 -36.569458) (xy 134.089765 -36.557486) (xy 133.920579 -36.537562) (xy 133.752513 -36.50973)
			(xy 133.585935 -36.474051) (xy 133.421214 -36.430603) (xy 133.25871 -36.379482) (xy 133.09878 -36.3208)
			(xy 132.941777 -36.254686) (xy 132.788046 -36.181286) (xy 132.637923 -36.100761) (xy 132.491741 -36.013288)
			(xy 132.349819 -35.919059) (xy 132.212469 -35.818282) (xy 132.079994 -35.711177) (xy 131.952686 -35.597981)
			(xy 131.830822 -35.478942) (xy 131.714673 -35.354322) (xy 131.604492 -35.224394) (xy 131.500522 -35.089445)
			(xy 131.402992 -34.949771) (xy 131.312116 -34.805679) (xy 131.228094 -34.657485) (xy 131.151111 -34.505517)
			(xy 131.081335 -34.350107) (xy 131.01892 -34.191597) (xy 130.964003 -34.030336) (xy 130.916706 -33.866678)
			(xy 130.877131 -33.700983) (xy 130.845367 -33.533615) (xy 130.821482 -33.364943) (xy 130.80553 -33.195336)
			(xy 130.797545 -33.025168) (xy 123.761654 -33.025168) (xy 123.755641 -33.102545) (xy 123.738864 -33.209828)
			(xy 123.713825 -33.315489) (xy 123.680673 -33.418892) (xy 123.639609 -33.519415) (xy 123.590879 -33.616455)
			(xy 123.534776 -33.709426) (xy 123.471638 -33.797771) (xy 123.401844 -33.880957) (xy 123.325813 -33.958486)
			(xy 123.244005 -34.029889) (xy 123.156909 -34.094739) (xy 123.11126 -34.124138) (xy 123.100084 -34.13125)
			(xy 123.087638 -34.153602) (xy 123.087638 -34.266378) (xy 123.100084 -34.28873) (xy 123.11126 -34.295842)
			(xy 123.15522 -34.324148) (xy 123.239268 -34.386354) (xy 123.318441 -34.454658) (xy 123.392295 -34.52868)
			(xy 123.46042 -34.608006) (xy 123.522436 -34.692195) (xy 123.577996 -34.780777) (xy 123.626791 -34.873258)
			(xy 123.668549 -34.969123) (xy 123.703037 -35.067836) (xy 123.730062 -35.168848) (xy 123.749475 -35.271594)
			(xy 123.761166 -35.375503) (xy 123.76507 -35.479995) (xy 123.761167 -35.584486) (xy 123.749476 -35.688395)
			(xy 123.730065 -35.791142) (xy 123.70304 -35.892154) (xy 123.668553 -35.990867) (xy 123.626796 -36.086732)
			(xy 123.578001 -36.179214) (xy 123.522442 -36.267796) (xy 123.460427 -36.351986) (xy 123.392303 -36.431313)
			(xy 123.318449 -36.505335) (xy 123.239277 -36.57364) (xy 123.155229 -36.635846) (xy 123.11126 -36.664138)
			(xy 123.100084 -36.67125) (xy 123.087638 -36.693602) (xy 123.087638 -36.806378) (xy 123.100084 -36.82873)
			(xy 123.11126 -36.835842) (xy 123.15522 -36.864148) (xy 123.239268 -36.926354) (xy 123.318441 -36.994658)
			(xy 123.392295 -37.06868) (xy 123.46042 -37.148006) (xy 123.522436 -37.232195) (xy 123.577996 -37.320777)
			(xy 123.626791 -37.413258) (xy 123.668549 -37.509123) (xy 123.703037 -37.607836) (xy 123.730062 -37.708848)
			(xy 123.749475 -37.811594) (xy 123.761166 -37.915503) (xy 123.76507 -38.019995) (xy 123.764517 -38.03481)
			(xy 165.292523 -38.03481) (xy 165.292523 -37.864454) (xy 165.300508 -37.694286) (xy 165.31646 -37.524679)
			(xy 165.340345 -37.356007) (xy 165.372109 -37.188639) (xy 165.411684 -37.022944) (xy 165.458981 -36.859286)
			(xy 165.513898 -36.698025) (xy 165.576313 -36.539515) (xy 165.646089 -36.384105) (xy 165.723072 -36.232137)
			(xy 165.807094 -36.083943) (xy 165.89797 -35.939851) (xy 165.9955 -35.800177) (xy 166.09947 -35.665228)
			(xy 166.209651 -35.5353) (xy 166.3258 -35.41068) (xy 166.447664 -35.291641) (xy 166.574972 -35.178445)
			(xy 166.707447 -35.07134) (xy 166.844797 -34.970563) (xy 166.986719 -34.876334) (xy 167.132901 -34.788861)
			(xy 167.283024 -34.708336) (xy 167.436755 -34.634936) (xy 167.593758 -34.568822) (xy 167.753688 -34.51014)
			(xy 167.916192 -34.459019) (xy 168.080913 -34.415571) (xy 168.247491 -34.379892) (xy 168.415557 -34.35206)
			(xy 168.584743 -34.332136) (xy 168.754677 -34.320164) (xy 168.924986 -34.316171) (xy 169.095295 -34.320164)
			(xy 169.265229 -34.332136) (xy 169.434415 -34.35206) (xy 169.602481 -34.379892) (xy 169.769059 -34.415571)
			(xy 169.93378 -34.459019) (xy 170.096284 -34.51014) (xy 170.256214 -34.568822) (xy 170.413217 -34.634936)
			(xy 170.566948 -34.708336) (xy 170.717071 -34.788861) (xy 170.863253 -34.876334) (xy 171.005175 -34.970563)
			(xy 171.142525 -35.07134) (xy 171.275 -35.178445) (xy 171.402308 -35.291641) (xy 171.523084 -35.409617)
			(xy 179.589712 -35.409617) (xy 179.593616 -35.305116) (xy 179.60531 -35.201197) (xy 179.624729 -35.098442)
			(xy 179.651763 -34.997422) (xy 179.686262 -34.898703) (xy 179.728034 -34.802833) (xy 179.776846 -34.71035)
			(xy 179.832424 -34.621768) (xy 179.89446 -34.537581) (xy 179.962607 -34.458261) (xy 180.036485 -34.384248)
			(xy 180.115681 -34.315956) (xy 180.199754 -34.253767) (xy 180.243734 -34.225484) (xy 180.25491 -34.218372)
			(xy 180.267356 -34.19602) (xy 180.267356 -34.083244) (xy 180.25491 -34.060892) (xy 180.243734 -34.05378)
			(xy 180.199782 -34.025453) (xy 180.115707 -33.963265) (xy 180.03651 -33.894975) (xy 179.96263 -33.820964)
			(xy 179.894482 -33.741645) (xy 179.832444 -33.65746) (xy 179.776863 -33.56888) (xy 179.728049 -33.476397)
			(xy 179.686275 -33.380529) (xy 179.651773 -33.28181) (xy 179.624736 -33.180792) (xy 179.605315 -33.078036)
			(xy 179.593619 -32.974118) (xy 179.589712 -32.869617) (xy 179.593616 -32.765116) (xy 179.60531 -32.661197)
			(xy 179.624729 -32.558442) (xy 179.651763 -32.457422) (xy 179.686262 -32.358703) (xy 179.728034 -32.262833)
			(xy 179.776846 -32.17035) (xy 179.832424 -32.081768) (xy 179.89446 -31.997581) (xy 179.962607 -31.918261)
			(xy 180.036485 -31.844248) (xy 180.115681 -31.775956) (xy 180.199754 -31.713767) (xy 180.243734 -31.685484)
			(xy 180.25491 -31.678372) (xy 180.267356 -31.65602) (xy 180.267356 -31.543244) (xy 180.25491 -31.520892)
			(xy 180.243734 -31.51378) (xy 180.198088 -31.484366) (xy 180.110965 -31.419535) (xy 180.029129 -31.348147)
			(xy 179.953072 -31.27063) (xy 179.883253 -31.187451) (xy 179.82009 -31.099111) (xy 179.763965 -31.006141)
			(xy 179.715214 -30.9091) (xy 179.674132 -30.808573) (xy 179.640965 -30.705163) (xy 179.615913 -30.599495)
			(xy 179.599126 -30.492202) (xy 179.590707 -30.383931) (xy 179.590192 -30.329632) (xy 179.590669 -30.277276)
			(xy 179.598492 -30.172858) (xy 179.614099 -30.069316) (xy 179.6374 -29.967231) (xy 179.668266 -29.867172)
			(xy 179.706525 -29.7697) (xy 179.751961 -29.675361) (xy 179.804321 -29.584681) (xy 179.863313 -29.498168)
			(xy 179.928605 -29.416307) (xy 179.999834 -29.339554) (xy 180.076599 -29.26834) (xy 180.158473 -29.203062)
			(xy 180.244996 -29.144086) (xy 180.335685 -29.091742) (xy 180.430033 -29.046323) (xy 180.527512 -29.008082)
			(xy 180.627576 -28.977234) (xy 180.729666 -28.953951) (xy 180.83321 -28.938364) (xy 180.93763 -28.930559)
			(xy 180.989986 -28.930092) (xy 181.04428 -28.93057) (xy 181.152542 -28.938984) (xy 181.259826 -28.955761)
			(xy 181.365488 -28.980801) (xy 181.468891 -29.013953) (xy 181.569415 -29.055018) (xy 181.666455 -29.10375)
			(xy 181.759426 -29.159854) (xy 181.847771 -29.222994) (xy 181.930957 -29.29279) (xy 182.008485 -29.368822)
			(xy 182.079887 -29.450632) (xy 182.144736 -29.53773) (xy 182.174134 -29.58338) (xy 182.181246 -29.594556)
			(xy 182.203598 -29.607002) (xy 182.316374 -29.607002) (xy 182.338726 -29.594556) (xy 182.345838 -29.58338)
			(xy 182.375221 -29.537722) (xy 182.440077 -29.450633) (xy 182.511486 -29.36883) (xy 182.589018 -29.292806)
			(xy 182.672208 -29.223017) (xy 182.760554 -29.159884) (xy 182.853527 -29.103785) (xy 182.950566 -29.055059)
			(xy 183.051089 -29.013997) (xy 183.154491 -28.980848) (xy 183.260151 -28.955809) (xy 183.367433 -28.939033)
			(xy 183.475693 -28.930618) (xy 183.529986 -28.930092) (xy 183.582338 -28.930608) (xy 183.686749 -28.938431)
			(xy 183.790283 -28.954033) (xy 183.892362 -28.977328) (xy 183.992415 -29.008186) (xy 184.089883 -29.046433)
			(xy 184.18422 -29.091856) (xy 184.2749 -29.144202) (xy 184.361415 -29.203176) (xy 184.443281 -29.268451)
			(xy 184.520041 -29.33966) (xy 184.591265 -29.416405) (xy 184.656556 -29.498258) (xy 184.715548 -29.584761)
			(xy 184.767912 -29.67543) (xy 184.813354 -29.769758) (xy 184.851621 -29.867218) (xy 184.882499 -29.967265)
			(xy 184.905814 -30.06934) (xy 184.921437 -30.172871) (xy 184.929281 -30.27728) (xy 184.92978 -30.329632)
			(xy 184.929276 -30.383932) (xy 184.920857 -30.492205) (xy 184.904071 -30.599499) (xy 184.87902 -30.70517)
			(xy 184.845853 -30.808581) (xy 184.804772 -30.909111) (xy 184.756023 -31.006154) (xy 184.699899 -31.099127)
			(xy 184.636737 -31.18747) (xy 184.566919 -31.270653) (xy 184.490864 -31.348173) (xy 184.409029 -31.419566)
			(xy 184.321907 -31.484402) (xy 184.276238 -31.51378) (xy 184.265062 -31.520892) (xy 184.252616 -31.543244)
			(xy 184.252616 -31.65602) (xy 184.265062 -31.678372) (xy 184.276238 -31.685484) (xy 184.320247 -31.713723)
			(xy 184.404319 -31.775918) (xy 184.483515 -31.844214) (xy 184.557391 -31.918231) (xy 184.625537 -31.997556)
			(xy 184.687572 -32.081746) (xy 184.74315 -32.170331) (xy 184.791961 -32.262818) (xy 184.833732 -32.35869)
			(xy 184.868231 -32.457412) (xy 184.895265 -32.558434) (xy 184.914682 -32.661192) (xy 184.926376 -32.765113)
			(xy 184.930281 -32.869617) (xy 184.926374 -32.974121) (xy 184.914677 -33.078041) (xy 184.895257 -33.180799)
			(xy 184.868221 -33.28182) (xy 184.83372 -33.380542) (xy 184.791946 -33.476413) (xy 184.743133 -33.568899)
			(xy 184.687553 -33.657483) (xy 184.625516 -33.741671) (xy 184.557368 -33.820994) (xy 184.48349 -33.895009)
			(xy 184.404293 -33.963304) (xy 184.320219 -34.025496) (xy 184.276238 -34.05378) (xy 184.265062 -34.060892)
			(xy 184.252616 -34.083244) (xy 184.252616 -34.19602) (xy 184.265062 -34.218372) (xy 184.276238 -34.225484)
			(xy 184.320247 -34.253723) (xy 184.404319 -34.315918) (xy 184.483515 -34.384214) (xy 184.557391 -34.458231)
			(xy 184.625537 -34.537556) (xy 184.687572 -34.621746) (xy 184.74315 -34.710331) (xy 184.791961 -34.802818)
			(xy 184.833732 -34.89869) (xy 184.868231 -34.997412) (xy 184.895265 -35.098434) (xy 184.914682 -35.201192)
			(xy 184.926376 -35.305113) (xy 184.930281 -35.409617) (xy 188.479712 -35.409617) (xy 188.483616 -35.305116)
			(xy 188.49531 -35.201197) (xy 188.514729 -35.098442) (xy 188.541763 -34.997422) (xy 188.576262 -34.898703)
			(xy 188.618034 -34.802833) (xy 188.666846 -34.71035) (xy 188.722424 -34.621768) (xy 188.78446 -34.537581)
			(xy 188.852607 -34.458261) (xy 188.926485 -34.384248) (xy 189.005681 -34.315956) (xy 189.089754 -34.253767)
			(xy 189.133734 -34.225484) (xy 189.14491 -34.218372) (xy 189.157356 -34.19602) (xy 189.157356 -34.083244)
			(xy 189.14491 -34.060892) (xy 189.133734 -34.05378) (xy 189.089782 -34.025453) (xy 189.005707 -33.963265)
			(xy 188.92651 -33.894975) (xy 188.85263 -33.820964) (xy 188.784482 -33.741645) (xy 188.722444 -33.65746)
			(xy 188.666863 -33.56888) (xy 188.618049 -33.476397) (xy 188.576275 -33.380529) (xy 188.541773 -33.28181)
			(xy 188.514736 -33.180792) (xy 188.495315 -33.078036) (xy 188.483619 -32.974118) (xy 188.479712 -32.869617)
			(xy 188.483616 -32.765116) (xy 188.49531 -32.661197) (xy 188.514729 -32.558442) (xy 188.541763 -32.457422)
			(xy 188.576262 -32.358703) (xy 188.618034 -32.262833) (xy 188.666846 -32.17035) (xy 188.722424 -32.081768)
			(xy 188.78446 -31.997581) (xy 188.852607 -31.918261) (xy 188.926485 -31.844248) (xy 189.005681 -31.775956)
			(xy 189.089754 -31.713767) (xy 189.133734 -31.685484) (xy 189.14491 -31.678372) (xy 189.157356 -31.65602)
			(xy 189.157356 -31.543244) (xy 189.14491 -31.520892) (xy 189.133734 -31.51378) (xy 189.088088 -31.484366)
			(xy 189.000965 -31.419535) (xy 188.919129 -31.348147) (xy 188.843072 -31.27063) (xy 188.773253 -31.187451)
			(xy 188.71009 -31.099111) (xy 188.653965 -31.006141) (xy 188.605214 -30.9091) (xy 188.564132 -30.808573)
			(xy 188.530965 -30.705163) (xy 188.505913 -30.599495) (xy 188.489126 -30.492202) (xy 188.480707 -30.383931)
			(xy 188.480192 -30.329632) (xy 188.480669 -30.277276) (xy 188.488492 -30.172858) (xy 188.504099 -30.069316)
			(xy 188.5274 -29.967231) (xy 188.558266 -29.867172) (xy 188.596525 -29.7697) (xy 188.641961 -29.675361)
			(xy 188.694321 -29.584681) (xy 188.753313 -29.498168) (xy 188.818605 -29.416307) (xy 188.889834 -29.339554)
			(xy 188.966599 -29.26834) (xy 189.048473 -29.203062) (xy 189.134996 -29.144086) (xy 189.225685 -29.091742)
			(xy 189.320033 -29.046323) (xy 189.417512 -29.008082) (xy 189.517576 -28.977234) (xy 189.619666 -28.953951)
			(xy 189.72321 -28.938364) (xy 189.82763 -28.930559) (xy 189.879986 -28.930092) (xy 189.93428 -28.93057)
			(xy 190.042542 -28.938984) (xy 190.149826 -28.955761) (xy 190.255488 -28.980801) (xy 190.358891 -29.013953)
			(xy 190.459415 -29.055018) (xy 190.556455 -29.10375) (xy 190.649426 -29.159854) (xy 190.737771 -29.222994)
			(xy 190.820957 -29.29279) (xy 190.898485 -29.368822) (xy 190.969887 -29.450632) (xy 191.034736 -29.53773)
			(xy 191.064134 -29.58338) (xy 191.071246 -29.594556) (xy 191.093598 -29.607002) (xy 191.206374 -29.607002)
			(xy 191.228726 -29.594556) (xy 191.235838 -29.58338) (xy 191.265221 -29.537722) (xy 191.330077 -29.450633)
			(xy 191.401486 -29.36883) (xy 191.479018 -29.292806) (xy 191.562208 -29.223017) (xy 191.650554 -29.159884)
			(xy 191.743527 -29.103785) (xy 191.840566 -29.055059) (xy 191.941089 -29.013997) (xy 192.044491 -28.980848)
			(xy 192.150151 -28.955809) (xy 192.257433 -28.939033) (xy 192.365693 -28.930618) (xy 192.419986 -28.930092)
			(xy 192.472338 -28.930608) (xy 192.576749 -28.938431) (xy 192.680283 -28.954033) (xy 192.782362 -28.977328)
			(xy 192.882415 -29.008186) (xy 192.979883 -29.046433) (xy 193.07422 -29.091856) (xy 193.1649 -29.144202)
			(xy 193.251415 -29.203176) (xy 193.333281 -29.268451) (xy 193.410041 -29.33966) (xy 193.481265 -29.416405)
			(xy 193.546556 -29.498258) (xy 193.605548 -29.584761) (xy 193.657912 -29.67543) (xy 193.703354 -29.769758)
			(xy 193.741621 -29.867218) (xy 193.772499 -29.967265) (xy 193.795814 -30.06934) (xy 193.811437 -30.172871)
			(xy 193.819281 -30.27728) (xy 193.81978 -30.329632) (xy 193.819276 -30.383932) (xy 193.810857 -30.492205)
			(xy 193.794071 -30.599499) (xy 193.76902 -30.70517) (xy 193.735853 -30.808581) (xy 193.694772 -30.909111)
			(xy 193.646023 -31.006154) (xy 193.589899 -31.099127) (xy 193.526737 -31.18747) (xy 193.456919 -31.270653)
			(xy 193.380864 -31.348173) (xy 193.299029 -31.419566) (xy 193.211907 -31.484402) (xy 193.166238 -31.51378)
			(xy 193.155062 -31.520892) (xy 193.142616 -31.543244) (xy 193.142616 -31.65602) (xy 193.155062 -31.678372)
			(xy 193.166238 -31.685484) (xy 193.210247 -31.713723) (xy 193.294319 -31.775918) (xy 193.373515 -31.844214)
			(xy 193.447391 -31.918231) (xy 193.515537 -31.997556) (xy 193.577572 -32.081746) (xy 193.63315 -32.170331)
			(xy 193.681961 -32.262818) (xy 193.723732 -32.35869) (xy 193.758231 -32.457412) (xy 193.785265 -32.558434)
			(xy 193.804682 -32.661192) (xy 193.816376 -32.765113) (xy 193.820281 -32.869617) (xy 193.816374 -32.974121)
			(xy 193.804677 -33.078041) (xy 193.785257 -33.180799) (xy 193.758221 -33.28182) (xy 193.72372 -33.380542)
			(xy 193.681946 -33.476413) (xy 193.633133 -33.568899) (xy 193.577553 -33.657483) (xy 193.515516 -33.741671)
			(xy 193.447368 -33.820994) (xy 193.37349 -33.895009) (xy 193.294293 -33.963304) (xy 193.210219 -34.025496)
			(xy 193.166238 -34.05378) (xy 193.155062 -34.060892) (xy 193.142616 -34.083244) (xy 193.142616 -34.19602)
			(xy 193.155062 -34.218372) (xy 193.166238 -34.225484) (xy 193.210247 -34.253723) (xy 193.294319 -34.315918)
			(xy 193.373515 -34.384214) (xy 193.447391 -34.458231) (xy 193.515537 -34.537556) (xy 193.577572 -34.621746)
			(xy 193.63315 -34.710331) (xy 193.681961 -34.802818) (xy 193.723732 -34.89869) (xy 193.758231 -34.997412)
			(xy 193.785265 -35.098434) (xy 193.804682 -35.201192) (xy 193.816376 -35.305113) (xy 193.820281 -35.409617)
			(xy 197.369712 -35.409617) (xy 197.373616 -35.305116) (xy 197.38531 -35.201197) (xy 197.404729 -35.098442)
			(xy 197.431763 -34.997422) (xy 197.466262 -34.898703) (xy 197.508034 -34.802833) (xy 197.556846 -34.71035)
			(xy 197.612424 -34.621768) (xy 197.67446 -34.537581) (xy 197.742607 -34.458261) (xy 197.816485 -34.384248)
			(xy 197.895681 -34.315956) (xy 197.979754 -34.253767) (xy 198.023734 -34.225484) (xy 198.03491 -34.218372)
			(xy 198.047356 -34.19602) (xy 198.047356 -34.083244) (xy 198.03491 -34.060892) (xy 198.023734 -34.05378)
			(xy 197.979782 -34.025453) (xy 197.895707 -33.963265) (xy 197.81651 -33.894975) (xy 197.74263 -33.820964)
			(xy 197.674482 -33.741645) (xy 197.612444 -33.65746) (xy 197.556863 -33.56888) (xy 197.508049 -33.476397)
			(xy 197.466275 -33.380529) (xy 197.431773 -33.28181) (xy 197.404736 -33.180792) (xy 197.385315 -33.078036)
			(xy 197.373619 -32.974118) (xy 197.369712 -32.869617) (xy 197.373616 -32.765116) (xy 197.38531 -32.661197)
			(xy 197.404729 -32.558442) (xy 197.431763 -32.457422) (xy 197.466262 -32.358703) (xy 197.508034 -32.262833)
			(xy 197.556846 -32.17035) (xy 197.612424 -32.081768) (xy 197.67446 -31.997581) (xy 197.742607 -31.918261)
			(xy 197.816485 -31.844248) (xy 197.895681 -31.775956) (xy 197.979754 -31.713767) (xy 198.023734 -31.685484)
			(xy 198.03491 -31.678372) (xy 198.047356 -31.65602) (xy 198.047356 -31.543244) (xy 198.03491 -31.520892)
			(xy 198.023734 -31.51378) (xy 197.978088 -31.484366) (xy 197.890965 -31.419535) (xy 197.809129 -31.348147)
			(xy 197.733072 -31.27063) (xy 197.663253 -31.187451) (xy 197.60009 -31.099111) (xy 197.543965 -31.006141)
			(xy 197.495214 -30.9091) (xy 197.454132 -30.808573) (xy 197.420965 -30.705163) (xy 197.395913 -30.599495)
			(xy 197.379126 -30.492202) (xy 197.370707 -30.383931) (xy 197.370192 -30.329632) (xy 197.370669 -30.277276)
			(xy 197.378492 -30.172858) (xy 197.394099 -30.069316) (xy 197.4174 -29.967231) (xy 197.448266 -29.867172)
			(xy 197.486525 -29.7697) (xy 197.531961 -29.675361) (xy 197.584321 -29.584681) (xy 197.643313 -29.498168)
			(xy 197.708605 -29.416307) (xy 197.779834 -29.339554) (xy 197.856599 -29.26834) (xy 197.938473 -29.203062)
			(xy 198.024996 -29.144086) (xy 198.115685 -29.091742) (xy 198.210033 -29.046323) (xy 198.307512 -29.008082)
			(xy 198.407576 -28.977234) (xy 198.509666 -28.953951) (xy 198.61321 -28.938364) (xy 198.71763 -28.930559)
			(xy 198.769986 -28.930092) (xy 198.82428 -28.93057) (xy 198.932542 -28.938984) (xy 199.039826 -28.955761)
			(xy 199.145488 -28.980801) (xy 199.248891 -29.013953) (xy 199.349415 -29.055018) (xy 199.446455 -29.10375)
			(xy 199.539426 -29.159854) (xy 199.627771 -29.222994) (xy 199.710957 -29.29279) (xy 199.788485 -29.368822)
			(xy 199.859887 -29.450632) (xy 199.924736 -29.53773) (xy 199.954134 -29.58338) (xy 199.961246 -29.594556)
			(xy 199.983598 -29.607002) (xy 200.096374 -29.607002) (xy 200.118726 -29.594556) (xy 200.125838 -29.58338)
			(xy 200.155221 -29.537722) (xy 200.220077 -29.450633) (xy 200.291486 -29.36883) (xy 200.369018 -29.292806)
			(xy 200.452208 -29.223017) (xy 200.540554 -29.159884) (xy 200.633527 -29.103785) (xy 200.730566 -29.055059)
			(xy 200.831089 -29.013997) (xy 200.934491 -28.980848) (xy 201.040151 -28.955809) (xy 201.147433 -28.939033)
			(xy 201.255693 -28.930618) (xy 201.309986 -28.930092) (xy 201.362338 -28.930608) (xy 201.466749 -28.938431)
			(xy 201.570283 -28.954033) (xy 201.672362 -28.977328) (xy 201.772415 -29.008186) (xy 201.869883 -29.046433)
			(xy 201.96422 -29.091856) (xy 202.0549 -29.144202) (xy 202.141415 -29.203176) (xy 202.223281 -29.268451)
			(xy 202.300041 -29.33966) (xy 202.371265 -29.416405) (xy 202.436556 -29.498258) (xy 202.495548 -29.584761)
			(xy 202.547912 -29.67543) (xy 202.593354 -29.769758) (xy 202.631621 -29.867218) (xy 202.662499 -29.967265)
			(xy 202.685814 -30.06934) (xy 202.701437 -30.172871) (xy 202.709281 -30.27728) (xy 202.70978 -30.329632)
			(xy 202.709276 -30.383932) (xy 202.700857 -30.492205) (xy 202.684071 -30.599499) (xy 202.663256 -30.6873)
			(xy 284.351952 -30.6873) (xy 284.355982 -30.602696) (xy 284.368036 -30.518857) (xy 284.388005 -30.436544)
			(xy 284.415708 -30.356502) (xy 284.450893 -30.279456) (xy 284.493244 -30.206103) (xy 284.542375 -30.137109)
			(xy 284.597842 -30.073096) (xy 284.659142 -30.014646) (xy 284.725721 -29.962288) (xy 284.796976 -29.916495)
			(xy 284.87226 -29.877683) (xy 284.950894 -29.846203) (xy 285.032163 -29.822341) (xy 285.115333 -29.806311)
			(xy 285.19965 -29.79826) (xy 285.242 -29.797756) (xy 285.288396 -29.798333) (xy 285.380684 -29.807979)
			(xy 285.471468 -29.827177) (xy 285.559762 -29.855717) (xy 285.602426 -29.873956) (xy 285.612368 -29.877762)
			(xy 285.633632 -29.877762) (xy 285.643574 -29.873956) (xy 285.686235 -29.855709) (xy 285.774528 -29.827166)
			(xy 285.865313 -29.807974) (xy 285.957604 -29.798341) (xy 286.004 -29.797756) (xy 286.047483 -29.798269)
			(xy 286.134036 -29.806754) (xy 286.219347 -29.823643) (xy 286.302603 -29.848776) (xy 286.38301 -29.881911)
			(xy 286.459801 -29.922733) (xy 286.532242 -29.970853) (xy 286.599643 -30.025811) (xy 286.630872 -30.056074)
			(xy 286.638238 -30.063186) (xy 286.656526 -30.070806) (xy 286.748474 -30.070806) (xy 286.766762 -30.063186)
			(xy 286.774128 -30.056074) (xy 286.805348 -30.025802) (xy 286.872752 -29.970849) (xy 286.945196 -29.922734)
			(xy 287.021989 -29.881915) (xy 287.102397 -29.848783) (xy 287.185654 -29.823654) (xy 287.270965 -29.806766)
			(xy 287.357517 -29.798282) (xy 287.401 -29.797756) (xy 287.447396 -29.798333) (xy 287.539684 -29.807979)
			(xy 287.630468 -29.827177) (xy 287.718762 -29.855717) (xy 287.761426 -29.873956) (xy 287.771368 -29.877762)
			(xy 287.792632 -29.877762) (xy 287.802574 -29.873956) (xy 287.845235 -29.855709) (xy 287.933528 -29.827166)
			(xy 288.024313 -29.807974) (xy 288.116604 -29.798341) (xy 288.163 -29.797756) (xy 288.205347 -29.798332)
			(xy 288.289657 -29.806382) (xy 288.37282 -29.822411) (xy 288.454083 -29.846271) (xy 288.53271 -29.877749)
			(xy 288.607988 -29.916558) (xy 288.679237 -29.962347) (xy 288.745811 -30.014701) (xy 288.807106 -30.073146)
			(xy 288.862569 -30.137153) (xy 288.911696 -30.206142) (xy 288.954043 -30.279489) (xy 288.989226 -30.356529)
			(xy 289.016926 -30.436565) (xy 289.036893 -30.518871) (xy 289.048947 -30.602702) (xy 289.052977 -30.6873)
			(xy 289.048947 -30.771898) (xy 289.036893 -30.855729) (xy 289.016926 -30.938035) (xy 288.989226 -31.018071)
			(xy 288.954043 -31.095111) (xy 288.911696 -31.168458) (xy 288.862569 -31.237447) (xy 288.807106 -31.301454)
			(xy 288.745811 -31.359899) (xy 288.679237 -31.412253) (xy 288.607988 -31.458042) (xy 288.53271 -31.496851)
			(xy 288.454083 -31.528329) (xy 288.37282 -31.552189) (xy 288.289657 -31.568218) (xy 288.205347 -31.576268)
			(xy 288.163 -31.576772) (xy 288.116604 -31.576192) (xy 288.024316 -31.566547) (xy 287.933532 -31.54735)
			(xy 287.845239 -31.518811) (xy 287.802574 -31.500572) (xy 287.792632 -31.496766) (xy 287.771368 -31.496766)
			(xy 287.761426 -31.500572) (xy 287.718763 -31.518815) (xy 287.630471 -31.54736) (xy 287.539686 -31.566553)
			(xy 287.447396 -31.576187) (xy 287.401 -31.576772) (xy 287.357516 -31.57628) (xy 287.270963 -31.567794)
			(xy 287.18565 -31.550903) (xy 287.102393 -31.525769) (xy 287.021986 -31.492631) (xy 286.945195 -31.451805)
			(xy 286.872755 -31.403681) (xy 286.805356 -31.348719) (xy 286.774128 -31.318454) (xy 286.766762 -31.311342)
			(xy 286.748474 -31.303722) (xy 286.656526 -31.303722) (xy 286.638238 -31.311342) (xy 286.630872 -31.318454)
			(xy 286.599639 -31.348712) (xy 286.532238 -31.403668) (xy 286.459797 -31.451787) (xy 286.383007 -31.492607)
			(xy 286.3026 -31.525741) (xy 286.219344 -31.550873) (xy 286.134034 -31.567761) (xy 286.047483 -31.576246)
			(xy 286.004 -31.576772) (xy 285.957604 -31.576192) (xy 285.865316 -31.566547) (xy 285.774532 -31.54735)
			(xy 285.686239 -31.518811) (xy 285.643574 -31.500572) (xy 285.633632 -31.496766) (xy 285.612368 -31.496766)
			(xy 285.602426 -31.500572) (xy 285.559763 -31.518815) (xy 285.471471 -31.54736) (xy 285.380686 -31.566553)
			(xy 285.288396 -31.576187) (xy 285.242 -31.576772) (xy 285.19965 -31.57634) (xy 285.115333 -31.568289)
			(xy 285.032163 -31.552259) (xy 284.950894 -31.528397) (xy 284.87226 -31.496917) (xy 284.796976 -31.458105)
			(xy 284.725721 -31.412312) (xy 284.659142 -31.359954) (xy 284.597842 -31.301504) (xy 284.542375 -31.237491)
			(xy 284.493244 -31.168497) (xy 284.450893 -31.095144) (xy 284.415708 -31.018098) (xy 284.388005 -30.938056)
			(xy 284.368036 -30.855743) (xy 284.355982 -30.771904) (xy 284.351952 -30.6873) (xy 202.663256 -30.6873)
			(xy 202.65902 -30.70517) (xy 202.625853 -30.808581) (xy 202.584772 -30.909111) (xy 202.536023 -31.006154)
			(xy 202.479899 -31.099127) (xy 202.416737 -31.18747) (xy 202.346919 -31.270653) (xy 202.270864 -31.348173)
			(xy 202.189029 -31.419566) (xy 202.101907 -31.484402) (xy 202.056238 -31.51378) (xy 202.045062 -31.520892)
			(xy 202.032616 -31.543244) (xy 202.032616 -31.65602) (xy 202.045062 -31.678372) (xy 202.056238 -31.685484)
			(xy 202.100247 -31.713723) (xy 202.184319 -31.775918) (xy 202.263515 -31.844214) (xy 202.337391 -31.918231)
			(xy 202.405537 -31.997556) (xy 202.467572 -32.081746) (xy 202.52315 -32.170331) (xy 202.571961 -32.262818)
			(xy 202.613732 -32.35869) (xy 202.648231 -32.457412) (xy 202.675265 -32.558434) (xy 202.694682 -32.661192)
			(xy 202.706376 -32.765113) (xy 202.710281 -32.869617) (xy 202.706374 -32.974121) (xy 202.694677 -33.078041)
			(xy 202.688184 -33.112399) (xy 274.529292 -33.112399) (xy 274.529292 -33.027677) (xy 274.537345 -32.94334)
			(xy 274.553379 -32.86015) (xy 274.577247 -32.77886) (xy 274.608735 -32.700208) (xy 274.647557 -32.624905)
			(xy 274.69336 -32.553633) (xy 274.745731 -32.487037) (xy 274.804196 -32.425722) (xy 274.868224 -32.370241)
			(xy 274.937236 -32.321098) (xy 275.010606 -32.278738) (xy 275.087671 -32.243543) (xy 275.167733 -32.215834)
			(xy 275.250066 -32.19586) (xy 275.333925 -32.183803) (xy 275.41855 -32.179772) (xy 275.503175 -32.183803)
			(xy 275.587034 -32.19586) (xy 275.598955 -32.198752) (xy 282.524141 -32.198752) (xy 282.524141 -32.114048)
			(xy 282.532193 -32.029727) (xy 282.548223 -31.946554) (xy 282.572088 -31.865281) (xy 282.60357 -31.786644)
			(xy 282.642385 -31.711356) (xy 282.68818 -31.640099) (xy 282.740542 -31.573518) (xy 282.798996 -31.512216)
			(xy 282.863012 -31.456748) (xy 282.932012 -31.407616) (xy 282.968446 -31.386018) (xy 283.002302 -31.366983)
			(xy 283.072707 -31.334173) (xy 283.145705 -31.307624) (xy 283.220737 -31.287536) (xy 283.297235 -31.274064)
			(xy 283.374616 -31.267309) (xy 283.413454 -31.266892) (xy 283.455805 -31.267378) (xy 283.540123 -31.275425)
			(xy 283.623294 -31.291451) (xy 283.704565 -31.315311) (xy 283.783201 -31.346788) (xy 283.858487 -31.385598)
			(xy 283.929744 -31.431388) (xy 283.996325 -31.483745) (xy 284.057628 -31.542194) (xy 284.113097 -31.606206)
			(xy 284.16223 -31.6752) (xy 284.204582 -31.748553) (xy 284.239769 -31.8256) (xy 284.267473 -31.905642)
			(xy 284.287443 -31.987956) (xy 284.299498 -32.071795) (xy 284.303528 -32.1564) (xy 284.299498 -32.241005)
			(xy 284.287443 -32.324844) (xy 284.267473 -32.407158) (xy 284.239769 -32.4872) (xy 284.204582 -32.564247)
			(xy 284.16223 -32.6376) (xy 284.113097 -32.706594) (xy 284.057628 -32.770606) (xy 283.996325 -32.829055)
			(xy 283.929744 -32.881412) (xy 283.858487 -32.927202) (xy 283.783201 -32.966012) (xy 283.704565 -32.997489)
			(xy 283.623294 -33.021349) (xy 283.540123 -33.037375) (xy 283.455805 -33.045422) (xy 283.413454 -33.045908)
			(xy 283.374614 -33.045521) (xy 283.297228 -33.038783) (xy 283.220725 -33.025319) (xy 283.145688 -33.005231)
			(xy 283.07269 -32.978672) (xy 283.002287 -32.945846) (xy 282.968446 -32.926782) (xy 282.932012 -32.905184)
			(xy 282.863012 -32.856052) (xy 282.798996 -32.800584) (xy 282.740542 -32.739282) (xy 282.68818 -32.672701)
			(xy 282.642385 -32.601444) (xy 282.60357 -32.526156) (xy 282.572088 -32.447519) (xy 282.548223 -32.366246)
			(xy 282.532193 -32.283073) (xy 282.524141 -32.198752) (xy 275.598955 -32.198752) (xy 275.669367 -32.215834)
			(xy 275.749429 -32.243543) (xy 275.826494 -32.278738) (xy 275.899864 -32.321098) (xy 275.968876 -32.370241)
			(xy 276.032904 -32.425722) (xy 276.091369 -32.487037) (xy 276.14374 -32.553633) (xy 276.189543 -32.624905)
			(xy 276.228365 -32.700208) (xy 276.259853 -32.77886) (xy 276.283721 -32.86015) (xy 276.299755 -32.94334)
			(xy 276.307808 -33.027677) (xy 276.308312 -33.070038) (xy 276.307808 -33.112399) (xy 276.299755 -33.196736)
			(xy 276.283721 -33.279926) (xy 276.259853 -33.361216) (xy 276.228365 -33.439868) (xy 276.189543 -33.515171)
			(xy 276.14374 -33.586443) (xy 276.091369 -33.653039) (xy 276.032904 -33.714354) (xy 275.968876 -33.769835)
			(xy 275.899864 -33.818978) (xy 275.826494 -33.861338) (xy 275.749429 -33.896533) (xy 275.669367 -33.924242)
			(xy 275.587034 -33.944216) (xy 275.503175 -33.956273) (xy 275.41855 -33.960305) (xy 275.333925 -33.956273)
			(xy 275.250066 -33.944216) (xy 275.167733 -33.924242) (xy 275.087671 -33.896533) (xy 275.010606 -33.861338)
			(xy 274.937236 -33.818978) (xy 274.868224 -33.769835) (xy 274.804196 -33.714354) (xy 274.745731 -33.653039)
			(xy 274.69336 -33.586443) (xy 274.647557 -33.515171) (xy 274.608735 -33.439868) (xy 274.577247 -33.361216)
			(xy 274.553379 -33.279926) (xy 274.537345 -33.196736) (xy 274.529292 -33.112399) (xy 202.688184 -33.112399)
			(xy 202.675257 -33.180799) (xy 202.648221 -33.28182) (xy 202.61372 -33.380542) (xy 202.571946 -33.476413)
			(xy 202.523133 -33.568899) (xy 202.467553 -33.657483) (xy 202.405516 -33.741671) (xy 202.337368 -33.820994)
			(xy 202.26349 -33.895009) (xy 202.184293 -33.963304) (xy 202.100219 -34.025496) (xy 202.056238 -34.05378)
			(xy 202.045062 -34.060892) (xy 202.032616 -34.083244) (xy 202.032616 -34.19602) (xy 202.045062 -34.218372)
			(xy 202.056238 -34.225484) (xy 202.100247 -34.253723) (xy 202.184319 -34.315918) (xy 202.263515 -34.384214)
			(xy 202.337391 -34.458231) (xy 202.405537 -34.537556) (xy 202.467572 -34.621746) (xy 202.52315 -34.710331)
			(xy 202.571961 -34.802818) (xy 202.613732 -34.89869) (xy 202.648231 -34.997412) (xy 202.675265 -35.098434)
			(xy 202.694682 -35.201192) (xy 202.706376 -35.305113) (xy 202.710281 -35.409617) (xy 202.706374 -35.514121)
			(xy 202.694677 -35.618041) (xy 202.675257 -35.720799) (xy 202.648221 -35.82182) (xy 202.61372 -35.920542)
			(xy 202.571946 -36.016413) (xy 202.523133 -36.108899) (xy 202.467553 -36.197483) (xy 202.405516 -36.281671)
			(xy 202.337368 -36.360994) (xy 202.26349 -36.435009) (xy 202.184293 -36.503304) (xy 202.100219 -36.565496)
			(xy 202.056238 -36.59378) (xy 202.045062 -36.600892) (xy 202.032616 -36.623244) (xy 202.032616 -36.73602)
			(xy 202.045062 -36.758372) (xy 202.056238 -36.765484) (xy 202.10193 -36.794827) (xy 202.189051 -36.859666)
			(xy 202.270885 -36.931062) (xy 202.346939 -37.008586) (xy 202.416756 -37.091772) (xy 202.479915 -37.180118)
			(xy 202.536037 -37.273094) (xy 202.584783 -37.37014) (xy 202.625861 -37.470673) (xy 202.659024 -37.574087)
			(xy 202.684071 -37.67976) (xy 202.700853 -37.787057) (xy 202.709268 -37.895331) (xy 202.70978 -37.949632)
			(xy 202.709293 -38.001987) (xy 202.706832 -38.03481) (xy 245.302523 -38.03481) (xy 245.302523 -37.864454)
			(xy 245.310508 -37.694286) (xy 245.32646 -37.524679) (xy 245.350345 -37.356007) (xy 245.382109 -37.188639)
			(xy 245.421684 -37.022944) (xy 245.468981 -36.859286) (xy 245.523898 -36.698025) (xy 245.586313 -36.539515)
			(xy 245.656089 -36.384105) (xy 245.733072 -36.232137) (xy 245.817094 -36.083943) (xy 245.90797 -35.939851)
			(xy 246.0055 -35.800177) (xy 246.10947 -35.665228) (xy 246.219651 -35.5353) (xy 246.3358 -35.41068)
			(xy 246.457664 -35.291641) (xy 246.584972 -35.178445) (xy 246.717447 -35.07134) (xy 246.854797 -34.970563)
			(xy 246.996719 -34.876334) (xy 247.142901 -34.788861) (xy 247.293024 -34.708336) (xy 247.446755 -34.634936)
			(xy 247.603758 -34.568822) (xy 247.763688 -34.51014) (xy 247.926192 -34.459019) (xy 248.090913 -34.415571)
			(xy 248.257491 -34.379892) (xy 248.425557 -34.35206) (xy 248.594743 -34.332136) (xy 248.764677 -34.320164)
			(xy 248.934986 -34.316171) (xy 249.105295 -34.320164) (xy 249.275229 -34.332136) (xy 249.444415 -34.35206)
			(xy 249.612481 -34.379892) (xy 249.779059 -34.415571) (xy 249.94378 -34.459019) (xy 250.106284 -34.51014)
			(xy 250.266214 -34.568822) (xy 250.423217 -34.634936) (xy 250.576948 -34.708336) (xy 250.727071 -34.788861)
			(xy 250.873253 -34.876334) (xy 251.015175 -34.970563) (xy 251.080047 -35.018161) (xy 293.293542 -35.018161)
			(xy 293.293542 -34.933439) (xy 293.301595 -34.849102) (xy 293.317629 -34.765912) (xy 293.341497 -34.684622)
			(xy 293.372985 -34.60597) (xy 293.411807 -34.530667) (xy 293.45761 -34.459395) (xy 293.509981 -34.392799)
			(xy 293.568446 -34.331484) (xy 293.632474 -34.276003) (xy 293.701486 -34.22686) (xy 293.774856 -34.1845)
			(xy 293.851921 -34.149305) (xy 293.931983 -34.121596) (xy 294.014316 -34.101622) (xy 294.098175 -34.089565)
			(xy 294.1828 -34.085534) (xy 294.267425 -34.089565) (xy 294.351284 -34.101622) (xy 294.433617 -34.121596)
			(xy 294.513679 -34.149305) (xy 294.590744 -34.1845) (xy 294.664114 -34.22686) (xy 294.733126 -34.276003)
			(xy 294.797154 -34.331484) (xy 294.855619 -34.392799) (xy 294.90799 -34.459395) (xy 294.953793 -34.530667)
			(xy 294.992615 -34.60597) (xy 295.024103 -34.684622) (xy 295.047971 -34.765912) (xy 295.064005 -34.849102)
			(xy 295.072058 -34.933439) (xy 295.072562 -34.9758) (xy 295.072058 -35.018161) (xy 295.064005 -35.102498)
			(xy 295.047971 -35.185688) (xy 295.024103 -35.266978) (xy 294.992615 -35.34563) (xy 294.953793 -35.420933)
			(xy 294.90799 -35.492205) (xy 294.855619 -35.558801) (xy 294.797154 -35.620116) (xy 294.733126 -35.675597)
			(xy 294.664114 -35.72474) (xy 294.590744 -35.7671) (xy 294.513679 -35.802295) (xy 294.433617 -35.830004)
			(xy 294.351284 -35.849978) (xy 294.267425 -35.862035) (xy 294.1828 -35.866067) (xy 294.098175 -35.862035)
			(xy 294.014316 -35.849978) (xy 293.931983 -35.830004) (xy 293.851921 -35.802295) (xy 293.774856 -35.7671)
			(xy 293.701486 -35.72474) (xy 293.632474 -35.675597) (xy 293.568446 -35.620116) (xy 293.509981 -35.558801)
			(xy 293.45761 -35.492205) (xy 293.411807 -35.420933) (xy 293.372985 -35.34563) (xy 293.341497 -35.266978)
			(xy 293.317629 -35.185688) (xy 293.301595 -35.102498) (xy 293.293542 -35.018161) (xy 251.080047 -35.018161)
			(xy 251.152525 -35.07134) (xy 251.285 -35.178445) (xy 251.412308 -35.291641) (xy 251.534172 -35.41068)
			(xy 251.650321 -35.5353) (xy 251.760502 -35.665228) (xy 251.864472 -35.800177) (xy 251.962002 -35.939851)
			(xy 252.052878 -36.083943) (xy 252.1369 -36.232137) (xy 252.213883 -36.384105) (xy 252.283659 -36.539515)
			(xy 252.346074 -36.698025) (xy 252.400991 -36.859286) (xy 252.448288 -37.022944) (xy 252.487863 -37.188639)
			(xy 252.504967 -37.278761) (xy 259.293102 -37.278761) (xy 259.293102 -37.194039) (xy 259.301155 -37.109702)
			(xy 259.317189 -37.026512) (xy 259.341057 -36.945222) (xy 259.372545 -36.86657) (xy 259.411367 -36.791267)
			(xy 259.45717 -36.719995) (xy 259.509541 -36.653399) (xy 259.568006 -36.592084) (xy 259.632034 -36.536603)
			(xy 259.701046 -36.48746) (xy 259.774416 -36.4451) (xy 259.851481 -36.409905) (xy 259.931543 -36.382196)
			(xy 260.013876 -36.362222) (xy 260.097735 -36.350165) (xy 260.18236 -36.346134) (xy 260.266985 -36.350165)
			(xy 260.350844 -36.362222) (xy 260.433177 -36.382196) (xy 260.513239 -36.409905) (xy 260.590304 -36.4451)
			(xy 260.663674 -36.48746) (xy 260.732686 -36.536603) (xy 260.796714 -36.592084) (xy 260.855179 -36.653399)
			(xy 260.90755 -36.719995) (xy 260.953353 -36.791267) (xy 260.992175 -36.86657) (xy 261.023663 -36.945222)
			(xy 261.047531 -37.026512) (xy 261.063565 -37.109702) (xy 261.071618 -37.194039) (xy 261.072122 -37.2364)
			(xy 261.071618 -37.278761) (xy 261.063565 -37.363098) (xy 261.047531 -37.446288) (xy 261.023663 -37.527578)
			(xy 260.992175 -37.60623) (xy 260.953353 -37.681533) (xy 260.90755 -37.752805) (xy 260.855179 -37.819401)
			(xy 260.796714 -37.880716) (xy 260.732686 -37.936197) (xy 260.663674 -37.98534) (xy 260.590304 -38.0277)
			(xy 260.513239 -38.062895) (xy 260.433177 -38.090604) (xy 260.350844 -38.110578) (xy 260.266985 -38.122635)
			(xy 260.18236 -38.126667) (xy 260.097735 -38.122635) (xy 260.013876 -38.110578) (xy 259.931543 -38.090604)
			(xy 259.851481 -38.062895) (xy 259.774416 -38.0277) (xy 259.701046 -37.98534) (xy 259.632034 -37.936197)
			(xy 259.568006 -37.880716) (xy 259.509541 -37.819401) (xy 259.45717 -37.752805) (xy 259.411367 -37.681533)
			(xy 259.372545 -37.60623) (xy 259.341057 -37.527578) (xy 259.317189 -37.446288) (xy 259.301155 -37.363098)
			(xy 259.293102 -37.278761) (xy 252.504967 -37.278761) (xy 252.519627 -37.356007) (xy 252.543512 -37.524679)
			(xy 252.559464 -37.694286) (xy 252.567449 -37.864454) (xy 252.567948 -37.949632) (xy 252.567449 -38.03481)
			(xy 252.559464 -38.204978) (xy 252.543512 -38.374585) (xy 252.519627 -38.543257) (xy 252.487863 -38.710625)
			(xy 252.448288 -38.87632) (xy 252.400991 -39.039978) (xy 252.350882 -39.18712) (xy 257.640836 -39.18712)
			(xy 257.641465 -39.140264) (xy 257.651373 -39.047077) (xy 257.671018 -38.955447) (xy 257.700183 -38.866389)
			(xy 257.718814 -38.823392) (xy 257.722591 -38.813952) (xy 257.723116 -38.793644) (xy 257.71983 -38.784022)
			(xy 257.705286 -38.745426) (xy 257.682591 -38.666124) (xy 257.667328 -38.585063) (xy 257.659626 -38.502938)
			(xy 257.659124 -38.461696) (xy 257.659628 -38.419335) (xy 257.667681 -38.334998) (xy 257.683715 -38.251808)
			(xy 257.707583 -38.170518) (xy 257.739071 -38.091866) (xy 257.777893 -38.016563) (xy 257.823696 -37.945291)
			(xy 257.876067 -37.878695) (xy 257.934532 -37.81738) (xy 257.99856 -37.761899) (xy 258.067572 -37.712756)
			(xy 258.140942 -37.670396) (xy 258.218007 -37.635201) (xy 258.298069 -37.607492) (xy 258.380402 -37.587518)
			(xy 258.464261 -37.575461) (xy 258.548886 -37.57143) (xy 258.633511 -37.575461) (xy 258.71737 -37.587518)
			(xy 258.799703 -37.607492) (xy 258.879765 -37.635201) (xy 258.95683 -37.670396) (xy 259.0302 -37.712756)
			(xy 259.099212 -37.761899) (xy 259.16324 -37.81738) (xy 259.221705 -37.878695) (xy 259.274076 -37.945291)
			(xy 259.319879 -38.016563) (xy 259.358701 -38.091866) (xy 259.390189 -38.170518) (xy 259.414057 -38.251808)
			(xy 259.430091 -38.334998) (xy 259.438144 -38.419335) (xy 259.438648 -38.461696) (xy 259.438331 -38.49433)
			(xy 259.433502 -38.559421) (xy 259.428996 -38.591744) (xy 259.427218 -38.603682) (xy 259.43433 -38.62578)
			(xy 259.506212 -38.700964) (xy 259.528056 -38.709092) (xy 259.53974 -38.707822) (xy 259.562407 -38.705593)
			(xy 259.607896 -38.703178) (xy 259.630672 -38.702996) (xy 259.671782 -38.703479) (xy 259.753652 -38.711065)
			(xy 259.834473 -38.726173) (xy 259.913554 -38.748676) (xy 259.990221 -38.778381) (xy 260.06382 -38.815034)
			(xy 260.133721 -38.858323) (xy 260.19933 -38.907879) (xy 260.260085 -38.963278) (xy 260.315468 -39.024047)
			(xy 260.365007 -39.089669) (xy 260.408278 -39.159581) (xy 260.444912 -39.233189) (xy 260.474597 -39.309864)
			(xy 260.49708 -39.388951) (xy 260.512167 -39.469776) (xy 260.519731 -39.551648) (xy 260.52018 -39.592758)
			(xy 260.519659 -39.635175) (xy 260.511589 -39.719623) (xy 260.495517 -39.80292) (xy 260.47159 -39.884309)
			(xy 260.440025 -39.963051) (xy 260.401108 -40.038431) (xy 260.355193 -40.109764) (xy 260.302698 -40.176404)
			(xy 260.244097 -40.237744) (xy 260.212332 -40.265858) (xy 260.203696 -40.273224) (xy 260.194806 -40.293036)
			(xy 260.194806 -40.392604) (xy 260.203696 -40.412416) (xy 260.212332 -40.419782) (xy 260.24409 -40.447905)
			(xy 260.302694 -40.509243) (xy 260.355193 -40.575881) (xy 260.401112 -40.647213) (xy 260.440033 -40.722591)
			(xy 260.471603 -40.801332) (xy 260.495535 -40.88272) (xy 260.502615 -40.9194) (xy 287.730188 -40.9194)
			(xy 287.734218 -40.834799) (xy 287.746271 -40.750964) (xy 287.766239 -40.668655) (xy 287.793941 -40.588616)
			(xy 287.829125 -40.511573) (xy 287.871474 -40.438223) (xy 287.920603 -40.369231) (xy 287.976068 -40.305221)
			(xy 288.037366 -40.246773) (xy 288.103942 -40.194417) (xy 288.175194 -40.148627) (xy 288.250475 -40.109816)
			(xy 288.329105 -40.078337) (xy 288.410372 -40.054476) (xy 288.493538 -40.038447) (xy 288.577852 -40.030396)
			(xy 288.6202 -40.029892) (xy 288.658991 -40.030305) (xy 288.736279 -40.037037) (xy 288.812687 -40.050475)
			(xy 288.887634 -40.070517) (xy 288.960551 -40.097012) (xy 289.030883 -40.129757) (xy 289.0647 -40.148764)
			(xy 289.072574 -40.152923) (xy 289.0901 -40.156017) (xy 289.107626 -40.152923) (xy 289.1155 -40.148764)
			(xy 289.149326 -40.129773) (xy 289.219657 -40.097028) (xy 289.292572 -40.070532) (xy 289.367517 -40.050487)
			(xy 289.443923 -40.037043) (xy 289.52121 -40.030305) (xy 289.56 -40.029892) (xy 289.602348 -40.030396)
			(xy 289.686662 -40.038447) (xy 289.769828 -40.054476) (xy 289.851095 -40.078337) (xy 289.929725 -40.109816)
			(xy 290.005006 -40.148627) (xy 290.076258 -40.194417) (xy 290.142834 -40.246773) (xy 290.204132 -40.305221)
			(xy 290.259597 -40.369231) (xy 290.308726 -40.438223) (xy 290.351075 -40.511573) (xy 290.386259 -40.588616)
			(xy 290.413961 -40.668655) (xy 290.433929 -40.750964) (xy 290.445982 -40.834799) (xy 290.450013 -40.9194)
			(xy 290.445982 -41.004001) (xy 290.433929 -41.087836) (xy 290.413961 -41.170145) (xy 290.386259 -41.250184)
			(xy 290.351075 -41.327227) (xy 290.308726 -41.400577) (xy 290.259597 -41.469569) (xy 290.204132 -41.533579)
			(xy 290.142834 -41.592027) (xy 290.076258 -41.644383) (xy 290.005006 -41.690173) (xy 289.929725 -41.728984)
			(xy 289.851095 -41.760463) (xy 289.769828 -41.784324) (xy 289.686662 -41.800353) (xy 289.602348 -41.808404)
			(xy 289.56 -41.808908) (xy 289.521209 -41.808495) (xy 289.443921 -41.801763) (xy 289.367513 -41.788325)
			(xy 289.292566 -41.768283) (xy 289.219649 -41.741788) (xy 289.149317 -41.709043) (xy 289.1155 -41.690036)
			(xy 289.107626 -41.685877) (xy 289.0901 -41.682783) (xy 289.072574 -41.685877) (xy 289.0647 -41.690036)
			(xy 289.030874 -41.709027) (xy 288.960543 -41.741772) (xy 288.887628 -41.768268) (xy 288.812683 -41.788313)
			(xy 288.736277 -41.801757) (xy 288.65899 -41.808495) (xy 288.6202 -41.808908) (xy 288.577852 -41.808404)
			(xy 288.493538 -41.800353) (xy 288.410372 -41.784324) (xy 288.329105 -41.760463) (xy 288.250475 -41.728984)
			(xy 288.175194 -41.690173) (xy 288.103942 -41.644383) (xy 288.037366 -41.592027) (xy 287.976068 -41.533579)
			(xy 287.920603 -41.469569) (xy 287.871474 -41.400577) (xy 287.829125 -41.327227) (xy 287.793941 -41.250184)
			(xy 287.766239 -41.170145) (xy 287.746271 -41.087836) (xy 287.734218 -41.004001) (xy 287.730188 -40.9194)
			(xy 260.502615 -40.9194) (xy 260.511612 -40.966017) (xy 260.519688 -41.050465) (xy 260.52018 -41.092882)
			(xy 260.519705 -41.135309) (xy 260.511626 -41.219777) (xy 260.49554 -41.303091) (xy 260.471593 -41.384495)
			(xy 260.440002 -41.463249) (xy 260.401055 -41.538636) (xy 260.355107 -41.609972) (xy 260.302573 -41.676608)
			(xy 260.243933 -41.737938) (xy 260.179718 -41.793405) (xy 260.110513 -41.842505) (xy 260.036947 -41.884791)
			(xy 259.959689 -41.919879) (xy 259.919724 -41.93413) (xy 259.910326 -41.937432) (xy 259.895594 -41.950132)
			(xy 259.854446 -42.03065) (xy 259.852668 -42.049954) (xy 259.855462 -42.059606) (xy 259.867486 -42.101336)
			(xy 259.874135 -42.134987) (xy 291.917116 -42.134987) (xy 291.917116 -42.050265) (xy 291.925169 -41.965928)
			(xy 291.941203 -41.882738) (xy 291.965071 -41.801448) (xy 291.996559 -41.722796) (xy 292.035381 -41.647493)
			(xy 292.081184 -41.576221) (xy 292.133555 -41.509625) (xy 292.19202 -41.44831) (xy 292.256048 -41.392829)
			(xy 292.32506 -41.343686) (xy 292.39843 -41.301326) (xy 292.475495 -41.266131) (xy 292.555557 -41.238422)
			(xy 292.63789 -41.218448) (xy 292.721749 -41.206391) (xy 292.806374 -41.20236) (xy 292.890999 -41.206391)
			(xy 292.974858 -41.218448) (xy 293.057191 -41.238422) (xy 293.137253 -41.266131) (xy 293.214318 -41.301326)
			(xy 293.287688 -41.343686) (xy 293.3567 -41.392829) (xy 293.420728 -41.44831) (xy 293.479193 -41.509625)
			(xy 293.531564 -41.576221) (xy 293.577367 -41.647493) (xy 293.616189 -41.722796) (xy 293.647677 -41.801448)
			(xy 293.671545 -41.882738) (xy 293.687579 -41.965928) (xy 293.695632 -42.050265) (xy 293.696136 -42.092626)
			(xy 293.695632 -42.134987) (xy 293.694026 -42.151808) (xy 298.200572 -42.151808) (xy 298.201202 -42.105406)
			(xy 298.210891 -42.013109) (xy 298.230144 -41.922323) (xy 298.258751 -41.834038) (xy 298.277026 -41.791382)
			(xy 298.280825 -41.781438) (xy 298.280828 -41.760177) (xy 298.277026 -41.750234) (xy 298.258766 -41.707572)
			(xy 298.230172 -41.619284) (xy 298.210915 -41.528502) (xy 298.201201 -41.436209) (xy 298.200572 -41.389808)
			(xy 298.20106 -41.348698) (xy 298.208647 -41.266829) (xy 298.223757 -41.18601) (xy 298.24626 -41.106929)
			(xy 298.275966 -41.030263) (xy 298.312619 -40.956666) (xy 298.355909 -40.886765) (xy 298.405464 -40.821157)
			(xy 298.460862 -40.760402) (xy 298.521631 -40.705019) (xy 298.587251 -40.655481) (xy 298.657163 -40.612209)
			(xy 298.73077 -40.575574) (xy 298.807444 -40.545888) (xy 298.88653 -40.523405) (xy 298.967353 -40.508316)
			(xy 299.049224 -40.50075) (xy 299.090334 -40.5003) (xy 299.136729 -40.500905) (xy 299.229017 -40.510544)
			(xy 299.319801 -40.529733) (xy 299.408095 -40.558265) (xy 299.45076 -40.5765) (xy 299.460702 -40.580306)
			(xy 299.481966 -40.580306) (xy 299.491908 -40.5765) (xy 299.534566 -40.558244) (xy 299.62286 -40.529703)
			(xy 299.713646 -40.510513) (xy 299.805938 -40.500883) (xy 299.852334 -40.5003) (xy 299.890619 -40.500677)
			(xy 299.966907 -40.507219) (xy 300.04235 -40.520304) (xy 300.116386 -40.539833) (xy 300.152562 -40.55237)
			(xy 300.160999 -40.555021) (xy 300.178669 -40.555021) (xy 300.187106 -40.55237) (xy 300.223291 -40.539863)
			(xy 300.297328 -40.520351) (xy 300.372767 -40.507266) (xy 300.449051 -40.500704) (xy 300.487334 -40.5003)
			(xy 300.525619 -40.500677) (xy 300.601907 -40.507219) (xy 300.67735 -40.520304) (xy 300.751386 -40.539833)
			(xy 300.787562 -40.55237) (xy 300.795999 -40.555021) (xy 300.813669 -40.555021) (xy 300.822106 -40.55237)
			(xy 300.858291 -40.539863) (xy 300.932328 -40.520351) (xy 301.007767 -40.507266) (xy 301.084051 -40.500704)
			(xy 301.122334 -40.5003) (xy 301.164317 -40.500787) (xy 301.247912 -40.508666) (xy 301.330395 -40.524379)
			(xy 301.411032 -40.547787) (xy 301.450248 -40.562784) (xy 301.460692 -40.566294) (xy 301.482669 -40.565127)
			(xy 301.492666 -40.560498) (xy 301.531214 -40.540705) (xy 301.611385 -40.507804) (xy 301.694374 -40.482849)
			(xy 301.779394 -40.466076) (xy 301.865642 -40.457644) (xy 301.908972 -40.45712) (xy 301.950076 -40.457579)
			(xy 302.031932 -40.465162) (xy 302.11274 -40.480265) (xy 302.191809 -40.502761) (xy 302.268465 -40.532456)
			(xy 302.342055 -40.569098) (xy 302.411949 -40.612374) (xy 302.477552 -40.661914) (xy 302.538303 -40.717297)
			(xy 302.593686 -40.778048) (xy 302.643226 -40.843651) (xy 302.686502 -40.913545) (xy 302.723144 -40.987135)
			(xy 302.752839 -41.063791) (xy 302.775335 -41.14286) (xy 302.790438 -41.223668) (xy 302.798021 -41.305524)
			(xy 302.79848 -41.346628) (xy 302.798042 -41.387131) (xy 302.7907 -41.467804) (xy 302.776059 -41.547476)
			(xy 302.754242 -41.625489) (xy 302.725429 -41.701197) (xy 302.708056 -41.737788) (xy 302.703447 -41.748346)
			(xy 302.703335 -41.771364) (xy 302.707802 -41.781984) (xy 302.724373 -41.817832) (xy 302.751818 -41.891892)
			(xy 302.772586 -41.968094) (xy 302.786514 -42.045837) (xy 302.793492 -42.124509) (xy 302.793908 -42.164)
			(xy 302.793433 -42.205102) (xy 302.785848 -42.286957) (xy 302.770743 -42.367762) (xy 302.748247 -42.446829)
			(xy 302.718551 -42.523483) (xy 302.681909 -42.59707) (xy 302.638634 -42.666962) (xy 302.589094 -42.732563)
			(xy 302.533713 -42.793313) (xy 302.472963 -42.848694) (xy 302.407362 -42.898234) (xy 302.33747 -42.941509)
			(xy 302.263883 -42.978151) (xy 302.187229 -43.007847) (xy 302.108162 -43.030343) (xy 302.027357 -43.045448)
			(xy 301.945502 -43.053033) (xy 301.9044 -43.053508) (xy 301.864854 -43.053073) (xy 301.786073 -43.046064)
			(xy 301.708224 -43.032091) (xy 301.631923 -43.011266) (xy 301.55777 -42.983752) (xy 301.521876 -42.967148)
			(xy 301.511763 -42.962977) (xy 301.489915 -42.962698) (xy 301.479712 -42.96664) (xy 301.437359 -42.984532)
			(xy 301.349773 -43.012514) (xy 301.25977 -43.031323) (xy 301.168308 -43.040759) (xy 301.122334 -43.041316)
			(xy 301.084049 -43.040947) (xy 301.00776 -43.034403) (xy 300.932318 -43.021316) (xy 300.858282 -43.001784)
			(xy 300.822106 -42.989246) (xy 300.813669 -42.986595) (xy 300.795999 -42.986595) (xy 300.787562 -42.989246)
			(xy 300.751381 -43.001762) (xy 300.677342 -43.021272) (xy 300.601902 -43.034355) (xy 300.525617 -43.040913)
			(xy 300.487334 -43.041316) (xy 300.449049 -43.040947) (xy 300.37276 -43.034403) (xy 300.297318 -43.021316)
			(xy 300.223282 -43.001784) (xy 300.187106 -42.989246) (xy 300.178669 -42.986595) (xy 300.160999 -42.986595)
			(xy 300.152562 -42.989246) (xy 300.116381 -43.001762) (xy 300.042342 -43.021272) (xy 299.966902 -43.034355)
			(xy 299.890617 -43.040913) (xy 299.852334 -43.041316) (xy 299.805939 -43.04072) (xy 299.713651 -43.031079)
			(xy 299.622867 -43.011887) (xy 299.534573 -42.983352) (xy 299.491908 -42.965116) (xy 299.481966 -42.96131)
			(xy 299.460702 -42.96131) (xy 299.45076 -42.965116) (xy 299.408093 -42.98335) (xy 299.319803 -43.011897)
			(xy 299.229019 -43.031093) (xy 299.13673 -43.040729) (xy 299.090334 -43.041316) (xy 299.049226 -43.040855)
			(xy 298.967362 -43.033273) (xy 298.886546 -43.018171) (xy 298.807467 -42.995678) (xy 298.730802 -42.965985)
			(xy 298.657202 -42.929345) (xy 298.587297 -42.886072) (xy 298.521682 -42.836534) (xy 298.460917 -42.781154)
			(xy 298.40552 -42.720404) (xy 298.355965 -42.654803) (xy 298.312673 -42.584909) (xy 298.276013 -42.51132)
			(xy 298.246299 -42.434662) (xy 298.223784 -42.35559) (xy 298.20866 -42.274778) (xy 298.201056 -42.192915)
			(xy 298.200572 -42.151808) (xy 293.694026 -42.151808) (xy 293.687579 -42.219324) (xy 293.671545 -42.302514)
			(xy 293.647677 -42.383804) (xy 293.616189 -42.462456) (xy 293.577367 -42.537759) (xy 293.531564 -42.609031)
			(xy 293.479193 -42.675627) (xy 293.420728 -42.736942) (xy 293.3567 -42.792423) (xy 293.287688 -42.841566)
			(xy 293.214318 -42.883926) (xy 293.137253 -42.919121) (xy 293.057191 -42.94683) (xy 292.974858 -42.966804)
			(xy 292.890999 -42.978861) (xy 292.806374 -42.982893) (xy 292.721749 -42.978861) (xy 292.63789 -42.966804)
			(xy 292.555557 -42.94683) (xy 292.475495 -42.919121) (xy 292.39843 -42.883926) (xy 292.32506 -42.841566)
			(xy 292.256048 -42.792423) (xy 292.19202 -42.736942) (xy 292.133555 -42.675627) (xy 292.081184 -42.609031)
			(xy 292.035381 -42.537759) (xy 291.996559 -42.462456) (xy 291.965071 -42.383804) (xy 291.941203 -42.302514)
			(xy 291.925169 -42.219324) (xy 291.917116 -42.134987) (xy 259.874135 -42.134987) (xy 259.88432 -42.186539)
			(xy 259.892782 -42.272975) (xy 259.893308 -42.3164) (xy 259.892842 -42.358233) (xy 259.885017 -42.441532)
			(xy 259.869417 -42.523731) (xy 259.858256 -42.56405) (xy 259.85597 -42.573278) (xy 259.857676 -42.592201)
			(xy 259.861558 -42.60088) (xy 259.87502 -42.627804) (xy 259.879656 -42.63618) (xy 259.893889 -42.648965)
			(xy 259.902706 -42.652696) (xy 259.941221 -42.667831) (xy 260.015569 -42.704177) (xy 260.086221 -42.747271)
			(xy 260.152565 -42.79674) (xy 260.214028 -42.852157) (xy 260.270078 -42.913043) (xy 260.320231 -42.978871)
			(xy 260.364054 -43.049073) (xy 260.401167 -43.123041) (xy 260.431251 -43.200137) (xy 260.454044 -43.279693)
			(xy 260.469349 -43.361022) (xy 260.477035 -43.443421) (xy 260.477508 -43.4848) (xy 260.477004 -43.527148)
			(xy 260.468953 -43.611462) (xy 260.452924 -43.694628) (xy 260.432497 -43.7642) (xy 287.730188 -43.7642)
			(xy 287.734218 -43.679599) (xy 287.746271 -43.595764) (xy 287.766239 -43.513455) (xy 287.793941 -43.433416)
			(xy 287.829125 -43.356373) (xy 287.871474 -43.283023) (xy 287.920603 -43.214031) (xy 287.976068 -43.150021)
			(xy 288.037366 -43.091573) (xy 288.103942 -43.039217) (xy 288.175194 -42.993427) (xy 288.250475 -42.954616)
			(xy 288.329105 -42.923137) (xy 288.410372 -42.899276) (xy 288.493538 -42.883247) (xy 288.577852 -42.875196)
			(xy 288.6202 -42.874692) (xy 288.658991 -42.875105) (xy 288.736279 -42.881837) (xy 288.812687 -42.895275)
			(xy 288.887634 -42.915317) (xy 288.960551 -42.941812) (xy 289.030883 -42.974557) (xy 289.0647 -42.993564)
			(xy 289.072574 -42.997723) (xy 289.0901 -43.000817) (xy 289.107626 -42.997723) (xy 289.1155 -42.993564)
			(xy 289.149326 -42.974573) (xy 289.219657 -42.941828) (xy 289.292572 -42.915332) (xy 289.367517 -42.895287)
			(xy 289.443923 -42.881843) (xy 289.52121 -42.875105) (xy 289.56 -42.874692) (xy 289.602348 -42.875196)
			(xy 289.686662 -42.883247) (xy 289.769828 -42.899276) (xy 289.851095 -42.923137) (xy 289.929725 -42.954616)
			(xy 290.005006 -42.993427) (xy 290.076258 -43.039217) (xy 290.142834 -43.091573) (xy 290.204132 -43.150021)
			(xy 290.259597 -43.214031) (xy 290.308726 -43.283023) (xy 290.351075 -43.356373) (xy 290.386259 -43.433416)
			(xy 290.413961 -43.513455) (xy 290.433929 -43.595764) (xy 290.445982 -43.679599) (xy 290.450013 -43.7642)
			(xy 290.445982 -43.848801) (xy 290.433929 -43.932636) (xy 290.413961 -44.014945) (xy 290.386259 -44.094984)
			(xy 290.351075 -44.172027) (xy 290.308726 -44.245377) (xy 290.259597 -44.314369) (xy 290.204132 -44.378379)
			(xy 290.142834 -44.436827) (xy 290.076258 -44.489183) (xy 290.005006 -44.534973) (xy 289.929725 -44.573784)
			(xy 289.851095 -44.605263) (xy 289.769828 -44.629124) (xy 289.686662 -44.645153) (xy 289.602348 -44.653204)
			(xy 289.56 -44.653708) (xy 289.521209 -44.653295) (xy 289.443921 -44.646563) (xy 289.367513 -44.633125)
			(xy 289.292566 -44.613083) (xy 289.219649 -44.586588) (xy 289.149317 -44.553843) (xy 289.1155 -44.534836)
			(xy 289.107626 -44.530677) (xy 289.0901 -44.527583) (xy 289.072574 -44.530677) (xy 289.0647 -44.534836)
			(xy 289.030874 -44.553827) (xy 288.960543 -44.586572) (xy 288.887628 -44.613068) (xy 288.812683 -44.633113)
			(xy 288.736277 -44.646557) (xy 288.65899 -44.653295) (xy 288.6202 -44.653708) (xy 288.577852 -44.653204)
			(xy 288.493538 -44.645153) (xy 288.410372 -44.629124) (xy 288.329105 -44.605263) (xy 288.250475 -44.573784)
			(xy 288.175194 -44.534973) (xy 288.103942 -44.489183) (xy 288.037366 -44.436827) (xy 287.976068 -44.378379)
			(xy 287.920603 -44.314369) (xy 287.871474 -44.245377) (xy 287.829125 -44.172027) (xy 287.793941 -44.094984)
			(xy 287.766239 -44.014945) (xy 287.746271 -43.932636) (xy 287.734218 -43.848801) (xy 287.730188 -43.7642)
			(xy 260.432497 -43.7642) (xy 260.429063 -43.775895) (xy 260.397584 -43.854525) (xy 260.358773 -43.929806)
			(xy 260.312983 -44.001058) (xy 260.260627 -44.067634) (xy 260.202179 -44.128932) (xy 260.138169 -44.184397)
			(xy 260.069177 -44.233526) (xy 259.995827 -44.275875) (xy 259.918784 -44.311059) (xy 259.838745 -44.338761)
			(xy 259.756436 -44.358729) (xy 259.672601 -44.370782) (xy 259.588 -44.374813) (xy 259.503399 -44.370782)
			(xy 259.419564 -44.358729) (xy 259.337255 -44.338761) (xy 259.257216 -44.311059) (xy 259.180173 -44.275875)
			(xy 259.106823 -44.233526) (xy 259.037831 -44.184397) (xy 258.973821 -44.128932) (xy 258.915373 -44.067634)
			(xy 258.863017 -44.001058) (xy 258.817227 -43.929806) (xy 258.778416 -43.854525) (xy 258.746937 -43.775895)
			(xy 258.723076 -43.694628) (xy 258.707047 -43.611462) (xy 258.698996 -43.527148) (xy 258.698492 -43.4848)
			(xy 258.698958 -43.442967) (xy 258.706783 -43.359668) (xy 258.722383 -43.277469) (xy 258.733544 -43.23715)
			(xy 258.73583 -43.227922) (xy 258.734124 -43.208999) (xy 258.730242 -43.20032) (xy 258.71678 -43.173396)
			(xy 258.712144 -43.16502) (xy 258.697911 -43.152235) (xy 258.689094 -43.148504) (xy 258.650579 -43.133369)
			(xy 258.576231 -43.097023) (xy 258.505579 -43.053929) (xy 258.439235 -43.00446) (xy 258.377772 -42.949043)
			(xy 258.321722 -42.888157) (xy 258.271569 -42.822329) (xy 258.227746 -42.752127) (xy 258.190633 -42.678159)
			(xy 258.160549 -42.601063) (xy 258.137756 -42.521507) (xy 258.122451 -42.440178) (xy 258.114765 -42.357779)
			(xy 258.114292 -42.3164) (xy 258.114767 -42.275174) (xy 258.122403 -42.193078) (xy 258.1376 -42.112039)
			(xy 258.160229 -42.032754) (xy 258.190094 -41.955902) (xy 258.226941 -41.882142) (xy 258.270452 -41.812106)
			(xy 258.320255 -41.746396) (xy 258.375923 -41.685574) (xy 258.406138 -41.657524) (xy 258.415282 -41.649142)
			(xy 258.423918 -41.62679) (xy 258.412488 -41.520618) (xy 258.39928 -41.500298) (xy 258.388612 -41.494202)
			(xy 258.352203 -41.47258) (xy 258.283247 -41.423422) (xy 258.219273 -41.367935) (xy 258.16086 -41.306622)
			(xy 258.108535 -41.240036) (xy 258.062773 -41.168781) (xy 258.023988 -41.093501) (xy 257.992529 -41.014876)
			(xy 257.968682 -40.933619) (xy 257.952663 -40.850463) (xy 257.944616 -40.766162) (xy 257.944112 -40.72382)
			(xy 257.944722 -40.676728) (xy 257.954664 -40.583071) (xy 257.974438 -40.490987) (xy 258.003824 -40.401506)
			(xy 258.022598 -40.358314) (xy 258.02655 -40.348334) (xy 258.026555 -40.32689) (xy 258.022598 -40.316912)
			(xy 258.004411 -40.274268) (xy 257.97595 -40.186031) (xy 257.956819 -40.095313) (xy 257.947225 -40.003097)
			(xy 257.946652 -39.95674) (xy 257.946693 -39.939388) (xy 257.947962 -39.904707) (xy 257.949192 -39.887398)
			(xy 257.949484 -39.87578) (xy 257.9409 -39.854212) (xy 257.932682 -39.845996) (xy 257.902445 -39.817967)
			(xy 257.846768 -39.757149) (xy 257.796958 -39.69144) (xy 257.753442 -39.621403) (xy 257.716595 -39.54764)
			(xy 257.686732 -39.470783) (xy 257.664109 -39.391493) (xy 257.648921 -39.310449) (xy 257.641298 -39.228347)
			(xy 257.640836 -39.18712) (xy 252.350882 -39.18712) (xy 252.346074 -39.201239) (xy 252.283659 -39.359749)
			(xy 252.213883 -39.515159) (xy 252.1369 -39.667127) (xy 252.052878 -39.815321) (xy 251.962002 -39.959413)
			(xy 251.864472 -40.099087) (xy 251.760502 -40.234036) (xy 251.650321 -40.363964) (xy 251.534172 -40.488584)
			(xy 251.412308 -40.607623) (xy 251.285 -40.720819) (xy 251.152525 -40.827924) (xy 251.015175 -40.928701)
			(xy 250.873253 -41.02293) (xy 250.727071 -41.110403) (xy 250.576948 -41.190928) (xy 250.423217 -41.264328)
			(xy 250.266214 -41.330442) (xy 250.106284 -41.389124) (xy 249.94378 -41.440245) (xy 249.779059 -41.483693)
			(xy 249.612481 -41.519372) (xy 249.444415 -41.547204) (xy 249.275229 -41.567128) (xy 249.105295 -41.5791)
			(xy 248.934986 -41.583094) (xy 248.764677 -41.5791) (xy 248.594743 -41.567128) (xy 248.425557 -41.547204)
			(xy 248.257491 -41.519372) (xy 248.090913 -41.483693) (xy 247.926192 -41.440245) (xy 247.763688 -41.389124)
			(xy 247.603758 -41.330442) (xy 247.446755 -41.264328) (xy 247.293024 -41.190928) (xy 247.142901 -41.110403)
			(xy 246.996719 -41.02293) (xy 246.854797 -40.928701) (xy 246.717447 -40.827924) (xy 246.584972 -40.720819)
			(xy 246.457664 -40.607623) (xy 246.3358 -40.488584) (xy 246.219651 -40.363964) (xy 246.10947 -40.234036)
			(xy 246.0055 -40.099087) (xy 245.90797 -39.959413) (xy 245.817094 -39.815321) (xy 245.733072 -39.667127)
			(xy 245.656089 -39.515159) (xy 245.586313 -39.359749) (xy 245.523898 -39.201239) (xy 245.468981 -39.039978)
			(xy 245.421684 -38.87632) (xy 245.382109 -38.710625) (xy 245.350345 -38.543257) (xy 245.32646 -38.374585)
			(xy 245.310508 -38.204978) (xy 245.302523 -38.03481) (xy 202.706832 -38.03481) (xy 202.701465 -38.106403)
			(xy 202.685855 -38.209943) (xy 202.662551 -38.312026) (xy 202.631683 -38.412082) (xy 202.593423 -38.509551)
			(xy 202.547985 -38.603889) (xy 202.495624 -38.694566) (xy 202.436633 -38.781077) (xy 202.371342 -38.862937)
			(xy 202.300114 -38.939688) (xy 202.22335 -39.010902) (xy 202.141479 -39.076179) (xy 202.054958 -39.135155)
			(xy 201.964271 -39.1875) (xy 201.869926 -39.232921) (xy 201.77245 -39.271164) (xy 201.672388 -39.302015)
			(xy 201.570301 -39.325301) (xy 201.466759 -39.340893) (xy 201.362341 -39.348702) (xy 201.309986 -39.349172)
			(xy 201.255694 -39.348606) (xy 201.147435 -39.340199) (xy 201.040154 -39.323428) (xy 200.934494 -39.298394)
			(xy 200.831092 -39.265249) (xy 200.730569 -39.224191) (xy 200.63353 -39.175467) (xy 200.540559 -39.11937)
			(xy 200.452213 -39.056237) (xy 200.369026 -38.986449) (xy 200.291496 -38.910425) (xy 200.22009 -38.828621)
			(xy 200.155238 -38.74153) (xy 200.125838 -38.695884) (xy 200.118726 -38.684708) (xy 200.096374 -38.672262)
			(xy 199.983598 -38.672262) (xy 199.961246 -38.684708) (xy 199.954134 -38.695884) (xy 199.924757 -38.741546)
			(xy 199.859901 -38.828636) (xy 199.788493 -38.91044) (xy 199.71096 -38.986465) (xy 199.62777 -39.056254)
			(xy 199.539423 -39.119388) (xy 199.44645 -39.175486) (xy 199.34941 -39.224212) (xy 199.248886 -39.265273)
			(xy 199.145483 -39.298422) (xy 199.039822 -39.323459) (xy 198.93254 -39.340234) (xy 198.824279 -39.348647)
			(xy 198.769986 -39.349172) (xy 198.717633 -39.348718) (xy 198.61322 -39.340894) (xy 198.509683 -39.325289)
			(xy 198.407602 -39.301991) (xy 198.307547 -39.271131) (xy 198.210078 -39.23288) (xy 198.11574 -39.187454)
			(xy 198.025059 -39.135106) (xy 197.938544 -39.076128) (xy 197.856677 -39.01085) (xy 197.779917 -38.939637)
			(xy 197.708692 -38.862888) (xy 197.643402 -38.781032) (xy 197.584411 -38.694526) (xy 197.532048 -38.603853)
			(xy 197.486607 -38.509522) (xy 197.448341 -38.412058) (xy 197.417465 -38.312008) (xy 197.394152 -38.209931)
			(xy 197.378531 -38.106397) (xy 197.37069 -38.001985) (xy 197.370192 -37.949632) (xy 197.370714 -37.895332)
			(xy 197.379129 -37.787059) (xy 197.395911 -37.679764) (xy 197.420959 -37.574093) (xy 197.454122 -37.470681)
			(xy 197.495202 -37.370151) (xy 197.543949 -37.273107) (xy 197.600072 -37.180134) (xy 197.663233 -37.09179)
			(xy 197.733051 -37.008608) (xy 197.809106 -36.931087) (xy 197.890942 -36.859696) (xy 197.978065 -36.794861)
			(xy 198.023734 -36.765484) (xy 198.03491 -36.758372) (xy 198.047356 -36.73602) (xy 198.047356 -36.623244)
			(xy 198.03491 -36.600892) (xy 198.023734 -36.59378) (xy 197.979782 -36.565453) (xy 197.895707 -36.503265)
			(xy 197.81651 -36.434975) (xy 197.74263 -36.360964) (xy 197.674482 -36.281645) (xy 197.612444 -36.19746)
			(xy 197.556863 -36.10888) (xy 197.508049 -36.016397) (xy 197.466275 -35.920529) (xy 197.431773 -35.82181)
			(xy 197.404736 -35.720792) (xy 197.385315 -35.618036) (xy 197.373619 -35.514118) (xy 197.369712 -35.409617)
			(xy 193.820281 -35.409617) (xy 193.816374 -35.514121) (xy 193.804677 -35.618041) (xy 193.785257 -35.720799)
			(xy 193.758221 -35.82182) (xy 193.72372 -35.920542) (xy 193.681946 -36.016413) (xy 193.633133 -36.108899)
			(xy 193.577553 -36.197483) (xy 193.515516 -36.281671) (xy 193.447368 -36.360994) (xy 193.37349 -36.435009)
			(xy 193.294293 -36.503304) (xy 193.210219 -36.565496) (xy 193.166238 -36.59378) (xy 193.155062 -36.600892)
			(xy 193.142616 -36.623244) (xy 193.142616 -36.73602) (xy 193.155062 -36.758372) (xy 193.166238 -36.765484)
			(xy 193.21193 -36.794827) (xy 193.299051 -36.859666) (xy 193.380885 -36.931062) (xy 193.456939 -37.008586)
			(xy 193.526756 -37.091772) (xy 193.589915 -37.180118) (xy 193.646037 -37.273094) (xy 193.694783 -37.37014)
			(xy 193.735861 -37.470673) (xy 193.769024 -37.574087) (xy 193.794071 -37.67976) (xy 193.810853 -37.787057)
			(xy 193.819268 -37.895331) (xy 193.81978 -37.949632) (xy 193.819293 -38.001987) (xy 193.811465 -38.106403)
			(xy 193.795855 -38.209943) (xy 193.772551 -38.312026) (xy 193.741683 -38.412082) (xy 193.703423 -38.509551)
			(xy 193.657985 -38.603889) (xy 193.605624 -38.694566) (xy 193.546633 -38.781077) (xy 193.481342 -38.862937)
			(xy 193.410114 -38.939688) (xy 193.33335 -39.010902) (xy 193.251479 -39.076179) (xy 193.164958 -39.135155)
			(xy 193.074271 -39.1875) (xy 192.979926 -39.232921) (xy 192.88245 -39.271164) (xy 192.782388 -39.302015)
			(xy 192.680301 -39.325301) (xy 192.576759 -39.340893) (xy 192.472341 -39.348702) (xy 192.419986 -39.349172)
			(xy 192.365694 -39.348606) (xy 192.257435 -39.340199) (xy 192.150154 -39.323428) (xy 192.044494 -39.298394)
			(xy 191.941092 -39.265249) (xy 191.840569 -39.224191) (xy 191.74353 -39.175467) (xy 191.650559 -39.11937)
			(xy 191.562213 -39.056237) (xy 191.479026 -38.986449) (xy 191.401496 -38.910425) (xy 191.33009 -38.828621)
			(xy 191.265238 -38.74153) (xy 191.235838 -38.695884) (xy 191.228726 -38.684708) (xy 191.206374 -38.672262)
			(xy 191.093598 -38.672262) (xy 191.071246 -38.684708) (xy 191.064134 -38.695884) (xy 191.034757 -38.741546)
			(xy 190.969901 -38.828636) (xy 190.898493 -38.91044) (xy 190.82096 -38.986465) (xy 190.73777 -39.056254)
			(xy 190.649423 -39.119388) (xy 190.55645 -39.175486) (xy 190.45941 -39.224212) (xy 190.358886 -39.265273)
			(xy 190.255483 -39.298422) (xy 190.149822 -39.323459) (xy 190.04254 -39.340234) (xy 189.934279 -39.348647)
			(xy 189.879986 -39.349172) (xy 189.827633 -39.348718) (xy 189.72322 -39.340894) (xy 189.619683 -39.325289)
			(xy 189.517602 -39.301991) (xy 189.417547 -39.271131) (xy 189.320078 -39.23288) (xy 189.22574 -39.187454)
			(xy 189.135059 -39.135106) (xy 189.048544 -39.076128) (xy 188.966677 -39.01085) (xy 188.889917 -38.939637)
			(xy 188.818692 -38.862888) (xy 188.753402 -38.781032) (xy 188.694411 -38.694526) (xy 188.642048 -38.603853)
			(xy 188.596607 -38.509522) (xy 188.558341 -38.412058) (xy 188.527465 -38.312008) (xy 188.504152 -38.209931)
			(xy 188.488531 -38.106397) (xy 188.48069 -38.001985) (xy 188.480192 -37.949632) (xy 188.480714 -37.895332)
			(xy 188.489129 -37.787059) (xy 188.505911 -37.679764) (xy 188.530959 -37.574093) (xy 188.564122 -37.470681)
			(xy 188.605202 -37.370151) (xy 188.653949 -37.273107) (xy 188.710072 -37.180134) (xy 188.773233 -37.09179)
			(xy 188.843051 -37.008608) (xy 188.919106 -36.931087) (xy 189.000942 -36.859696) (xy 189.088065 -36.794861)
			(xy 189.133734 -36.765484) (xy 189.14491 -36.758372) (xy 189.157356 -36.73602) (xy 189.157356 -36.623244)
			(xy 189.14491 -36.600892) (xy 189.133734 -36.59378) (xy 189.089782 -36.565453) (xy 189.005707 -36.503265)
			(xy 188.92651 -36.434975) (xy 188.85263 -36.360964) (xy 188.784482 -36.281645) (xy 188.722444 -36.19746)
			(xy 188.666863 -36.10888) (xy 188.618049 -36.016397) (xy 188.576275 -35.920529) (xy 188.541773 -35.82181)
			(xy 188.514736 -35.720792) (xy 188.495315 -35.618036) (xy 188.483619 -35.514118) (xy 188.479712 -35.409617)
			(xy 184.930281 -35.409617) (xy 184.926374 -35.514121) (xy 184.914677 -35.618041) (xy 184.895257 -35.720799)
			(xy 184.868221 -35.82182) (xy 184.83372 -35.920542) (xy 184.791946 -36.016413) (xy 184.743133 -36.108899)
			(xy 184.687553 -36.197483) (xy 184.625516 -36.281671) (xy 184.557368 -36.360994) (xy 184.48349 -36.435009)
			(xy 184.404293 -36.503304) (xy 184.320219 -36.565496) (xy 184.276238 -36.59378) (xy 184.265062 -36.600892)
			(xy 184.252616 -36.623244) (xy 184.252616 -36.73602) (xy 184.265062 -36.758372) (xy 184.276238 -36.765484)
			(xy 184.32193 -36.794827) (xy 184.409051 -36.859666) (xy 184.490885 -36.931062) (xy 184.566939 -37.008586)
			(xy 184.636756 -37.091772) (xy 184.699915 -37.180118) (xy 184.756037 -37.273094) (xy 184.804783 -37.37014)
			(xy 184.845861 -37.470673) (xy 184.879024 -37.574087) (xy 184.904071 -37.67976) (xy 184.920853 -37.787057)
			(xy 184.929268 -37.895331) (xy 184.92978 -37.949632) (xy 184.929293 -38.001987) (xy 184.921465 -38.106403)
			(xy 184.905855 -38.209943) (xy 184.882551 -38.312026) (xy 184.851683 -38.412082) (xy 184.813423 -38.509551)
			(xy 184.767985 -38.603889) (xy 184.715624 -38.694566) (xy 184.656633 -38.781077) (xy 184.591342 -38.862937)
			(xy 184.520114 -38.939688) (xy 184.44335 -39.010902) (xy 184.361479 -39.076179) (xy 184.274958 -39.135155)
			(xy 184.184271 -39.1875) (xy 184.089926 -39.232921) (xy 183.99245 -39.271164) (xy 183.892388 -39.302015)
			(xy 183.790301 -39.325301) (xy 183.686759 -39.340893) (xy 183.582341 -39.348702) (xy 183.529986 -39.349172)
			(xy 183.475694 -39.348606) (xy 183.367435 -39.340199) (xy 183.260154 -39.323428) (xy 183.154494 -39.298394)
			(xy 183.051092 -39.265249) (xy 182.950569 -39.224191) (xy 182.85353 -39.175467) (xy 182.760559 -39.11937)
			(xy 182.672213 -39.056237) (xy 182.589026 -38.986449) (xy 182.511496 -38.910425) (xy 182.44009 -38.828621)
			(xy 182.375238 -38.74153) (xy 182.345838 -38.695884) (xy 182.338726 -38.684708) (xy 182.316374 -38.672262)
			(xy 182.203598 -38.672262) (xy 182.181246 -38.684708) (xy 182.174134 -38.695884) (xy 182.144757 -38.741546)
			(xy 182.079901 -38.828636) (xy 182.008493 -38.91044) (xy 181.93096 -38.986465) (xy 181.84777 -39.056254)
			(xy 181.759423 -39.119388) (xy 181.66645 -39.175486) (xy 181.56941 -39.224212) (xy 181.468886 -39.265273)
			(xy 181.365483 -39.298422) (xy 181.259822 -39.323459) (xy 181.15254 -39.340234) (xy 181.044279 -39.348647)
			(xy 180.989986 -39.349172) (xy 180.937633 -39.348718) (xy 180.83322 -39.340894) (xy 180.729683 -39.325289)
			(xy 180.627602 -39.301991) (xy 180.527547 -39.271131) (xy 180.430078 -39.23288) (xy 180.33574 -39.187454)
			(xy 180.245059 -39.135106) (xy 180.158544 -39.076128) (xy 180.076677 -39.01085) (xy 179.999917 -38.939637)
			(xy 179.928692 -38.862888) (xy 179.863402 -38.781032) (xy 179.804411 -38.694526) (xy 179.752048 -38.603853)
			(xy 179.706607 -38.509522) (xy 179.668341 -38.412058) (xy 179.637465 -38.312008) (xy 179.614152 -38.209931)
			(xy 179.598531 -38.106397) (xy 179.59069 -38.001985) (xy 179.590192 -37.949632) (xy 179.590714 -37.895332)
			(xy 179.599129 -37.787059) (xy 179.615911 -37.679764) (xy 179.640959 -37.574093) (xy 179.674122 -37.470681)
			(xy 179.715202 -37.370151) (xy 179.763949 -37.273107) (xy 179.820072 -37.180134) (xy 179.883233 -37.09179)
			(xy 179.953051 -37.008608) (xy 180.029106 -36.931087) (xy 180.110942 -36.859696) (xy 180.198065 -36.794861)
			(xy 180.243734 -36.765484) (xy 180.25491 -36.758372) (xy 180.267356 -36.73602) (xy 180.267356 -36.623244)
			(xy 180.25491 -36.600892) (xy 180.243734 -36.59378) (xy 180.199782 -36.565453) (xy 180.115707 -36.503265)
			(xy 180.03651 -36.434975) (xy 179.96263 -36.360964) (xy 179.894482 -36.281645) (xy 179.832444 -36.19746)
			(xy 179.776863 -36.10888) (xy 179.728049 -36.016397) (xy 179.686275 -35.920529) (xy 179.651773 -35.82181)
			(xy 179.624736 -35.720792) (xy 179.605315 -35.618036) (xy 179.593619 -35.514118) (xy 179.589712 -35.409617)
			(xy 171.523084 -35.409617) (xy 171.524172 -35.41068) (xy 171.640321 -35.5353) (xy 171.750502 -35.665228)
			(xy 171.854472 -35.800177) (xy 171.952002 -35.939851) (xy 172.042878 -36.083943) (xy 172.1269 -36.232137)
			(xy 172.203883 -36.384105) (xy 172.273659 -36.539515) (xy 172.336074 -36.698025) (xy 172.390991 -36.859286)
			(xy 172.438288 -37.022944) (xy 172.477863 -37.188639) (xy 172.509627 -37.356007) (xy 172.533512 -37.524679)
			(xy 172.549464 -37.694286) (xy 172.557449 -37.864454) (xy 172.557948 -37.949632) (xy 172.557449 -38.03481)
			(xy 172.549464 -38.204978) (xy 172.533512 -38.374585) (xy 172.509627 -38.543257) (xy 172.477863 -38.710625)
			(xy 172.438288 -38.87632) (xy 172.390991 -39.039978) (xy 172.336074 -39.201239) (xy 172.273659 -39.359749)
			(xy 172.203883 -39.515159) (xy 172.1269 -39.667127) (xy 172.042878 -39.815321) (xy 171.952002 -39.959413)
			(xy 171.854472 -40.099087) (xy 171.750502 -40.234036) (xy 171.640321 -40.363964) (xy 171.524172 -40.488584)
			(xy 171.402308 -40.607623) (xy 171.275 -40.720819) (xy 171.142525 -40.827924) (xy 171.005175 -40.928701)
			(xy 170.863253 -41.02293) (xy 170.717071 -41.110403) (xy 170.566948 -41.190928) (xy 170.413217 -41.264328)
			(xy 170.256214 -41.330442) (xy 170.096284 -41.389124) (xy 169.93378 -41.440245) (xy 169.769059 -41.483693)
			(xy 169.602481 -41.519372) (xy 169.434415 -41.547204) (xy 169.265229 -41.567128) (xy 169.095295 -41.5791)
			(xy 168.924986 -41.583094) (xy 168.754677 -41.5791) (xy 168.584743 -41.567128) (xy 168.415557 -41.547204)
			(xy 168.247491 -41.519372) (xy 168.080913 -41.483693) (xy 167.916192 -41.440245) (xy 167.753688 -41.389124)
			(xy 167.593758 -41.330442) (xy 167.436755 -41.264328) (xy 167.283024 -41.190928) (xy 167.132901 -41.110403)
			(xy 166.986719 -41.02293) (xy 166.844797 -40.928701) (xy 166.707447 -40.827924) (xy 166.574972 -40.720819)
			(xy 166.447664 -40.607623) (xy 166.3258 -40.488584) (xy 166.209651 -40.363964) (xy 166.09947 -40.234036)
			(xy 165.9955 -40.099087) (xy 165.89797 -39.959413) (xy 165.807094 -39.815321) (xy 165.723072 -39.667127)
			(xy 165.646089 -39.515159) (xy 165.576313 -39.359749) (xy 165.513898 -39.201239) (xy 165.458981 -39.039978)
			(xy 165.411684 -38.87632) (xy 165.372109 -38.710625) (xy 165.340345 -38.543257) (xy 165.31646 -38.374585)
			(xy 165.300508 -38.204978) (xy 165.292523 -38.03481) (xy 123.764517 -38.03481) (xy 123.761167 -38.124486)
			(xy 123.749476 -38.228395) (xy 123.730065 -38.331142) (xy 123.70304 -38.432154) (xy 123.668553 -38.530867)
			(xy 123.626796 -38.626732) (xy 123.578001 -38.719214) (xy 123.522442 -38.807796) (xy 123.460427 -38.891986)
			(xy 123.392303 -38.971313) (xy 123.318449 -39.045335) (xy 123.239277 -39.11364) (xy 123.155229 -39.175846)
			(xy 123.11126 -39.204138) (xy 123.100084 -39.21125) (xy 123.087638 -39.233602) (xy 123.087638 -39.346378)
			(xy 123.100084 -39.36873) (xy 123.11126 -39.375842) (xy 123.156905 -39.405244) (xy 123.243996 -39.470097)
			(xy 123.325801 -39.541503) (xy 123.401827 -39.619033) (xy 123.471617 -39.702221) (xy 123.534751 -39.790565)
			(xy 123.590851 -39.883536) (xy 123.639579 -39.980574) (xy 123.680641 -40.081096) (xy 123.713792 -40.184498)
			(xy 123.738831 -40.290157) (xy 123.755608 -40.397438) (xy 123.764022 -40.505697) (xy 123.764548 -40.55999)
			(xy 123.764095 -40.612343) (xy 123.756272 -40.716757) (xy 123.740669 -40.820294) (xy 123.717372 -40.922376)
			(xy 123.686513 -41.022432) (xy 123.648263 -41.119902) (xy 123.602837 -41.214241) (xy 123.550489 -41.304922)
			(xy 123.491511 -41.391438) (xy 123.426233 -41.473306) (xy 123.35502 -41.550066) (xy 123.278271 -41.621291)
			(xy 123.196414 -41.686581) (xy 123.109907 -41.745573) (xy 123.019234 -41.797935) (xy 122.924902 -41.843376)
			(xy 122.827438 -41.881641) (xy 122.727387 -41.912516) (xy 122.625308 -41.935828) (xy 122.521774 -41.951448)
			(xy 122.417361 -41.959287) (xy 122.365008 -41.959784) (xy 122.310709 -41.959246) (xy 122.202437 -41.95083)
			(xy 122.095143 -41.934047) (xy 121.989473 -41.908999) (xy 121.886062 -41.875835) (xy 121.785533 -41.834757)
			(xy 121.68849 -41.786011) (xy 121.595516 -41.729889) (xy 121.507173 -41.666731) (xy 121.42399 -41.596915)
			(xy 121.346469 -41.520862) (xy 121.275075 -41.43903) (xy 121.210239 -41.35191) (xy 121.18086 -41.306242)
			(xy 121.173748 -41.295066) (xy 121.151396 -41.28262) (xy 121.03862 -41.28262) (xy 121.016268 -41.295066)
			(xy 121.009156 -41.306242) (xy 120.979787 -41.351917) (xy 120.91495 -41.439038) (xy 120.843556 -41.520872)
			(xy 120.766034 -41.596926) (xy 120.682851 -41.666744) (xy 120.594507 -41.729904) (xy 120.501533 -41.786026)
			(xy 120.404489 -41.834774) (xy 120.303959 -41.875854) (xy 120.200547 -41.909019) (xy 120.094876 -41.934068)
			(xy 119.987581 -41.950853) (xy 119.879308 -41.95927) (xy 119.825008 -41.959784) (xy 119.772654 -41.959255)
			(xy 119.668238 -41.95143) (xy 119.5647 -41.935823) (xy 119.462617 -41.912521) (xy 119.362562 -41.881656)
			(xy 119.265093 -41.843398) (xy 119.170756 -41.797963) (xy 119.080078 -41.745605) (xy 118.993567 -41.686616)
			(xy 118.911707 -41.621327) (xy 118.834955 -41.550102) (xy 118.763742 -41.47334) (xy 118.698464 -41.39147)
			(xy 118.639487 -41.304951) (xy 118.587142 -41.214266) (xy 118.541721 -41.119922) (xy 118.503478 -41.022448)
			(xy 118.472627 -40.922388) (xy 118.44934 -40.820302) (xy 118.433748 -40.716761) (xy 118.425938 -40.612344)
			(xy 118.425468 -40.55999) (xy 118.426019 -40.505697) (xy 118.434426 -40.397438) (xy 118.451197 -40.290155)
			(xy 118.476231 -40.184495) (xy 118.509377 -40.081093) (xy 118.550436 -39.980569) (xy 118.599162 -39.88353)
			(xy 118.65526 -39.790558) (xy 118.718394 -39.702213) (xy 118.788184 -39.619026) (xy 118.864211 -39.541497)
			(xy 118.946016 -39.470092) (xy 119.033109 -39.405241) (xy 119.078756 -39.375842) (xy 119.089932 -39.36873)
			(xy 119.102378 -39.346378) (xy 119.102378 -39.233602) (xy 119.089932 -39.21125) (xy 119.078756 -39.204138)
			(xy 119.03478 -39.175858) (xy 118.950735 -39.113648) (xy 118.871567 -39.045341) (xy 118.797716 -38.971316)
			(xy 118.729595 -38.891987) (xy 118.667583 -38.807796) (xy 118.612027 -38.719212) (xy 118.563235 -38.62673)
			(xy 118.52148 -38.530865) (xy 118.486995 -38.432152) (xy 118.459971 -38.33114) (xy 118.440561 -38.228394)
			(xy 118.428871 -38.124486) (xy 118.424968 -38.019995) (xy 114.87507 -38.019995) (xy 114.871167 -38.124486)
			(xy 114.859476 -38.228395) (xy 114.840065 -38.331142) (xy 114.81304 -38.432154) (xy 114.778553 -38.530867)
			(xy 114.736796 -38.626732) (xy 114.688001 -38.719214) (xy 114.632442 -38.807796) (xy 114.570427 -38.891986)
			(xy 114.502303 -38.971313) (xy 114.428449 -39.045335) (xy 114.349277 -39.11364) (xy 114.265229 -39.175846)
			(xy 114.22126 -39.204138) (xy 114.210084 -39.21125) (xy 114.197638 -39.233602) (xy 114.197638 -39.346378)
			(xy 114.210084 -39.36873) (xy 114.22126 -39.375842) (xy 114.266905 -39.405244) (xy 114.353996 -39.470097)
			(xy 114.435801 -39.541503) (xy 114.511827 -39.619033) (xy 114.581617 -39.702221) (xy 114.644751 -39.790565)
			(xy 114.700851 -39.883536) (xy 114.749579 -39.980574) (xy 114.790641 -40.081096) (xy 114.823792 -40.184498)
			(xy 114.848831 -40.290157) (xy 114.865608 -40.397438) (xy 114.874022 -40.505697) (xy 114.874548 -40.55999)
			(xy 114.874095 -40.612343) (xy 114.866272 -40.716757) (xy 114.850669 -40.820294) (xy 114.827372 -40.922376)
			(xy 114.796513 -41.022432) (xy 114.758263 -41.119902) (xy 114.712837 -41.214241) (xy 114.660489 -41.304922)
			(xy 114.601511 -41.391438) (xy 114.536233 -41.473306) (xy 114.46502 -41.550066) (xy 114.388271 -41.621291)
			(xy 114.306414 -41.686581) (xy 114.219907 -41.745573) (xy 114.129234 -41.797935) (xy 114.034902 -41.843376)
			(xy 113.937438 -41.881641) (xy 113.837387 -41.912516) (xy 113.735308 -41.935828) (xy 113.631774 -41.951448)
			(xy 113.527361 -41.959287) (xy 113.475008 -41.959784) (xy 113.420709 -41.959246) (xy 113.312437 -41.95083)
			(xy 113.205143 -41.934047) (xy 113.099473 -41.908999) (xy 112.996062 -41.875835) (xy 112.895533 -41.834757)
			(xy 112.79849 -41.786011) (xy 112.705516 -41.729889) (xy 112.617173 -41.666731) (xy 112.53399 -41.596915)
			(xy 112.456469 -41.520862) (xy 112.385075 -41.43903) (xy 112.320239 -41.35191) (xy 112.29086 -41.306242)
			(xy 112.283748 -41.295066) (xy 112.261396 -41.28262) (xy 112.14862 -41.28262) (xy 112.126268 -41.295066)
			(xy 112.119156 -41.306242) (xy 112.089787 -41.351917) (xy 112.02495 -41.439038) (xy 111.953556 -41.520872)
			(xy 111.876034 -41.596926) (xy 111.792851 -41.666744) (xy 111.704507 -41.729904) (xy 111.611533 -41.786026)
			(xy 111.514489 -41.834774) (xy 111.413959 -41.875854) (xy 111.310547 -41.909019) (xy 111.204876 -41.934068)
			(xy 111.097581 -41.950853) (xy 110.989308 -41.95927) (xy 110.935008 -41.959784) (xy 110.882654 -41.959255)
			(xy 110.778238 -41.95143) (xy 110.6747 -41.935823) (xy 110.572617 -41.912521) (xy 110.472562 -41.881656)
			(xy 110.375093 -41.843398) (xy 110.280756 -41.797963) (xy 110.190078 -41.745605) (xy 110.103567 -41.686616)
			(xy 110.021707 -41.621327) (xy 109.944955 -41.550102) (xy 109.873742 -41.47334) (xy 109.808464 -41.39147)
			(xy 109.749487 -41.304951) (xy 109.697142 -41.214266) (xy 109.651721 -41.119922) (xy 109.613478 -41.022448)
			(xy 109.582627 -40.922388) (xy 109.55934 -40.820302) (xy 109.543748 -40.716761) (xy 109.535938 -40.612344)
			(xy 109.535468 -40.55999) (xy 109.536019 -40.505697) (xy 109.544426 -40.397438) (xy 109.561197 -40.290155)
			(xy 109.586231 -40.184495) (xy 109.619377 -40.081093) (xy 109.660436 -39.980569) (xy 109.709162 -39.88353)
			(xy 109.76526 -39.790558) (xy 109.828394 -39.702213) (xy 109.898184 -39.619026) (xy 109.974211 -39.541497)
			(xy 110.056016 -39.470092) (xy 110.143109 -39.405241) (xy 110.188756 -39.375842) (xy 110.199932 -39.36873)
			(xy 110.212378 -39.346378) (xy 110.212378 -39.233602) (xy 110.199932 -39.21125) (xy 110.188756 -39.204138)
			(xy 110.14478 -39.175858) (xy 110.060735 -39.113648) (xy 109.981567 -39.045341) (xy 109.907716 -38.971316)
			(xy 109.839595 -38.891987) (xy 109.777583 -38.807796) (xy 109.722027 -38.719212) (xy 109.673235 -38.62673)
			(xy 109.63148 -38.530865) (xy 109.596995 -38.432152) (xy 109.569971 -38.33114) (xy 109.550561 -38.228394)
			(xy 109.538871 -38.124486) (xy 109.534968 -38.019995) (xy 105.98507 -38.019995) (xy 105.981167 -38.124486)
			(xy 105.969476 -38.228395) (xy 105.950065 -38.331142) (xy 105.92304 -38.432154) (xy 105.888553 -38.530867)
			(xy 105.846796 -38.626732) (xy 105.798001 -38.719214) (xy 105.742442 -38.807796) (xy 105.680427 -38.891986)
			(xy 105.612303 -38.971313) (xy 105.538449 -39.045335) (xy 105.459277 -39.11364) (xy 105.375229 -39.175846)
			(xy 105.33126 -39.204138) (xy 105.320084 -39.21125) (xy 105.307638 -39.233602) (xy 105.307638 -39.346378)
			(xy 105.320084 -39.36873) (xy 105.33126 -39.375842) (xy 105.376905 -39.405244) (xy 105.463996 -39.470097)
			(xy 105.545801 -39.541503) (xy 105.621827 -39.619033) (xy 105.691617 -39.702221) (xy 105.754751 -39.790565)
			(xy 105.810851 -39.883536) (xy 105.859579 -39.980574) (xy 105.900641 -40.081096) (xy 105.933792 -40.184498)
			(xy 105.958831 -40.290157) (xy 105.975608 -40.397438) (xy 105.984022 -40.505697) (xy 105.984548 -40.55999)
			(xy 105.984095 -40.612343) (xy 105.976272 -40.716757) (xy 105.960669 -40.820294) (xy 105.937372 -40.922376)
			(xy 105.906513 -41.022432) (xy 105.868263 -41.119902) (xy 105.822837 -41.214241) (xy 105.770489 -41.304922)
			(xy 105.711511 -41.391438) (xy 105.646233 -41.473306) (xy 105.57502 -41.550066) (xy 105.498271 -41.621291)
			(xy 105.416414 -41.686581) (xy 105.329907 -41.745573) (xy 105.239234 -41.797935) (xy 105.144902 -41.843376)
			(xy 105.047438 -41.881641) (xy 104.947387 -41.912516) (xy 104.845308 -41.935828) (xy 104.741774 -41.951448)
			(xy 104.637361 -41.959287) (xy 104.585008 -41.959784) (xy 104.530709 -41.959246) (xy 104.422437 -41.95083)
			(xy 104.315143 -41.934047) (xy 104.209473 -41.908999) (xy 104.106062 -41.875835) (xy 104.005533 -41.834757)
			(xy 103.90849 -41.786011) (xy 103.815516 -41.729889) (xy 103.727173 -41.666731) (xy 103.64399 -41.596915)
			(xy 103.566469 -41.520862) (xy 103.495075 -41.43903) (xy 103.430239 -41.35191) (xy 103.40086 -41.306242)
			(xy 103.393748 -41.295066) (xy 103.371396 -41.28262) (xy 103.25862 -41.28262) (xy 103.236268 -41.295066)
			(xy 103.229156 -41.306242) (xy 103.199787 -41.351917) (xy 103.13495 -41.439038) (xy 103.063556 -41.520872)
			(xy 102.986034 -41.596926) (xy 102.902851 -41.666744) (xy 102.814507 -41.729904) (xy 102.721533 -41.786026)
			(xy 102.624489 -41.834774) (xy 102.523959 -41.875854) (xy 102.420547 -41.909019) (xy 102.314876 -41.934068)
			(xy 102.207581 -41.950853) (xy 102.099308 -41.95927) (xy 102.045008 -41.959784) (xy 101.992654 -41.959255)
			(xy 101.888238 -41.95143) (xy 101.7847 -41.935823) (xy 101.682617 -41.912521) (xy 101.582562 -41.881656)
			(xy 101.485093 -41.843398) (xy 101.390756 -41.797963) (xy 101.300078 -41.745605) (xy 101.213567 -41.686616)
			(xy 101.131707 -41.621327) (xy 101.054955 -41.550102) (xy 100.983742 -41.47334) (xy 100.918464 -41.39147)
			(xy 100.859487 -41.304951) (xy 100.807142 -41.214266) (xy 100.761721 -41.119922) (xy 100.723478 -41.022448)
			(xy 100.692627 -40.922388) (xy 100.66934 -40.820302) (xy 100.653748 -40.716761) (xy 100.645938 -40.612344)
			(xy 100.645468 -40.55999) (xy 100.646019 -40.505697) (xy 100.654426 -40.397438) (xy 100.671197 -40.290155)
			(xy 100.696231 -40.184495) (xy 100.729377 -40.081093) (xy 100.770436 -39.980569) (xy 100.819162 -39.88353)
			(xy 100.87526 -39.790558) (xy 100.938394 -39.702213) (xy 101.008184 -39.619026) (xy 101.084211 -39.541497)
			(xy 101.166016 -39.470092) (xy 101.253109 -39.405241) (xy 101.298756 -39.375842) (xy 101.309932 -39.36873)
			(xy 101.322378 -39.346378) (xy 101.322378 -39.233602) (xy 101.309932 -39.21125) (xy 101.298756 -39.204138)
			(xy 101.25478 -39.175858) (xy 101.170735 -39.113648) (xy 101.091567 -39.045341) (xy 101.017716 -38.971316)
			(xy 100.949595 -38.891987) (xy 100.887583 -38.807796) (xy 100.832027 -38.719212) (xy 100.783235 -38.62673)
			(xy 100.74148 -38.530865) (xy 100.706995 -38.432152) (xy 100.679971 -38.33114) (xy 100.660561 -38.228394)
			(xy 100.648871 -38.124486) (xy 100.644968 -38.019995) (xy 0.509016 -38.019995) (xy 0.509016 -45.466)
			(xy 293.242492 -45.466) (xy 293.242987 -45.423046) (xy 293.251252 -45.337536) (xy 293.267725 -45.253222)
			(xy 293.292251 -45.170889) (xy 293.324602 -45.091305) (xy 293.364476 -45.015211) (xy 293.411503 -44.943317)
			(xy 293.465243 -44.876293) (xy 293.525197 -44.814764) (xy 293.590803 -44.759303) (xy 293.661453 -44.710426)
			(xy 293.736486 -44.668591) (xy 293.775638 -44.650914) (xy 293.783674 -44.646948) (xy 293.796551 -44.634501)
			(xy 293.804365 -44.618386) (xy 293.80561 -44.609512) (xy 293.810549 -44.566203) (xy 293.827823 -44.48076)
			(xy 293.853371 -44.397415) (xy 293.886947 -44.316968) (xy 293.928229 -44.240191) (xy 293.976821 -44.167818)
			(xy 294.032259 -44.100545) (xy 294.094009 -44.039015) (xy 294.161481 -43.98382) (xy 294.234027 -43.935487)
			(xy 294.310952 -43.89448) (xy 294.391519 -43.861193) (xy 294.474954 -43.835944) (xy 294.560459 -43.818976)
			(xy 294.647214 -43.810451) (xy 294.6908 -43.80992) (xy 294.72807 -43.810301) (xy 294.802353 -43.816489)
			(xy 294.875858 -43.828865) (xy 294.948072 -43.84734) (xy 294.983408 -43.859196) (xy 294.991804 -43.861751)
			(xy 295.009341 -43.861622) (xy 295.017698 -43.858942) (xy 295.054748 -43.845723) (xy 295.130664 -43.825091)
			(xy 295.208104 -43.811237) (xy 295.286465 -43.80427) (xy 295.3258 -43.803824) (xy 295.366912 -43.804252)
			(xy 295.448784 -43.811841) (xy 295.529606 -43.826952) (xy 295.608689 -43.849458) (xy 295.685358 -43.879166)
			(xy 295.758958 -43.915823) (xy 295.82886 -43.959116) (xy 295.894469 -44.008675) (xy 295.955224 -44.064078)
			(xy 296.010607 -44.124851) (xy 296.060146 -44.190476) (xy 296.103416 -44.260392) (xy 296.140049 -44.334004)
			(xy 296.161782 -44.390144) (xy 307.777633 -44.390144) (xy 307.777633 -44.219788) (xy 307.785618 -44.04962)
			(xy 307.80157 -43.880013) (xy 307.825455 -43.711341) (xy 307.857219 -43.543973) (xy 307.896794 -43.378278)
			(xy 307.944091 -43.21462) (xy 307.999008 -43.053359) (xy 308.061423 -42.894849) (xy 308.131199 -42.739439)
			(xy 308.208182 -42.587471) (xy 308.292204 -42.439277) (xy 308.38308 -42.295185) (xy 308.48061 -42.155511)
			(xy 308.58458 -42.020562) (xy 308.694761 -41.890634) (xy 308.81091 -41.766014) (xy 308.932774 -41.646975)
			(xy 309.060082 -41.533779) (xy 309.192557 -41.426674) (xy 309.329907 -41.325897) (xy 309.471829 -41.231668)
			(xy 309.618011 -41.144195) (xy 309.768134 -41.06367) (xy 309.921865 -40.99027) (xy 310.078868 -40.924156)
			(xy 310.238798 -40.865474) (xy 310.401302 -40.814353) (xy 310.566023 -40.770905) (xy 310.732601 -40.735226)
			(xy 310.900667 -40.707394) (xy 311.069853 -40.68747) (xy 311.239787 -40.675498) (xy 311.410096 -40.671505)
			(xy 311.580405 -40.675498) (xy 311.750339 -40.68747) (xy 311.919525 -40.707394) (xy 312.087591 -40.735226)
			(xy 312.254169 -40.770905) (xy 312.41889 -40.814353) (xy 312.581394 -40.865474) (xy 312.741324 -40.924156)
			(xy 312.898327 -40.99027) (xy 313.052058 -41.06367) (xy 313.202181 -41.144195) (xy 313.348363 -41.231668)
			(xy 313.490285 -41.325897) (xy 313.627635 -41.426674) (xy 313.76011 -41.533779) (xy 313.887418 -41.646975)
			(xy 314.009282 -41.766014) (xy 314.125431 -41.890634) (xy 314.235612 -42.020562) (xy 314.339582 -42.155511)
			(xy 314.437112 -42.295185) (xy 314.527988 -42.439277) (xy 314.61201 -42.587471) (xy 314.688993 -42.739439)
			(xy 314.758769 -42.894849) (xy 314.821184 -43.053359) (xy 314.876101 -43.21462) (xy 314.923398 -43.378278)
			(xy 314.962973 -43.543973) (xy 314.994737 -43.711341) (xy 315.018622 -43.880013) (xy 315.034574 -44.04962)
			(xy 315.042559 -44.219788) (xy 315.043058 -44.304966) (xy 315.042559 -44.390144) (xy 315.034574 -44.560312)
			(xy 315.018622 -44.729919) (xy 314.994737 -44.898591) (xy 314.962973 -45.065959) (xy 314.923398 -45.231654)
			(xy 314.876101 -45.395312) (xy 314.821184 -45.556573) (xy 314.758769 -45.715083) (xy 314.688993 -45.870493)
			(xy 314.61201 -46.022461) (xy 314.527988 -46.170655) (xy 314.437112 -46.314747) (xy 314.339582 -46.454421)
			(xy 314.235612 -46.58937) (xy 314.125431 -46.719298) (xy 314.009282 -46.843918) (xy 313.887418 -46.962957)
			(xy 313.76011 -47.076153) (xy 313.627635 -47.183258) (xy 313.490285 -47.284035) (xy 313.348363 -47.378264)
			(xy 313.202181 -47.465737) (xy 313.052058 -47.546262) (xy 312.898327 -47.619662) (xy 312.741324 -47.685776)
			(xy 312.581394 -47.744458) (xy 312.41889 -47.795579) (xy 312.254169 -47.839027) (xy 312.087591 -47.874706)
			(xy 311.919525 -47.902538) (xy 311.750339 -47.922462) (xy 311.580405 -47.934434) (xy 311.410096 -47.938428)
			(xy 311.239787 -47.934434) (xy 311.069853 -47.922462) (xy 310.900667 -47.902538) (xy 310.732601 -47.874706)
			(xy 310.566023 -47.839027) (xy 310.401302 -47.795579) (xy 310.238798 -47.744458) (xy 310.078868 -47.685776)
			(xy 309.921865 -47.619662) (xy 309.768134 -47.546262) (xy 309.618011 -47.465737) (xy 309.471829 -47.378264)
			(xy 309.329907 -47.284035) (xy 309.192557 -47.183258) (xy 309.060082 -47.076153) (xy 308.932774 -46.962957)
			(xy 308.81091 -46.843918) (xy 308.694761 -46.719298) (xy 308.58458 -46.58937) (xy 308.48061 -46.454421)
			(xy 308.38308 -46.314747) (xy 308.292204 -46.170655) (xy 308.208182 -46.022461) (xy 308.131199 -45.870493)
			(xy 308.061423 -45.715083) (xy 307.999008 -45.556573) (xy 307.944091 -45.395312) (xy 307.896794 -45.231654)
			(xy 307.857219 -45.065959) (xy 307.825455 -44.898591) (xy 307.80157 -44.729919) (xy 307.785618 -44.560312)
			(xy 307.777633 -44.390144) (xy 296.161782 -44.390144) (xy 296.169733 -44.410682) (xy 296.192213 -44.489772)
			(xy 296.207299 -44.5706) (xy 296.214861 -44.652474) (xy 296.215308 -44.693586) (xy 296.214781 -44.738929)
			(xy 296.205621 -44.829149) (xy 296.19702 -44.873672) (xy 296.194226 -44.88688) (xy 296.202354 -44.91228)
			(xy 296.28592 -44.989496) (xy 296.311574 -44.995592) (xy 296.324528 -44.992036) (xy 296.364572 -44.981036)
			(xy 296.446183 -44.965647) (xy 296.528875 -44.957947) (xy 296.5704 -44.957492) (xy 296.611502 -44.957967)
			(xy 296.693357 -44.965552) (xy 296.774162 -44.980657) (xy 296.853229 -45.003153) (xy 296.929883 -45.032849)
			(xy 297.00347 -45.069491) (xy 297.073362 -45.112766) (xy 297.138963 -45.162306) (xy 297.199713 -45.217687)
			(xy 297.255094 -45.278437) (xy 297.304634 -45.344038) (xy 297.347909 -45.41393) (xy 297.384551 -45.487517)
			(xy 297.414247 -45.564171) (xy 297.436743 -45.643238) (xy 297.451848 -45.724043) (xy 297.459433 -45.805898)
			(xy 297.459908 -45.847) (xy 297.459411 -45.889308) (xy 297.451408 -45.973544) (xy 297.435447 -46.05664)
			(xy 297.41167 -46.137846) (xy 297.380294 -46.216429) (xy 297.341601 -46.291679) (xy 297.319192 -46.327568)
			(xy 297.314312 -46.335958) (xy 297.310644 -46.355) (xy 297.314312 -46.374042) (xy 297.319192 -46.382432)
			(xy 297.341624 -46.418309) (xy 297.380335 -46.493554) (xy 297.411721 -46.572137) (xy 297.435497 -46.653347)
			(xy 297.45145 -46.736449) (xy 297.459434 -46.82069) (xy 297.459908 -46.863) (xy 297.459446 -46.903899)
			(xy 297.451939 -46.985353) (xy 297.436989 -47.065774) (xy 297.414721 -47.144483) (xy 297.385324 -47.220817)
			(xy 297.349046 -47.29413) (xy 297.306193 -47.363806) (xy 297.257126 -47.429254) (xy 297.230038 -47.4599)
			(xy 297.222926 -47.467774) (xy 297.216068 -47.488094) (xy 297.225212 -47.584106) (xy 297.235626 -47.602648)
			(xy 297.244262 -47.609252) (xy 297.255779 -47.618387) (xy 297.274571 -47.640984) (xy 297.287678 -47.667291)
			(xy 297.294399 -47.695902) (xy 297.294808 -47.710598) (xy 297.294808 -50.488088) (xy 297.294295 -50.504742)
			(xy 297.285677 -50.536914) (xy 297.269026 -50.565761) (xy 297.245477 -50.589314) (xy 297.216633 -50.60597)
			(xy 297.184461 -50.614592) (xy 297.167808 -50.615088) (xy 295.953434 -50.615088) (xy 295.93678 -50.614576)
			(xy 295.904605 -50.605961) (xy 295.875756 -50.589312) (xy 295.852202 -50.565761) (xy 295.835547 -50.536916)
			(xy 295.826927 -50.504742) (xy 295.826434 -50.488088) (xy 295.826434 -47.710598) (xy 295.826902 -47.694875)
			(xy 295.834601 -47.664385) (xy 295.849508 -47.636695) (xy 295.870721 -47.613481) (xy 295.883584 -47.604426)
			(xy 295.892982 -47.59833) (xy 295.904666 -47.579788) (xy 295.91762 -47.48149) (xy 295.91127 -47.460662)
			(xy 295.903904 -47.45228) (xy 295.877568 -47.421825) (xy 295.829911 -47.356921) (xy 295.788317 -47.287975)
			(xy 295.753126 -47.215551) (xy 295.724627 -47.140242) (xy 295.703053 -47.062664) (xy 295.688581 -46.983455)
			(xy 295.681328 -46.903261) (xy 295.680892 -46.863) (xy 295.681389 -46.820692) (xy 295.689392 -46.736456)
			(xy 295.705353 -46.65336) (xy 295.72913 -46.572154) (xy 295.760506 -46.493571) (xy 295.799199 -46.418321)
			(xy 295.821608 -46.382432) (xy 295.826488 -46.374042) (xy 295.830156 -46.355) (xy 295.826488 -46.335958)
			(xy 295.821608 -46.327568) (xy 295.799176 -46.291691) (xy 295.760465 -46.216446) (xy 295.729079 -46.137863)
			(xy 295.705303 -46.056653) (xy 295.68935 -45.973551) (xy 295.681366 -45.88931) (xy 295.680892 -45.847)
			(xy 295.681417 -45.801657) (xy 295.690578 -45.711437) (xy 295.69918 -45.666914) (xy 295.701974 -45.653706)
			(xy 295.693846 -45.628306) (xy 295.61028 -45.55109) (xy 295.584626 -45.544994) (xy 295.571672 -45.54855)
			(xy 295.531633 -45.559591) (xy 295.450025 -45.575055) (xy 295.36733 -45.582845) (xy 295.3258 -45.583348)
			(xy 295.275639 -45.58264) (xy 295.175958 -45.571313) (xy 295.126918 -45.560742) (xy 295.116758 -45.558456)
			(xy 295.096438 -45.562012) (xy 295.017952 -45.612812) (xy 295.006522 -45.62983) (xy 295.00449 -45.639736)
			(xy 294.995423 -45.682457) (xy 294.970051 -45.766028) (xy 294.936612 -45.84671) (xy 294.895425 -45.923726)
			(xy 294.846889 -45.996335) (xy 294.79147 -46.063838) (xy 294.729702 -46.125584) (xy 294.66218 -46.180979)
			(xy 294.589554 -46.229489) (xy 294.512523 -46.270648) (xy 294.431829 -46.304058) (xy 294.348248 -46.3294)
			(xy 294.262587 -46.346427) (xy 294.175669 -46.354977) (xy 294.132 -46.355508) (xy 294.090898 -46.355033)
			(xy 294.009043 -46.347448) (xy 293.928238 -46.332343) (xy 293.849171 -46.309847) (xy 293.772517 -46.280151)
			(xy 293.69893 -46.243509) (xy 293.629038 -46.200234) (xy 293.563437 -46.150694) (xy 293.502687 -46.095313)
			(xy 293.447306 -46.034563) (xy 293.397766 -45.968962) (xy 293.354491 -45.89907) (xy 293.317849 -45.825483)
			(xy 293.288153 -45.748829) (xy 293.265657 -45.669762) (xy 293.250552 -45.588957) (xy 293.242967 -45.507102)
			(xy 293.242492 -45.466) (xy 0.509016 -45.466) (xy 0.509016 -46.6242) (xy 288.755312 -46.6242) (xy 288.759342 -46.539599)
			(xy 288.771396 -46.455763) (xy 288.791365 -46.373454) (xy 288.819068 -46.293415) (xy 288.854253 -46.216372)
			(xy 288.896603 -46.143023) (xy 288.945734 -46.074031) (xy 289.0012 -46.010023) (xy 289.0625 -45.951576)
			(xy 289.129078 -45.899222) (xy 289.200331 -45.853433) (xy 289.275615 -45.814625) (xy 289.354246 -45.783149)
			(xy 289.435514 -45.759291) (xy 289.518681 -45.743265) (xy 289.602995 -45.735218) (xy 289.645344 -45.734732)
			(xy 289.684496 -45.735134) (xy 289.7625 -45.741969) (xy 289.8396 -45.755642) (xy 289.915198 -45.776048)
			(xy 289.988706 -45.803028) (xy 290.024312 -45.819314) (xy 290.034699 -45.823549) (xy 290.057105 -45.823549)
			(xy 290.067492 -45.819314) (xy 290.103097 -45.80303) (xy 290.176614 -45.77608) (xy 290.252213 -45.755686)
			(xy 290.32931 -45.742008) (xy 290.407309 -45.735149) (xy 290.44646 -45.734732) (xy 290.488812 -45.735138)
			(xy 290.573134 -45.743186) (xy 290.656308 -45.759214) (xy 290.737583 -45.783075) (xy 290.816221 -45.814554)
			(xy 290.891511 -45.853365) (xy 290.96277 -45.899158) (xy 291.029354 -45.951517) (xy 291.090659 -46.009969)
			(xy 291.14613 -46.073983) (xy 291.195265 -46.142981) (xy 291.237618 -46.216336) (xy 291.272807 -46.293386)
			(xy 291.300512 -46.373432) (xy 291.320482 -46.455749) (xy 291.332537 -46.539591) (xy 291.336568 -46.6242)
			(xy 291.332537 -46.708809) (xy 291.320482 -46.792651) (xy 291.300512 -46.874968) (xy 291.272807 -46.955014)
			(xy 291.237618 -47.032064) (xy 291.195265 -47.105419) (xy 291.14613 -47.174417) (xy 291.090659 -47.238431)
			(xy 291.029354 -47.296883) (xy 290.96277 -47.349242) (xy 290.891511 -47.395035) (xy 290.85596 -47.413361)
			(xy 291.845742 -47.413361) (xy 291.845742 -47.328639) (xy 291.853795 -47.244302) (xy 291.869829 -47.161112)
			(xy 291.893697 -47.079822) (xy 291.925185 -47.00117) (xy 291.964007 -46.925867) (xy 292.00981 -46.854595)
			(xy 292.062181 -46.787999) (xy 292.120646 -46.726684) (xy 292.184674 -46.671203) (xy 292.253686 -46.62206)
			(xy 292.327056 -46.5797) (xy 292.404121 -46.544505) (xy 292.484183 -46.516796) (xy 292.566516 -46.496822)
			(xy 292.650375 -46.484765) (xy 292.735 -46.480734) (xy 292.819625 -46.484765) (xy 292.903484 -46.496822)
			(xy 292.985817 -46.516796) (xy 293.065879 -46.544505) (xy 293.142944 -46.5797) (xy 293.216314 -46.62206)
			(xy 293.285326 -46.671203) (xy 293.349354 -46.726684) (xy 293.407819 -46.787999) (xy 293.46019 -46.854595)
			(xy 293.505993 -46.925867) (xy 293.544815 -47.00117) (xy 293.576303 -47.079822) (xy 293.600171 -47.161112)
			(xy 293.616205 -47.244302) (xy 293.624258 -47.328639) (xy 293.624762 -47.371) (xy 293.624258 -47.413361)
			(xy 293.616205 -47.497698) (xy 293.600171 -47.580888) (xy 293.576303 -47.662178) (xy 293.544815 -47.74083)
			(xy 293.505993 -47.816133) (xy 293.46019 -47.887405) (xy 293.407819 -47.954001) (xy 293.349354 -48.015316)
			(xy 293.285326 -48.070797) (xy 293.216314 -48.11994) (xy 293.142944 -48.1623) (xy 293.065879 -48.197495)
			(xy 292.985817 -48.225204) (xy 292.903484 -48.245178) (xy 292.819625 -48.257235) (xy 292.735 -48.261267)
			(xy 292.650375 -48.257235) (xy 292.566516 -48.245178) (xy 292.484183 -48.225204) (xy 292.404121 -48.197495)
			(xy 292.327056 -48.1623) (xy 292.253686 -48.11994) (xy 292.184674 -48.070797) (xy 292.120646 -48.015316)
			(xy 292.062181 -47.954001) (xy 292.00981 -47.887405) (xy 291.964007 -47.816133) (xy 291.925185 -47.74083)
			(xy 291.893697 -47.662178) (xy 291.869829 -47.580888) (xy 291.853795 -47.497698) (xy 291.845742 -47.413361)
			(xy 290.85596 -47.413361) (xy 290.816221 -47.433846) (xy 290.737583 -47.465325) (xy 290.656308 -47.489186)
			(xy 290.573134 -47.505214) (xy 290.488812 -47.513262) (xy 290.44646 -47.513748) (xy 290.407308 -47.513346)
			(xy 290.329304 -47.506512) (xy 290.252204 -47.492839) (xy 290.176606 -47.472433) (xy 290.103098 -47.445452)
			(xy 290.067492 -47.429166) (xy 290.057105 -47.424931) (xy 290.034699 -47.424931) (xy 290.024312 -47.429166)
			(xy 289.988705 -47.445448) (xy 289.915189 -47.472398) (xy 289.839591 -47.492792) (xy 289.762494 -47.506472)
			(xy 289.684494 -47.513331) (xy 289.645344 -47.513748) (xy 289.602995 -47.513182) (xy 289.518681 -47.505135)
			(xy 289.435514 -47.489109) (xy 289.354246 -47.465251) (xy 289.275615 -47.433775) (xy 289.200331 -47.394967)
			(xy 289.129078 -47.349178) (xy 289.0625 -47.296824) (xy 289.0012 -47.238377) (xy 288.945734 -47.174369)
			(xy 288.896603 -47.105377) (xy 288.854253 -47.032028) (xy 288.819068 -46.954985) (xy 288.791365 -46.874946)
			(xy 288.771396 -46.792637) (xy 288.759342 -46.708801) (xy 288.755312 -46.6242) (xy 0.509016 -46.6242)
			(xy 0.509016 -48.327818) (xy 257.330448 -48.327818) (xy 257.331032 -48.281422) (xy 257.340676 -48.189134)
			(xy 257.359872 -48.09835) (xy 257.38841 -48.010057) (xy 257.406648 -47.967392) (xy 257.410445 -47.957447)
			(xy 257.410452 -47.936186) (xy 257.406648 -47.926244) (xy 257.388413 -47.883578) (xy 257.359865 -47.795287)
			(xy 257.340669 -47.704503) (xy 257.331034 -47.612214) (xy 257.330448 -47.565818) (xy 257.330952 -47.52347)
			(xy 257.339003 -47.439156) (xy 257.355032 -47.35599) (xy 257.378893 -47.274723) (xy 257.410372 -47.196093)
			(xy 257.449183 -47.120812) (xy 257.494973 -47.04956) (xy 257.547329 -46.982984) (xy 257.605777 -46.921686)
			(xy 257.669787 -46.866221) (xy 257.738779 -46.817092) (xy 257.812129 -46.774743) (xy 257.889172 -46.739559)
			(xy 257.969211 -46.711857) (xy 258.05152 -46.691889) (xy 258.135355 -46.679836) (xy 258.219956 -46.675806)
			(xy 258.304557 -46.679836) (xy 258.388392 -46.691889) (xy 258.470701 -46.711857) (xy 258.55074 -46.739559)
			(xy 258.627783 -46.774743) (xy 258.701133 -46.817092) (xy 258.770125 -46.866221) (xy 258.834135 -46.921686)
			(xy 258.892583 -46.982984) (xy 258.944939 -47.04956) (xy 258.990729 -47.120812) (xy 259.02954 -47.196093)
			(xy 259.061019 -47.274723) (xy 259.08488 -47.35599) (xy 259.100909 -47.439156) (xy 259.10896 -47.52347)
			(xy 259.109464 -47.565818) (xy 259.108891 -47.612214) (xy 259.099244 -47.704503) (xy 259.080045 -47.795286)
			(xy 259.051504 -47.88358) (xy 259.033264 -47.926244) (xy 259.029445 -47.936182) (xy 259.029452 -47.95745)
			(xy 259.033264 -47.967392) (xy 259.051512 -48.010053) (xy 259.080056 -48.098346) (xy 259.099248 -48.189131)
			(xy 259.10888 -48.281422) (xy 259.109464 -48.327818) (xy 259.10896 -48.370166) (xy 259.100909 -48.45448)
			(xy 259.08488 -48.537646) (xy 259.061019 -48.618913) (xy 259.02954 -48.697543) (xy 258.990729 -48.772824)
			(xy 258.944939 -48.844076) (xy 258.892583 -48.910652) (xy 258.834135 -48.97195) (xy 258.770125 -49.027415)
			(xy 258.701133 -49.076544) (xy 258.627783 -49.118893) (xy 258.55074 -49.154077) (xy 258.470701 -49.181779)
			(xy 258.388392 -49.201747) (xy 258.304557 -49.2138) (xy 258.219956 -49.217831) (xy 258.135355 -49.2138)
			(xy 258.05152 -49.201747) (xy 257.969211 -49.181779) (xy 257.889172 -49.154077) (xy 257.812129 -49.118893)
			(xy 257.738779 -49.076544) (xy 257.669787 -49.027415) (xy 257.605777 -48.97195) (xy 257.547329 -48.910652)
			(xy 257.494973 -48.844076) (xy 257.449183 -48.772824) (xy 257.410372 -48.697543) (xy 257.378893 -48.618913)
			(xy 257.355032 -48.537646) (xy 257.339003 -48.45448) (xy 257.330952 -48.370166) (xy 257.330448 -48.327818)
			(xy 0.509016 -48.327818) (xy 0.509016 -52.2859) (xy 43.474132 -52.2859) (xy 43.47455 -52.246133)
			(xy 43.48159 -52.166911) (xy 43.495677 -52.088634) (xy 43.516699 -52.011928) (xy 43.544486 -51.937406)
			(xy 43.561254 -51.901344) (xy 43.565585 -51.890843) (xy 43.565585 -51.868157) (xy 43.561254 -51.857656)
			(xy 43.544513 -51.821583) (xy 43.516732 -51.74706) (xy 43.495709 -51.670357) (xy 43.481612 -51.592084)
			(xy 43.474554 -51.512866) (xy 43.474132 -51.4731) (xy 43.474546 -51.432489) (xy 43.481951 -51.351605)
			(xy 43.496699 -51.271733) (xy 43.518668 -51.193537) (xy 43.547674 -51.117671) (xy 43.583475 -51.044765)
			(xy 43.625775 -50.975426) (xy 43.674219 -50.910233) (xy 43.728406 -50.849727) (xy 43.787882 -50.794414)
			(xy 43.852155 -50.744753) (xy 43.920686 -50.701159) (xy 43.992907 -50.663994) (xy 44.030392 -50.648362)
			(xy 44.040552 -50.644044) (xy 44.055792 -50.628042) (xy 44.087796 -50.534062) (xy 44.08551 -50.511964)
			(xy 44.079922 -50.502566) (xy 44.060228 -50.46832) (xy 44.026305 -50.396969) (xy 43.998845 -50.322889)
			(xy 43.978066 -50.246665) (xy 43.96413 -50.168899) (xy 43.957148 -50.090203) (xy 43.956732 -50.0507)
			(xy 43.957152 -50.009596) (xy 43.964738 -49.927738) (xy 43.979844 -49.846929) (xy 44.002342 -49.767859)
			(xy 44.03204 -49.691202) (xy 44.068685 -49.617612) (xy 44.111963 -49.547717) (xy 44.161506 -49.482114)
			(xy 44.216891 -49.421363) (xy 44.277645 -49.36598) (xy 44.34325 -49.31644) (xy 44.413147 -49.273165)
			(xy 44.486738 -49.236524) (xy 44.563397 -49.206829) (xy 44.642468 -49.184335) (xy 44.723277 -49.169232)
			(xy 44.805136 -49.16165) (xy 44.84624 -49.161192) (xy 44.891005 -49.161711) (xy 44.980087 -49.170644)
			(xy 45.06782 -49.188486) (xy 45.153315 -49.215055) (xy 45.194728 -49.232058) (xy 45.204319 -49.235623)
			(xy 45.224761 -49.235623) (xy 45.234352 -49.232058) (xy 45.275769 -49.215065) (xy 45.361266 -49.188508)
			(xy 45.448997 -49.170667) (xy 45.538076 -49.161723) (xy 45.58284 -49.161192) (xy 45.625958 -49.161716)
			(xy 45.71179 -49.170059) (xy 45.796411 -49.186672) (xy 45.879027 -49.211399) (xy 45.919136 -49.227232)
			(xy 45.928507 -49.230558) (xy 45.948373 -49.230558) (xy 45.957744 -49.227232) (xy 45.997848 -49.211383)
			(xy 46.080465 -49.186656) (xy 46.165087 -49.170043) (xy 46.250921 -49.161699) (xy 46.29404 -49.161192)
			(xy 46.336388 -49.161696) (xy 46.420702 -49.169747) (xy 46.503868 -49.185776) (xy 46.585135 -49.209637)
			(xy 46.663765 -49.241116) (xy 46.739046 -49.279927) (xy 46.810298 -49.325717) (xy 46.876874 -49.378073)
			(xy 46.938172 -49.436521) (xy 46.993637 -49.500531) (xy 47.042766 -49.569523) (xy 47.085115 -49.642873)
			(xy 47.120299 -49.719916) (xy 47.148001 -49.799955) (xy 47.167969 -49.882264) (xy 47.180022 -49.966099)
			(xy 47.184053 -50.0507) (xy 47.180022 -50.135301) (xy 47.167969 -50.219136) (xy 47.148001 -50.301445)
			(xy 47.120299 -50.381484) (xy 47.085115 -50.458527) (xy 47.042766 -50.531877) (xy 46.993637 -50.600869)
			(xy 46.938172 -50.664879) (xy 46.876874 -50.723327) (xy 46.810298 -50.775683) (xy 46.739046 -50.821473)
			(xy 46.663765 -50.860284) (xy 46.585135 -50.891763) (xy 46.503868 -50.915624) (xy 46.420702 -50.931653)
			(xy 46.336388 -50.939704) (xy 46.29404 -50.940208) (xy 46.250922 -50.939691) (xy 46.165089 -50.931346)
			(xy 46.080468 -50.914731) (xy 45.997853 -50.890002) (xy 45.957744 -50.874168) (xy 45.948373 -50.870842)
			(xy 45.928507 -50.870842) (xy 45.919136 -50.874168) (xy 45.879023 -50.889992) (xy 45.796409 -50.914725)
			(xy 45.71179 -50.931346) (xy 45.625958 -50.939697) (xy 45.58284 -50.940208) (xy 45.538075 -50.939695)
			(xy 45.448993 -50.930761) (xy 45.36126 -50.912917) (xy 45.275765 -50.886346) (xy 45.234352 -50.869342)
			(xy 45.224761 -50.865777) (xy 45.204319 -50.865777) (xy 45.194728 -50.869342) (xy 45.179488 -50.875438)
			(xy 45.169328 -50.879756) (xy 45.154088 -50.895758) (xy 45.122084 -50.989738) (xy 45.12437 -51.011836)
			(xy 45.129958 -51.021234) (xy 45.14965 -51.055481) (xy 45.183574 -51.126832) (xy 45.211034 -51.200912)
			(xy 45.231814 -51.277135) (xy 45.24575 -51.354901) (xy 45.252732 -51.433597) (xy 45.253148 -51.4731)
			(xy 45.252732 -51.512867) (xy 45.245691 -51.59209) (xy 45.231604 -51.670366) (xy 45.210582 -51.747072)
			(xy 45.182794 -51.821594) (xy 45.166026 -51.857656) (xy 45.161691 -51.868157) (xy 45.161691 -51.890843)
			(xy 45.166026 -51.901344) (xy 45.182773 -51.937415) (xy 45.210551 -52.011938) (xy 45.231572 -52.088642)
			(xy 45.245668 -52.166915) (xy 45.252726 -52.246134) (xy 45.253148 -52.2859) (xy 45.252644 -52.328248)
			(xy 45.244593 -52.412562) (xy 45.228564 -52.495728) (xy 45.204703 -52.576995) (xy 45.173224 -52.655625)
			(xy 45.134413 -52.730906) (xy 45.088623 -52.802158) (xy 45.036267 -52.868734) (xy 44.986526 -52.9209)
			(xy 46.166532 -52.9209) (xy 46.167111 -52.874504) (xy 46.176757 -52.782216) (xy 46.195954 -52.691432)
			(xy 46.224493 -52.603139) (xy 46.242732 -52.560474) (xy 46.246541 -52.550532) (xy 46.246541 -52.529268)
			(xy 46.242732 -52.519326) (xy 46.22449 -52.476663) (xy 46.195944 -52.388371) (xy 46.176751 -52.297586)
			(xy 46.167117 -52.205296) (xy 46.166532 -52.1589) (xy 46.167036 -52.116552) (xy 46.175087 -52.032238)
			(xy 46.191116 -51.949072) (xy 46.214977 -51.867805) (xy 46.246456 -51.789175) (xy 46.285267 -51.713894)
			(xy 46.331057 -51.642642) (xy 46.383413 -51.576066) (xy 46.441861 -51.514768) (xy 46.505871 -51.459303)
			(xy 46.574863 -51.410174) (xy 46.648213 -51.367825) (xy 46.725256 -51.332641) (xy 46.805295 -51.304939)
			(xy 46.887604 -51.284971) (xy 46.971439 -51.272918) (xy 47.05604 -51.268888) (xy 47.140641 -51.272918)
			(xy 47.224476 -51.284971) (xy 47.306785 -51.304939) (xy 47.386824 -51.332641) (xy 47.463867 -51.367825)
			(xy 47.537217 -51.410174) (xy 47.606209 -51.459303) (xy 47.670219 -51.514768) (xy 47.728667 -51.576066)
			(xy 47.781023 -51.642642) (xy 47.826813 -51.713894) (xy 47.865624 -51.789175) (xy 47.897103 -51.867805)
			(xy 47.920964 -51.949072) (xy 47.936993 -52.032238) (xy 47.945044 -52.116552) (xy 47.945548 -52.1589)
			(xy 47.94497 -52.205296) (xy 47.935324 -52.297584) (xy 47.916127 -52.388368) (xy 47.887587 -52.476662)
			(xy 47.869348 -52.519326) (xy 47.86554 -52.529268) (xy 47.86554 -52.550532) (xy 47.869348 -52.560474)
			(xy 47.887595 -52.603135) (xy 47.916138 -52.691428) (xy 47.93533 -52.782213) (xy 47.944963 -52.874504)
			(xy 47.945068 -52.8828) (xy 48.427132 -52.8828) (xy 48.427711 -52.836404) (xy 48.437357 -52.744116)
			(xy 48.456554 -52.653332) (xy 48.485093 -52.565039) (xy 48.503332 -52.522374) (xy 48.507141 -52.512432)
			(xy 48.507141 -52.491168) (xy 48.503332 -52.481226) (xy 48.48509 -52.438563) (xy 48.456544 -52.350271)
			(xy 48.437351 -52.259486) (xy 48.427717 -52.167196) (xy 48.427132 -52.1208) (xy 48.427552 -52.079696)
			(xy 48.435138 -51.997838) (xy 48.450244 -51.917029) (xy 48.472742 -51.837959) (xy 48.50244 -51.761302)
			(xy 48.539085 -51.687712) (xy 48.582363 -51.617817) (xy 48.631906 -51.552214) (xy 48.687291 -51.491463)
			(xy 48.748045 -51.43608) (xy 48.81365 -51.38654) (xy 48.883547 -51.343265) (xy 48.957138 -51.306624)
			(xy 49.033797 -51.276929) (xy 49.112868 -51.254435) (xy 49.193677 -51.239332) (xy 49.275536 -51.23175)
			(xy 49.31664 -51.231292) (xy 49.363035 -51.231896) (xy 49.455323 -51.241535) (xy 49.546107 -51.260725)
			(xy 49.634401 -51.289257) (xy 49.677066 -51.307492) (xy 49.687008 -51.311298) (xy 49.708272 -51.311298)
			(xy 49.718214 -51.307492) (xy 49.760871 -51.289234) (xy 49.849165 -51.260693) (xy 49.939952 -51.241504)
			(xy 50.032243 -51.231875) (xy 50.07864 -51.231292) (xy 50.125035 -51.231896) (xy 50.217323 -51.241535)
			(xy 50.308107 -51.260725) (xy 50.396401 -51.289257) (xy 50.439066 -51.307492) (xy 50.449008 -51.311298)
			(xy 50.470272 -51.311298) (xy 50.480214 -51.307492) (xy 50.522871 -51.289234) (xy 50.611165 -51.260693)
			(xy 50.701952 -51.241504) (xy 50.794243 -51.231875) (xy 50.84064 -51.231292) (xy 50.881743 -51.231728)
			(xy 50.963598 -51.239317) (xy 51.044404 -51.254426) (xy 51.123472 -51.276925) (xy 51.200126 -51.306624)
			(xy 51.273713 -51.343269) (xy 51.343605 -51.386547) (xy 51.409206 -51.436089) (xy 51.469955 -51.491473)
			(xy 51.525336 -51.552225) (xy 51.574875 -51.617828) (xy 51.61815 -51.687722) (xy 51.654792 -51.761311)
			(xy 51.684487 -51.837966) (xy 51.706984 -51.917034) (xy 51.722089 -51.997841) (xy 51.729673 -52.079697)
			(xy 51.730148 -52.1208) (xy 51.72957 -52.167196) (xy 51.719924 -52.259484) (xy 51.706282 -52.324)
			(xy 70.992492 -52.324) (xy 70.99288 -52.285716) (xy 70.999419 -52.209427) (xy 71.0125 -52.133985)
			(xy 71.032027 -52.059948) (xy 71.044562 -52.023772) (xy 71.047213 -52.015335) (xy 71.047213 -51.997665)
			(xy 71.044562 -51.989228) (xy 71.032037 -51.95305) (xy 71.012529 -51.87901) (xy 70.999449 -51.803569)
			(xy 70.992894 -51.727283) (xy 70.992492 -51.689) (xy 70.992943 -51.648953) (xy 71.000117 -51.569181)
			(xy 71.014434 -51.490378) (xy 71.035778 -51.413181) (xy 71.063976 -51.338215) (xy 71.0988 -51.266088)
			(xy 71.139968 -51.197385) (xy 71.187146 -51.13266) (xy 71.213218 -51.10226) (xy 71.218983 -51.095171)
			(xy 71.225495 -51.078114) (xy 71.225918 -51.068986) (xy 71.225918 -51.039014) (xy 71.225484 -51.029891)
			(xy 71.218964 -51.012841) (xy 71.213218 -51.00574) (xy 71.187158 -50.975329) (xy 71.139979 -50.910606)
			(xy 71.098809 -50.841904) (xy 71.063981 -50.769779) (xy 71.035779 -50.694815) (xy 71.014429 -50.61762)
			(xy 71.000105 -50.538818) (xy 70.992923 -50.459047) (xy 70.992492 -50.419) (xy 70.99288 -50.380716)
			(xy 70.999419 -50.304427) (xy 71.0125 -50.228985) (xy 71.032027 -50.154948) (xy 71.044562 -50.118772)
			(xy 71.047213 -50.110335) (xy 71.047213 -50.092665) (xy 71.044562 -50.084228) (xy 71.032037 -50.04805)
			(xy 71.012529 -49.97401) (xy 70.999449 -49.898569) (xy 70.992894 -49.822283) (xy 70.992492 -49.784)
			(xy 70.992996 -49.741652) (xy 71.001047 -49.657338) (xy 71.017076 -49.574172) (xy 71.040937 -49.492905)
			(xy 71.072416 -49.414275) (xy 71.111227 -49.338994) (xy 71.157017 -49.267742) (xy 71.209373 -49.201166)
			(xy 71.267821 -49.139868) (xy 71.331831 -49.084403) (xy 71.400823 -49.035274) (xy 71.474173 -48.992925)
			(xy 71.551216 -48.957741) (xy 71.631255 -48.930039) (xy 71.713564 -48.910071) (xy 71.797399 -48.898018)
			(xy 71.882 -48.893988) (xy 71.966601 -48.898018) (xy 72.050436 -48.910071) (xy 72.132745 -48.930039)
			(xy 72.212784 -48.957741) (xy 72.289827 -48.992925) (xy 72.363177 -49.035274) (xy 72.432169 -49.084403)
			(xy 72.496179 -49.139868) (xy 72.554627 -49.201166) (xy 72.606983 -49.267742) (xy 72.652773 -49.338994)
			(xy 72.691584 -49.414275) (xy 72.723063 -49.492905) (xy 72.746924 -49.574172) (xy 72.762953 -49.657338)
			(xy 72.771004 -49.741652) (xy 72.771508 -49.784) (xy 72.77112 -49.822284) (xy 72.764581 -49.898573)
			(xy 72.7515 -49.974015) (xy 72.731973 -50.048052) (xy 72.719438 -50.084228) (xy 72.716787 -50.092665)
			(xy 72.716787 -50.110335) (xy 72.719438 -50.118772) (xy 72.731963 -50.15495) (xy 72.751471 -50.22899)
			(xy 72.764551 -50.304431) (xy 72.771106 -50.380717) (xy 72.771508 -50.419) (xy 72.771057 -50.459047)
			(xy 72.763883 -50.538819) (xy 72.749566 -50.617622) (xy 72.728222 -50.694819) (xy 72.700024 -50.769785)
			(xy 72.6652 -50.841912) (xy 72.624032 -50.910615) (xy 72.576854 -50.97534) (xy 72.550782 -51.00574)
			(xy 72.545017 -51.012829) (xy 72.538505 -51.029886) (xy 72.538082 -51.039014) (xy 72.538082 -51.068986)
			(xy 72.538516 -51.078109) (xy 72.545036 -51.095159) (xy 72.550782 -51.10226) (xy 72.576842 -51.132671)
			(xy 72.624021 -51.197394) (xy 72.665191 -51.266096) (xy 72.700019 -51.338221) (xy 72.728221 -51.413185)
			(xy 72.749571 -51.49038) (xy 72.763895 -51.569182) (xy 72.771077 -51.648953) (xy 72.771508 -51.689)
			(xy 72.77112 -51.727284) (xy 72.764581 -51.803573) (xy 72.7515 -51.879015) (xy 72.731973 -51.953052)
			(xy 72.719438 -51.989228) (xy 72.716787 -51.997665) (xy 72.716787 -52.015335) (xy 72.719438 -52.023772)
			(xy 72.731963 -52.05995) (xy 72.751471 -52.13399) (xy 72.764551 -52.209431) (xy 72.771106 -52.285717)
			(xy 72.771508 -52.324) (xy 76.453492 -52.324) (xy 76.45388 -52.285716) (xy 76.460419 -52.209427)
			(xy 76.4735 -52.133985) (xy 76.493027 -52.059948) (xy 76.505562 -52.023772) (xy 76.508213 -52.015335)
			(xy 76.508213 -51.997665) (xy 76.505562 -51.989228) (xy 76.493037 -51.95305) (xy 76.473529 -51.87901)
			(xy 76.460449 -51.803569) (xy 76.453894 -51.727283) (xy 76.453492 -51.689) (xy 76.453943 -51.648953)
			(xy 76.461117 -51.569181) (xy 76.475434 -51.490378) (xy 76.496778 -51.413181) (xy 76.524976 -51.338215)
			(xy 76.5598 -51.266088) (xy 76.600968 -51.197385) (xy 76.648146 -51.13266) (xy 76.674218 -51.10226)
			(xy 76.679983 -51.095171) (xy 76.686495 -51.078114) (xy 76.686918 -51.068986) (xy 76.686918 -51.039014)
			(xy 76.686484 -51.029891) (xy 76.679964 -51.012841) (xy 76.674218 -51.00574) (xy 76.648158 -50.975329)
			(xy 76.600979 -50.910606) (xy 76.559809 -50.841904) (xy 76.524981 -50.769779) (xy 76.496779 -50.694815)
			(xy 76.475429 -50.61762) (xy 76.461105 -50.538818) (xy 76.453923 -50.459047) (xy 76.453492 -50.419)
			(xy 76.45388 -50.380716) (xy 76.460419 -50.304427) (xy 76.4735 -50.228985) (xy 76.493027 -50.154948)
			(xy 76.505562 -50.118772) (xy 76.508213 -50.110335) (xy 76.508213 -50.092665) (xy 76.505562 -50.084228)
			(xy 76.493037 -50.04805) (xy 76.473529 -49.97401) (xy 76.460449 -49.898569) (xy 76.453894 -49.822283)
			(xy 76.453492 -49.784) (xy 76.453996 -49.741652) (xy 76.462047 -49.657338) (xy 76.478076 -49.574172)
			(xy 76.501937 -49.492905) (xy 76.533416 -49.414275) (xy 76.572227 -49.338994) (xy 76.618017 -49.267742)
			(xy 76.670373 -49.201166) (xy 76.728821 -49.139868) (xy 76.792831 -49.084403) (xy 76.861823 -49.035274)
			(xy 76.935173 -48.992925) (xy 77.012216 -48.957741) (xy 77.092255 -48.930039) (xy 77.174564 -48.910071)
			(xy 77.258399 -48.898018) (xy 77.343 -48.893988) (xy 77.427601 -48.898018) (xy 77.511436 -48.910071)
			(xy 77.593745 -48.930039) (xy 77.673784 -48.957741) (xy 77.750827 -48.992925) (xy 77.824177 -49.035274)
			(xy 77.893169 -49.084403) (xy 77.957179 -49.139868) (xy 78.015627 -49.201166) (xy 78.067983 -49.267742)
			(xy 78.113773 -49.338994) (xy 78.152584 -49.414275) (xy 78.184063 -49.492905) (xy 78.207924 -49.574172)
			(xy 78.223953 -49.657338) (xy 78.232004 -49.741652) (xy 78.232508 -49.784) (xy 78.23212 -49.822284)
			(xy 78.225581 -49.898573) (xy 78.2125 -49.974015) (xy 78.192973 -50.048052) (xy 78.180438 -50.084228)
			(xy 78.177787 -50.092665) (xy 78.177787 -50.110335) (xy 78.180438 -50.118772) (xy 78.192963 -50.15495)
			(xy 78.212471 -50.22899) (xy 78.225551 -50.304431) (xy 78.232106 -50.380717) (xy 78.232508 -50.419)
			(xy 78.232057 -50.459047) (xy 78.224883 -50.538819) (xy 78.210566 -50.617622) (xy 78.189222 -50.694819)
			(xy 78.161024 -50.769785) (xy 78.1262 -50.841912) (xy 78.085032 -50.910615) (xy 78.037854 -50.97534)
			(xy 78.011782 -51.00574) (xy 78.006017 -51.012829) (xy 77.999505 -51.029886) (xy 77.999082 -51.039014)
			(xy 77.999082 -51.068986) (xy 77.999516 -51.078109) (xy 78.006036 -51.095159) (xy 78.011782 -51.10226)
			(xy 78.037842 -51.132671) (xy 78.085021 -51.197394) (xy 78.126191 -51.266096) (xy 78.161019 -51.338221)
			(xy 78.189221 -51.413185) (xy 78.210571 -51.49038) (xy 78.224895 -51.569182) (xy 78.232077 -51.648953)
			(xy 78.232508 -51.689) (xy 78.23212 -51.727284) (xy 78.225581 -51.803573) (xy 78.2125 -51.879015)
			(xy 78.192973 -51.953052) (xy 78.180438 -51.989228) (xy 78.177787 -51.997665) (xy 78.177787 -52.015335)
			(xy 78.180438 -52.023772) (xy 78.192963 -52.05995) (xy 78.212471 -52.13399) (xy 78.225551 -52.209431)
			(xy 78.232106 -52.285717) (xy 78.232508 -52.324) (xy 81.914492 -52.324) (xy 81.91488 -52.285716)
			(xy 81.921419 -52.209427) (xy 81.9345 -52.133985) (xy 81.954027 -52.059948) (xy 81.966562 -52.023772)
			(xy 81.969213 -52.015335) (xy 81.969213 -51.997665) (xy 81.966562 -51.989228) (xy 81.954037 -51.95305)
			(xy 81.934529 -51.87901) (xy 81.921449 -51.803569) (xy 81.914894 -51.727283) (xy 81.914492 -51.689)
			(xy 81.914943 -51.648953) (xy 81.922117 -51.569181) (xy 81.936434 -51.490378) (xy 81.957778 -51.413181)
			(xy 81.985976 -51.338215) (xy 82.0208 -51.266088) (xy 82.061968 -51.197385) (xy 82.109146 -51.13266)
			(xy 82.135218 -51.10226) (xy 82.140983 -51.095171) (xy 82.147495 -51.078114) (xy 82.147918 -51.068986)
			(xy 82.147918 -51.039014) (xy 82.147484 -51.029891) (xy 82.140964 -51.012841) (xy 82.135218 -51.00574)
			(xy 82.109158 -50.975329) (xy 82.061979 -50.910606) (xy 82.020809 -50.841904) (xy 81.985981 -50.769779)
			(xy 81.957779 -50.694815) (xy 81.936429 -50.61762) (xy 81.922105 -50.538818) (xy 81.914923 -50.459047)
			(xy 81.914492 -50.419) (xy 81.91488 -50.380716) (xy 81.921419 -50.304427) (xy 81.9345 -50.228985)
			(xy 81.954027 -50.154948) (xy 81.966562 -50.118772) (xy 81.969213 -50.110335) (xy 81.969213 -50.092665)
			(xy 81.966562 -50.084228) (xy 81.954037 -50.04805) (xy 81.934529 -49.97401) (xy 81.921449 -49.898569)
			(xy 81.914894 -49.822283) (xy 81.914492 -49.784) (xy 81.914996 -49.741652) (xy 81.923047 -49.657338)
			(xy 81.939076 -49.574172) (xy 81.962937 -49.492905) (xy 81.994416 -49.414275) (xy 82.033227 -49.338994)
			(xy 82.079017 -49.267742) (xy 82.131373 -49.201166) (xy 82.189821 -49.139868) (xy 82.253831 -49.084403)
			(xy 82.322823 -49.035274) (xy 82.396173 -48.992925) (xy 82.473216 -48.957741) (xy 82.553255 -48.930039)
			(xy 82.635564 -48.910071) (xy 82.719399 -48.898018) (xy 82.804 -48.893988) (xy 82.888601 -48.898018)
			(xy 82.972436 -48.910071) (xy 83.054745 -48.930039) (xy 83.134784 -48.957741) (xy 83.211827 -48.992925)
			(xy 83.285177 -49.035274) (xy 83.354169 -49.084403) (xy 83.418179 -49.139868) (xy 83.476627 -49.201166)
			(xy 83.528983 -49.267742) (xy 83.574773 -49.338994) (xy 83.613584 -49.414275) (xy 83.645063 -49.492905)
			(xy 83.668924 -49.574172) (xy 83.684953 -49.657338) (xy 83.693004 -49.741652) (xy 83.693508 -49.784)
			(xy 83.69312 -49.822284) (xy 83.686581 -49.898573) (xy 83.6735 -49.974015) (xy 83.653973 -50.048052)
			(xy 83.641438 -50.084228) (xy 83.638787 -50.092665) (xy 83.638787 -50.110335) (xy 83.641438 -50.118772)
			(xy 83.653963 -50.15495) (xy 83.673471 -50.22899) (xy 83.686551 -50.304431) (xy 83.693106 -50.380717)
			(xy 83.693508 -50.419) (xy 83.693057 -50.459047) (xy 83.685883 -50.538819) (xy 83.671566 -50.617622)
			(xy 83.650222 -50.694819) (xy 83.622024 -50.769785) (xy 83.5872 -50.841912) (xy 83.546032 -50.910615)
			(xy 83.498854 -50.97534) (xy 83.472782 -51.00574) (xy 83.467017 -51.012829) (xy 83.460505 -51.029886)
			(xy 83.460082 -51.039014) (xy 83.460082 -51.068986) (xy 83.460516 -51.078109) (xy 83.467036 -51.095159)
			(xy 83.472782 -51.10226) (xy 83.498842 -51.132671) (xy 83.546021 -51.197394) (xy 83.587191 -51.266096)
			(xy 83.622019 -51.338221) (xy 83.650221 -51.413185) (xy 83.671571 -51.49038) (xy 83.685895 -51.569182)
			(xy 83.693077 -51.648953) (xy 83.693508 -51.689) (xy 83.69312 -51.727284) (xy 83.686581 -51.803573)
			(xy 83.6735 -51.879015) (xy 83.653973 -51.953052) (xy 83.641438 -51.989228) (xy 83.638787 -51.997665)
			(xy 83.638787 -52.015335) (xy 83.641438 -52.023772) (xy 83.653963 -52.05995) (xy 83.673471 -52.13399)
			(xy 83.686551 -52.209431) (xy 83.693106 -52.285717) (xy 83.693508 -52.324) (xy 87.375492 -52.324)
			(xy 87.37588 -52.285716) (xy 87.382419 -52.209427) (xy 87.3955 -52.133985) (xy 87.415027 -52.059948)
			(xy 87.427562 -52.023772) (xy 87.430213 -52.015335) (xy 87.430213 -51.997665) (xy 87.427562 -51.989228)
			(xy 87.415037 -51.95305) (xy 87.395529 -51.87901) (xy 87.382449 -51.803569) (xy 87.375894 -51.727283)
			(xy 87.375492 -51.689) (xy 87.375943 -51.648953) (xy 87.383117 -51.569181) (xy 87.397434 -51.490378)
			(xy 87.418778 -51.413181) (xy 87.446976 -51.338215) (xy 87.4818 -51.266088) (xy 87.522968 -51.197385)
			(xy 87.570146 -51.13266) (xy 87.596218 -51.10226) (xy 87.601983 -51.095171) (xy 87.608495 -51.078114)
			(xy 87.608918 -51.068986) (xy 87.608918 -51.039014) (xy 87.608484 -51.029891) (xy 87.601964 -51.012841)
			(xy 87.596218 -51.00574) (xy 87.570158 -50.975329) (xy 87.522979 -50.910606) (xy 87.481809 -50.841904)
			(xy 87.446981 -50.769779) (xy 87.418779 -50.694815) (xy 87.397429 -50.61762) (xy 87.383105 -50.538818)
			(xy 87.375923 -50.459047) (xy 87.375492 -50.419) (xy 87.37588 -50.380716) (xy 87.382419 -50.304427)
			(xy 87.3955 -50.228985) (xy 87.415027 -50.154948) (xy 87.427562 -50.118772) (xy 87.430213 -50.110335)
			(xy 87.430213 -50.092665) (xy 87.427562 -50.084228) (xy 87.415037 -50.04805) (xy 87.395529 -49.97401)
			(xy 87.382449 -49.898569) (xy 87.375894 -49.822283) (xy 87.375492 -49.784) (xy 87.375996 -49.741652)
			(xy 87.384047 -49.657338) (xy 87.400076 -49.574172) (xy 87.423937 -49.492905) (xy 87.455416 -49.414275)
			(xy 87.494227 -49.338994) (xy 87.540017 -49.267742) (xy 87.592373 -49.201166) (xy 87.650821 -49.139868)
			(xy 87.714831 -49.084403) (xy 87.783823 -49.035274) (xy 87.857173 -48.992925) (xy 87.934216 -48.957741)
			(xy 88.014255 -48.930039) (xy 88.096564 -48.910071) (xy 88.180399 -48.898018) (xy 88.265 -48.893988)
			(xy 88.349601 -48.898018) (xy 88.433436 -48.910071) (xy 88.515745 -48.930039) (xy 88.595784 -48.957741)
			(xy 88.672827 -48.992925) (xy 88.746177 -49.035274) (xy 88.815169 -49.084403) (xy 88.879179 -49.139868)
			(xy 88.937627 -49.201166) (xy 88.989983 -49.267742) (xy 89.035773 -49.338994) (xy 89.074584 -49.414275)
			(xy 89.106063 -49.492905) (xy 89.129924 -49.574172) (xy 89.145953 -49.657338) (xy 89.154004 -49.741652)
			(xy 89.154508 -49.784) (xy 89.15412 -49.822284) (xy 89.147581 -49.898573) (xy 89.1345 -49.974015)
			(xy 89.114973 -50.048052) (xy 89.102438 -50.084228) (xy 89.099787 -50.092665) (xy 89.099787 -50.110335)
			(xy 89.102438 -50.118772) (xy 89.114963 -50.15495) (xy 89.134471 -50.22899) (xy 89.147551 -50.304431)
			(xy 89.154106 -50.380717) (xy 89.154508 -50.419) (xy 89.154057 -50.459047) (xy 89.146883 -50.538819)
			(xy 89.132566 -50.617622) (xy 89.111222 -50.694819) (xy 89.083024 -50.769785) (xy 89.0482 -50.841912)
			(xy 89.007032 -50.910615) (xy 88.959854 -50.97534) (xy 88.933782 -51.00574) (xy 88.928017 -51.012829)
			(xy 88.921505 -51.029886) (xy 88.921082 -51.039014) (xy 88.921082 -51.068986) (xy 88.921516 -51.078109)
			(xy 88.928036 -51.095159) (xy 88.933782 -51.10226) (xy 88.959842 -51.132671) (xy 89.007021 -51.197394)
			(xy 89.048191 -51.266096) (xy 89.083019 -51.338221) (xy 89.111221 -51.413185) (xy 89.132571 -51.49038)
			(xy 89.146895 -51.569182) (xy 89.154077 -51.648953) (xy 89.154508 -51.689) (xy 89.15412 -51.727284)
			(xy 89.147581 -51.803573) (xy 89.1345 -51.879015) (xy 89.114973 -51.953052) (xy 89.102438 -51.989228)
			(xy 89.099787 -51.997665) (xy 89.099787 -52.015335) (xy 89.102438 -52.023772) (xy 89.114963 -52.05995)
			(xy 89.134471 -52.13399) (xy 89.147551 -52.209431) (xy 89.154106 -52.285717) (xy 89.154508 -52.324)
			(xy 92.836492 -52.324) (xy 92.83688 -52.285716) (xy 92.843419 -52.209427) (xy 92.8565 -52.133985)
			(xy 92.876027 -52.059948) (xy 92.888562 -52.023772) (xy 92.891213 -52.015335) (xy 92.891213 -51.997665)
			(xy 92.888562 -51.989228) (xy 92.876037 -51.95305) (xy 92.856529 -51.87901) (xy 92.843449 -51.803569)
			(xy 92.836894 -51.727283) (xy 92.836492 -51.689) (xy 92.836943 -51.648953) (xy 92.844117 -51.569181)
			(xy 92.858434 -51.490378) (xy 92.879778 -51.413181) (xy 92.907976 -51.338215) (xy 92.9428 -51.266088)
			(xy 92.983968 -51.197385) (xy 93.031146 -51.13266) (xy 93.057218 -51.10226) (xy 93.062983 -51.095171)
			(xy 93.069495 -51.078114) (xy 93.069918 -51.068986) (xy 93.069918 -51.039014) (xy 93.069484 -51.029891)
			(xy 93.062964 -51.012841) (xy 93.057218 -51.00574) (xy 93.031158 -50.975329) (xy 92.983979 -50.910606)
			(xy 92.942809 -50.841904) (xy 92.907981 -50.769779) (xy 92.879779 -50.694815) (xy 92.858429 -50.61762)
			(xy 92.844105 -50.538818) (xy 92.836923 -50.459047) (xy 92.836492 -50.419) (xy 92.83688 -50.380716)
			(xy 92.843419 -50.304427) (xy 92.8565 -50.228985) (xy 92.876027 -50.154948) (xy 92.888562 -50.118772)
			(xy 92.891213 -50.110335) (xy 92.891213 -50.092665) (xy 92.888562 -50.084228) (xy 92.876037 -50.04805)
			(xy 92.856529 -49.97401) (xy 92.843449 -49.898569) (xy 92.836894 -49.822283) (xy 92.836492 -49.784)
			(xy 92.836996 -49.741652) (xy 92.845047 -49.657338) (xy 92.861076 -49.574172) (xy 92.884937 -49.492905)
			(xy 92.916416 -49.414275) (xy 92.955227 -49.338994) (xy 93.001017 -49.267742) (xy 93.053373 -49.201166)
			(xy 93.111821 -49.139868) (xy 93.175831 -49.084403) (xy 93.244823 -49.035274) (xy 93.318173 -48.992925)
			(xy 93.395216 -48.957741) (xy 93.475255 -48.930039) (xy 93.557564 -48.910071) (xy 93.641399 -48.898018)
			(xy 93.726 -48.893988) (xy 93.810601 -48.898018) (xy 93.894436 -48.910071) (xy 93.976745 -48.930039)
			(xy 94.056784 -48.957741) (xy 94.133827 -48.992925) (xy 94.207177 -49.035274) (xy 94.276169 -49.084403)
			(xy 94.340179 -49.139868) (xy 94.398627 -49.201166) (xy 94.450983 -49.267742) (xy 94.496773 -49.338994)
			(xy 94.535584 -49.414275) (xy 94.567063 -49.492905) (xy 94.590924 -49.574172) (xy 94.606953 -49.657338)
			(xy 94.615004 -49.741652) (xy 94.615508 -49.784) (xy 94.61512 -49.822284) (xy 94.608581 -49.898573)
			(xy 94.5955 -49.974015) (xy 94.575973 -50.048052) (xy 94.563438 -50.084228) (xy 94.560787 -50.092665)
			(xy 94.560787 -50.110335) (xy 94.563438 -50.118772) (xy 94.575963 -50.15495) (xy 94.595471 -50.22899)
			(xy 94.608551 -50.304431) (xy 94.615106 -50.380717) (xy 94.615508 -50.419) (xy 94.615057 -50.459047)
			(xy 94.607883 -50.538819) (xy 94.593566 -50.617622) (xy 94.572222 -50.694819) (xy 94.544024 -50.769785)
			(xy 94.5092 -50.841912) (xy 94.468032 -50.910615) (xy 94.420854 -50.97534) (xy 94.394782 -51.00574)
			(xy 94.389017 -51.012829) (xy 94.382505 -51.029886) (xy 94.382082 -51.039014) (xy 94.382082 -51.068986)
			(xy 94.382516 -51.078109) (xy 94.389036 -51.095159) (xy 94.394782 -51.10226) (xy 94.420842 -51.132671)
			(xy 94.468021 -51.197394) (xy 94.509191 -51.266096) (xy 94.544019 -51.338221) (xy 94.572221 -51.413185)
			(xy 94.593571 -51.49038) (xy 94.607895 -51.569182) (xy 94.615077 -51.648953) (xy 94.615508 -51.689)
			(xy 94.61512 -51.727284) (xy 94.608581 -51.803573) (xy 94.5955 -51.879015) (xy 94.575973 -51.953052)
			(xy 94.563438 -51.989228) (xy 94.560787 -51.997665) (xy 94.560787 -52.015335) (xy 94.563438 -52.023772)
			(xy 94.575963 -52.05995) (xy 94.595471 -52.13399) (xy 94.608551 -52.209431) (xy 94.615106 -52.285717)
			(xy 94.615508 -52.324) (xy 98.297492 -52.324) (xy 98.29788 -52.285716) (xy 98.304419 -52.209427)
			(xy 98.3175 -52.133985) (xy 98.337027 -52.059948) (xy 98.349562 -52.023772) (xy 98.352213 -52.015335)
			(xy 98.352213 -51.997665) (xy 98.349562 -51.989228) (xy 98.337037 -51.95305) (xy 98.317529 -51.87901)
			(xy 98.304449 -51.803569) (xy 98.297894 -51.727283) (xy 98.297492 -51.689) (xy 98.297943 -51.648953)
			(xy 98.305117 -51.569181) (xy 98.319434 -51.490378) (xy 98.340778 -51.413181) (xy 98.368976 -51.338215)
			(xy 98.4038 -51.266088) (xy 98.444968 -51.197385) (xy 98.492146 -51.13266) (xy 98.518218 -51.10226)
			(xy 98.523983 -51.095171) (xy 98.530495 -51.078114) (xy 98.530918 -51.068986) (xy 98.530918 -51.039014)
			(xy 98.530484 -51.029891) (xy 98.523964 -51.012841) (xy 98.518218 -51.00574) (xy 98.492158 -50.975329)
			(xy 98.444979 -50.910606) (xy 98.403809 -50.841904) (xy 98.368981 -50.769779) (xy 98.340779 -50.694815)
			(xy 98.319429 -50.61762) (xy 98.305105 -50.538818) (xy 98.297923 -50.459047) (xy 98.297492 -50.419)
			(xy 98.29788 -50.380716) (xy 98.304419 -50.304427) (xy 98.3175 -50.228985) (xy 98.337027 -50.154948)
			(xy 98.349562 -50.118772) (xy 98.352213 -50.110335) (xy 98.352213 -50.092665) (xy 98.349562 -50.084228)
			(xy 98.337037 -50.04805) (xy 98.317529 -49.97401) (xy 98.304449 -49.898569) (xy 98.297894 -49.822283)
			(xy 98.297492 -49.784) (xy 98.297996 -49.741652) (xy 98.306047 -49.657338) (xy 98.322076 -49.574172)
			(xy 98.345937 -49.492905) (xy 98.377416 -49.414275) (xy 98.416227 -49.338994) (xy 98.462017 -49.267742)
			(xy 98.514373 -49.201166) (xy 98.572821 -49.139868) (xy 98.636831 -49.084403) (xy 98.705823 -49.035274)
			(xy 98.779173 -48.992925) (xy 98.856216 -48.957741) (xy 98.936255 -48.930039) (xy 99.018564 -48.910071)
			(xy 99.102399 -48.898018) (xy 99.187 -48.893988) (xy 99.271601 -48.898018) (xy 99.355436 -48.910071)
			(xy 99.437745 -48.930039) (xy 99.517784 -48.957741) (xy 99.594827 -48.992925) (xy 99.668177 -49.035274)
			(xy 99.737169 -49.084403) (xy 99.801179 -49.139868) (xy 99.859627 -49.201166) (xy 99.911983 -49.267742)
			(xy 99.957773 -49.338994) (xy 99.996584 -49.414275) (xy 100.028063 -49.492905) (xy 100.051924 -49.574172)
			(xy 100.067953 -49.657338) (xy 100.076004 -49.741652) (xy 100.076508 -49.784) (xy 100.07612 -49.822284)
			(xy 100.069581 -49.898573) (xy 100.0565 -49.974015) (xy 100.036973 -50.048052) (xy 100.024438 -50.084228)
			(xy 100.021787 -50.092665) (xy 100.021787 -50.110335) (xy 100.024438 -50.118772) (xy 100.036963 -50.15495)
			(xy 100.056471 -50.22899) (xy 100.069551 -50.304431) (xy 100.076106 -50.380717) (xy 100.076508 -50.419)
			(xy 100.076057 -50.459047) (xy 100.068883 -50.538819) (xy 100.054566 -50.617622) (xy 100.033222 -50.694819)
			(xy 100.005024 -50.769785) (xy 99.9702 -50.841912) (xy 99.929032 -50.910615) (xy 99.881854 -50.97534)
			(xy 99.855782 -51.00574) (xy 99.850017 -51.012829) (xy 99.843505 -51.029886) (xy 99.843082 -51.039014)
			(xy 99.843082 -51.068986) (xy 99.843516 -51.078109) (xy 99.850036 -51.095159) (xy 99.855782 -51.10226)
			(xy 99.881842 -51.132671) (xy 99.929021 -51.197394) (xy 99.970191 -51.266096) (xy 100.005019 -51.338221)
			(xy 100.033221 -51.413185) (xy 100.054571 -51.49038) (xy 100.068895 -51.569182) (xy 100.076077 -51.648953)
			(xy 100.076508 -51.689) (xy 100.07612 -51.727284) (xy 100.069581 -51.803573) (xy 100.0565 -51.879015)
			(xy 100.036973 -51.953052) (xy 100.024438 -51.989228) (xy 100.021787 -51.997665) (xy 100.021787 -52.015335)
			(xy 100.024438 -52.023772) (xy 100.036963 -52.05995) (xy 100.056471 -52.13399) (xy 100.069551 -52.209431)
			(xy 100.076106 -52.285717) (xy 100.076508 -52.324) (xy 103.758492 -52.324) (xy 103.75888 -52.285716)
			(xy 103.765419 -52.209427) (xy 103.7785 -52.133985) (xy 103.798027 -52.059948) (xy 103.810562 -52.023772)
			(xy 103.813213 -52.015335) (xy 103.813213 -51.997665) (xy 103.810562 -51.989228) (xy 103.798037 -51.95305)
			(xy 103.778529 -51.87901) (xy 103.765449 -51.803569) (xy 103.758894 -51.727283) (xy 103.758492 -51.689)
			(xy 103.758943 -51.648953) (xy 103.766117 -51.569181) (xy 103.780434 -51.490378) (xy 103.801778 -51.413181)
			(xy 103.829976 -51.338215) (xy 103.8648 -51.266088) (xy 103.905968 -51.197385) (xy 103.953146 -51.13266)
			(xy 103.979218 -51.10226) (xy 103.984983 -51.095171) (xy 103.991495 -51.078114) (xy 103.991918 -51.068986)
			(xy 103.991918 -51.039014) (xy 103.991484 -51.029891) (xy 103.984964 -51.012841) (xy 103.979218 -51.00574)
			(xy 103.953158 -50.975329) (xy 103.905979 -50.910606) (xy 103.864809 -50.841904) (xy 103.829981 -50.769779)
			(xy 103.801779 -50.694815) (xy 103.780429 -50.61762) (xy 103.766105 -50.538818) (xy 103.758923 -50.459047)
			(xy 103.758492 -50.419) (xy 103.75888 -50.380716) (xy 103.765419 -50.304427) (xy 103.7785 -50.228985)
			(xy 103.798027 -50.154948) (xy 103.810562 -50.118772) (xy 103.813213 -50.110335) (xy 103.813213 -50.092665)
			(xy 103.810562 -50.084228) (xy 103.798037 -50.04805) (xy 103.778529 -49.97401) (xy 103.765449 -49.898569)
			(xy 103.758894 -49.822283) (xy 103.758492 -49.784) (xy 103.758996 -49.741652) (xy 103.767047 -49.657338)
			(xy 103.783076 -49.574172) (xy 103.806937 -49.492905) (xy 103.838416 -49.414275) (xy 103.877227 -49.338994)
			(xy 103.923017 -49.267742) (xy 103.975373 -49.201166) (xy 104.033821 -49.139868) (xy 104.097831 -49.084403)
			(xy 104.166823 -49.035274) (xy 104.240173 -48.992925) (xy 104.317216 -48.957741) (xy 104.397255 -48.930039)
			(xy 104.479564 -48.910071) (xy 104.563399 -48.898018) (xy 104.648 -48.893988) (xy 104.732601 -48.898018)
			(xy 104.816436 -48.910071) (xy 104.898745 -48.930039) (xy 104.978784 -48.957741) (xy 105.055827 -48.992925)
			(xy 105.129177 -49.035274) (xy 105.198169 -49.084403) (xy 105.262179 -49.139868) (xy 105.320627 -49.201166)
			(xy 105.372983 -49.267742) (xy 105.418773 -49.338994) (xy 105.457584 -49.414275) (xy 105.489063 -49.492905)
			(xy 105.512924 -49.574172) (xy 105.528953 -49.657338) (xy 105.537004 -49.741652) (xy 105.537508 -49.784)
			(xy 105.53712 -49.822284) (xy 105.530581 -49.898573) (xy 105.5175 -49.974015) (xy 105.497973 -50.048052)
			(xy 105.485438 -50.084228) (xy 105.482787 -50.092665) (xy 105.482787 -50.110335) (xy 105.485438 -50.118772)
			(xy 105.497963 -50.15495) (xy 105.517471 -50.22899) (xy 105.530551 -50.304431) (xy 105.537106 -50.380717)
			(xy 105.537508 -50.419) (xy 105.537057 -50.459047) (xy 105.529883 -50.538819) (xy 105.515566 -50.617622)
			(xy 105.494222 -50.694819) (xy 105.466024 -50.769785) (xy 105.4312 -50.841912) (xy 105.390032 -50.910615)
			(xy 105.342854 -50.97534) (xy 105.316782 -51.00574) (xy 105.311017 -51.012829) (xy 105.304505 -51.029886)
			(xy 105.304082 -51.039014) (xy 105.304082 -51.068986) (xy 105.304516 -51.078109) (xy 105.311036 -51.095159)
			(xy 105.316782 -51.10226) (xy 105.342842 -51.132671) (xy 105.390021 -51.197394) (xy 105.431191 -51.266096)
			(xy 105.466019 -51.338221) (xy 105.494221 -51.413185) (xy 105.515571 -51.49038) (xy 105.529895 -51.569182)
			(xy 105.537077 -51.648953) (xy 105.537508 -51.689) (xy 105.53712 -51.727284) (xy 105.530581 -51.803573)
			(xy 105.5175 -51.879015) (xy 105.497973 -51.953052) (xy 105.485438 -51.989228) (xy 105.482787 -51.997665)
			(xy 105.482787 -52.015335) (xy 105.485438 -52.023772) (xy 105.497963 -52.05995) (xy 105.517471 -52.13399)
			(xy 105.528396 -52.197) (xy 149.097492 -52.197) (xy 149.09788 -52.158716) (xy 149.104419 -52.082427)
			(xy 149.1175 -52.006985) (xy 149.137027 -51.932948) (xy 149.149562 -51.896772) (xy 149.152213 -51.888335)
			(xy 149.152213 -51.870665) (xy 149.149562 -51.862228) (xy 149.137037 -51.82605) (xy 149.117529 -51.75201)
			(xy 149.104449 -51.676569) (xy 149.097894 -51.600283) (xy 149.097492 -51.562) (xy 149.097943 -51.521953)
			(xy 149.105117 -51.442181) (xy 149.119434 -51.363378) (xy 149.140778 -51.286181) (xy 149.168976 -51.211215)
			(xy 149.2038 -51.139088) (xy 149.244968 -51.070385) (xy 149.292146 -51.00566) (xy 149.318218 -50.97526)
			(xy 149.323983 -50.968171) (xy 149.330495 -50.951114) (xy 149.330918 -50.941986) (xy 149.330918 -50.912014)
			(xy 149.330484 -50.902891) (xy 149.323964 -50.885841) (xy 149.318218 -50.87874) (xy 149.292158 -50.848329)
			(xy 149.244979 -50.783606) (xy 149.203809 -50.714904) (xy 149.168981 -50.642779) (xy 149.140779 -50.567815)
			(xy 149.119429 -50.49062) (xy 149.105105 -50.411818) (xy 149.097923 -50.332047) (xy 149.097492 -50.292)
			(xy 149.09788 -50.253716) (xy 149.104419 -50.177427) (xy 149.1175 -50.101985) (xy 149.137027 -50.027948)
			(xy 149.149562 -49.991772) (xy 149.152213 -49.983335) (xy 149.152213 -49.965665) (xy 149.149562 -49.957228)
			(xy 149.137037 -49.92105) (xy 149.117529 -49.84701) (xy 149.104449 -49.771569) (xy 149.097894 -49.695283)
			(xy 149.097492 -49.657) (xy 149.097996 -49.614652) (xy 149.106047 -49.530338) (xy 149.122076 -49.447172)
			(xy 149.145937 -49.365905) (xy 149.177416 -49.287275) (xy 149.216227 -49.211994) (xy 149.262017 -49.140742)
			(xy 149.314373 -49.074166) (xy 149.372821 -49.012868) (xy 149.436831 -48.957403) (xy 149.505823 -48.908274)
			(xy 149.579173 -48.865925) (xy 149.656216 -48.830741) (xy 149.736255 -48.803039) (xy 149.818564 -48.783071)
			(xy 149.902399 -48.771018) (xy 149.987 -48.766988) (xy 150.071601 -48.771018) (xy 150.155436 -48.783071)
			(xy 150.237745 -48.803039) (xy 150.317784 -48.830741) (xy 150.394827 -48.865925) (xy 150.468177 -48.908274)
			(xy 150.537169 -48.957403) (xy 150.601179 -49.012868) (xy 150.659627 -49.074166) (xy 150.711983 -49.140742)
			(xy 150.757773 -49.211994) (xy 150.796584 -49.287275) (xy 150.828063 -49.365905) (xy 150.851924 -49.447172)
			(xy 150.867953 -49.530338) (xy 150.876004 -49.614652) (xy 150.876508 -49.657) (xy 150.87612 -49.695284)
			(xy 150.869581 -49.771573) (xy 150.8565 -49.847015) (xy 150.836973 -49.921052) (xy 150.824438 -49.957228)
			(xy 150.821787 -49.965665) (xy 150.821787 -49.983335) (xy 150.824438 -49.991772) (xy 150.836963 -50.02795)
			(xy 150.856471 -50.10199) (xy 150.869551 -50.177431) (xy 150.876106 -50.253717) (xy 150.876508 -50.292)
			(xy 150.876057 -50.332047) (xy 150.868883 -50.411819) (xy 150.854566 -50.490622) (xy 150.833222 -50.567819)
			(xy 150.805024 -50.642785) (xy 150.7702 -50.714912) (xy 150.729032 -50.783615) (xy 150.681854 -50.84834)
			(xy 150.655782 -50.87874) (xy 150.650017 -50.885829) (xy 150.643505 -50.902886) (xy 150.643082 -50.912014)
			(xy 150.643082 -50.941986) (xy 150.643516 -50.951109) (xy 150.650036 -50.968159) (xy 150.655782 -50.97526)
			(xy 150.681842 -51.005671) (xy 150.729021 -51.070394) (xy 150.770191 -51.139096) (xy 150.805019 -51.211221)
			(xy 150.833221 -51.286185) (xy 150.854571 -51.36338) (xy 150.868895 -51.442182) (xy 150.876077 -51.521953)
			(xy 150.876508 -51.562) (xy 150.87612 -51.600284) (xy 150.869581 -51.676573) (xy 150.8565 -51.752015)
			(xy 150.836973 -51.826052) (xy 150.824438 -51.862228) (xy 150.821787 -51.870665) (xy 150.821787 -51.888335)
			(xy 150.824438 -51.896772) (xy 150.836963 -51.93295) (xy 150.856471 -52.00699) (xy 150.869551 -52.082431)
			(xy 150.876106 -52.158717) (xy 150.876508 -52.197) (xy 154.558492 -52.197) (xy 154.55888 -52.158716)
			(xy 154.565419 -52.082427) (xy 154.5785 -52.006985) (xy 154.598027 -51.932948) (xy 154.610562 -51.896772)
			(xy 154.613213 -51.888335) (xy 154.613213 -51.870665) (xy 154.610562 -51.862228) (xy 154.598037 -51.82605)
			(xy 154.578529 -51.75201) (xy 154.565449 -51.676569) (xy 154.558894 -51.600283) (xy 154.558492 -51.562)
			(xy 154.558943 -51.521953) (xy 154.566117 -51.442181) (xy 154.580434 -51.363378) (xy 154.601778 -51.286181)
			(xy 154.629976 -51.211215) (xy 154.6648 -51.139088) (xy 154.705968 -51.070385) (xy 154.753146 -51.00566)
			(xy 154.779218 -50.97526) (xy 154.784983 -50.968171) (xy 154.791495 -50.951114) (xy 154.791918 -50.941986)
			(xy 154.791918 -50.912014) (xy 154.791484 -50.902891) (xy 154.784964 -50.885841) (xy 154.779218 -50.87874)
			(xy 154.753158 -50.848329) (xy 154.705979 -50.783606) (xy 154.664809 -50.714904) (xy 154.629981 -50.642779)
			(xy 154.601779 -50.567815) (xy 154.580429 -50.49062) (xy 154.566105 -50.411818) (xy 154.558923 -50.332047)
			(xy 154.558492 -50.292) (xy 154.55888 -50.253716) (xy 154.565419 -50.177427) (xy 154.5785 -50.101985)
			(xy 154.598027 -50.027948) (xy 154.610562 -49.991772) (xy 154.613213 -49.983335) (xy 154.613213 -49.965665)
			(xy 154.610562 -49.957228) (xy 154.598037 -49.92105) (xy 154.578529 -49.84701) (xy 154.565449 -49.771569)
			(xy 154.558894 -49.695283) (xy 154.558492 -49.657) (xy 154.558996 -49.614652) (xy 154.567047 -49.530338)
			(xy 154.583076 -49.447172) (xy 154.606937 -49.365905) (xy 154.638416 -49.287275) (xy 154.677227 -49.211994)
			(xy 154.723017 -49.140742) (xy 154.775373 -49.074166) (xy 154.833821 -49.012868) (xy 154.897831 -48.957403)
			(xy 154.966823 -48.908274) (xy 155.040173 -48.865925) (xy 155.117216 -48.830741) (xy 155.197255 -48.803039)
			(xy 155.279564 -48.783071) (xy 155.363399 -48.771018) (xy 155.448 -48.766988) (xy 155.532601 -48.771018)
			(xy 155.616436 -48.783071) (xy 155.698745 -48.803039) (xy 155.778784 -48.830741) (xy 155.855827 -48.865925)
			(xy 155.929177 -48.908274) (xy 155.998169 -48.957403) (xy 156.062179 -49.012868) (xy 156.120627 -49.074166)
			(xy 156.172983 -49.140742) (xy 156.218773 -49.211994) (xy 156.257584 -49.287275) (xy 156.289063 -49.365905)
			(xy 156.312924 -49.447172) (xy 156.328953 -49.530338) (xy 156.337004 -49.614652) (xy 156.337508 -49.657)
			(xy 156.33712 -49.695284) (xy 156.330581 -49.771573) (xy 156.3175 -49.847015) (xy 156.297973 -49.921052)
			(xy 156.285438 -49.957228) (xy 156.282787 -49.965665) (xy 156.282787 -49.983335) (xy 156.285438 -49.991772)
			(xy 156.297963 -50.02795) (xy 156.317471 -50.10199) (xy 156.330551 -50.177431) (xy 156.337106 -50.253717)
			(xy 156.337508 -50.292) (xy 156.337057 -50.332047) (xy 156.329883 -50.411819) (xy 156.315566 -50.490622)
			(xy 156.294222 -50.567819) (xy 156.266024 -50.642785) (xy 156.2312 -50.714912) (xy 156.190032 -50.783615)
			(xy 156.142854 -50.84834) (xy 156.116782 -50.87874) (xy 156.111017 -50.885829) (xy 156.104505 -50.902886)
			(xy 156.104082 -50.912014) (xy 156.104082 -50.941986) (xy 156.104516 -50.951109) (xy 156.111036 -50.968159)
			(xy 156.116782 -50.97526) (xy 156.142842 -51.005671) (xy 156.190021 -51.070394) (xy 156.231191 -51.139096)
			(xy 156.266019 -51.211221) (xy 156.294221 -51.286185) (xy 156.315571 -51.36338) (xy 156.329895 -51.442182)
			(xy 156.337077 -51.521953) (xy 156.337508 -51.562) (xy 156.33712 -51.600284) (xy 156.330581 -51.676573)
			(xy 156.3175 -51.752015) (xy 156.297973 -51.826052) (xy 156.285438 -51.862228) (xy 156.282787 -51.870665)
			(xy 156.282787 -51.888335) (xy 156.285438 -51.896772) (xy 156.297963 -51.93295) (xy 156.317471 -52.00699)
			(xy 156.330551 -52.082431) (xy 156.337106 -52.158717) (xy 156.337508 -52.197) (xy 160.019492 -52.197)
			(xy 160.01988 -52.158716) (xy 160.026419 -52.082427) (xy 160.0395 -52.006985) (xy 160.059027 -51.932948)
			(xy 160.071562 -51.896772) (xy 160.074213 -51.888335) (xy 160.074213 -51.870665) (xy 160.071562 -51.862228)
			(xy 160.059037 -51.82605) (xy 160.039529 -51.75201) (xy 160.026449 -51.676569) (xy 160.019894 -51.600283)
			(xy 160.019492 -51.562) (xy 160.019943 -51.521953) (xy 160.027117 -51.442181) (xy 160.041434 -51.363378)
			(xy 160.062778 -51.286181) (xy 160.090976 -51.211215) (xy 160.1258 -51.139088) (xy 160.166968 -51.070385)
			(xy 160.214146 -51.00566) (xy 160.240218 -50.97526) (xy 160.245983 -50.968171) (xy 160.252495 -50.951114)
			(xy 160.252918 -50.941986) (xy 160.252918 -50.912014) (xy 160.252484 -50.902891) (xy 160.245964 -50.885841)
			(xy 160.240218 -50.87874) (xy 160.214158 -50.848329) (xy 160.166979 -50.783606) (xy 160.125809 -50.714904)
			(xy 160.090981 -50.642779) (xy 160.062779 -50.567815) (xy 160.041429 -50.49062) (xy 160.027105 -50.411818)
			(xy 160.019923 -50.332047) (xy 160.019492 -50.292) (xy 160.01988 -50.253716) (xy 160.026419 -50.177427)
			(xy 160.0395 -50.101985) (xy 160.059027 -50.027948) (xy 160.071562 -49.991772) (xy 160.074213 -49.983335)
			(xy 160.074213 -49.965665) (xy 160.071562 -49.957228) (xy 160.059037 -49.92105) (xy 160.039529 -49.84701)
			(xy 160.026449 -49.771569) (xy 160.019894 -49.695283) (xy 160.019492 -49.657) (xy 160.019996 -49.614652)
			(xy 160.028047 -49.530338) (xy 160.044076 -49.447172) (xy 160.067937 -49.365905) (xy 160.099416 -49.287275)
			(xy 160.138227 -49.211994) (xy 160.184017 -49.140742) (xy 160.236373 -49.074166) (xy 160.294821 -49.012868)
			(xy 160.358831 -48.957403) (xy 160.427823 -48.908274) (xy 160.501173 -48.865925) (xy 160.578216 -48.830741)
			(xy 160.658255 -48.803039) (xy 160.740564 -48.783071) (xy 160.824399 -48.771018) (xy 160.909 -48.766988)
			(xy 160.993601 -48.771018) (xy 161.077436 -48.783071) (xy 161.159745 -48.803039) (xy 161.239784 -48.830741)
			(xy 161.316827 -48.865925) (xy 161.390177 -48.908274) (xy 161.459169 -48.957403) (xy 161.523179 -49.012868)
			(xy 161.581627 -49.074166) (xy 161.633983 -49.140742) (xy 161.679773 -49.211994) (xy 161.718584 -49.287275)
			(xy 161.750063 -49.365905) (xy 161.773924 -49.447172) (xy 161.789953 -49.530338) (xy 161.798004 -49.614652)
			(xy 161.798508 -49.657) (xy 161.79812 -49.695284) (xy 161.791581 -49.771573) (xy 161.7785 -49.847015)
			(xy 161.758973 -49.921052) (xy 161.746438 -49.957228) (xy 161.743787 -49.965665) (xy 161.743787 -49.983335)
			(xy 161.746438 -49.991772) (xy 161.758963 -50.02795) (xy 161.778471 -50.10199) (xy 161.791551 -50.177431)
			(xy 161.798106 -50.253717) (xy 161.798508 -50.292) (xy 161.798057 -50.332047) (xy 161.790883 -50.411819)
			(xy 161.776566 -50.490622) (xy 161.755222 -50.567819) (xy 161.727024 -50.642785) (xy 161.6922 -50.714912)
			(xy 161.651032 -50.783615) (xy 161.603854 -50.84834) (xy 161.577782 -50.87874) (xy 161.572017 -50.885829)
			(xy 161.565505 -50.902886) (xy 161.565082 -50.912014) (xy 161.565082 -50.941986) (xy 161.565516 -50.951109)
			(xy 161.572036 -50.968159) (xy 161.577782 -50.97526) (xy 161.603842 -51.005671) (xy 161.651021 -51.070394)
			(xy 161.692191 -51.139096) (xy 161.727019 -51.211221) (xy 161.755221 -51.286185) (xy 161.776571 -51.36338)
			(xy 161.790895 -51.442182) (xy 161.798077 -51.521953) (xy 161.798508 -51.562) (xy 161.79812 -51.600284)
			(xy 161.791581 -51.676573) (xy 161.7785 -51.752015) (xy 161.758973 -51.826052) (xy 161.746438 -51.862228)
			(xy 161.743787 -51.870665) (xy 161.743787 -51.888335) (xy 161.746438 -51.896772) (xy 161.758963 -51.93295)
			(xy 161.778471 -52.00699) (xy 161.791551 -52.082431) (xy 161.798106 -52.158717) (xy 161.798508 -52.197)
			(xy 165.480492 -52.197) (xy 165.48088 -52.158716) (xy 165.487419 -52.082427) (xy 165.5005 -52.006985)
			(xy 165.520027 -51.932948) (xy 165.532562 -51.896772) (xy 165.535213 -51.888335) (xy 165.535213 -51.870665)
			(xy 165.532562 -51.862228) (xy 165.520037 -51.82605) (xy 165.500529 -51.75201) (xy 165.487449 -51.676569)
			(xy 165.480894 -51.600283) (xy 165.480492 -51.562) (xy 165.480943 -51.521953) (xy 165.488117 -51.442181)
			(xy 165.502434 -51.363378) (xy 165.523778 -51.286181) (xy 165.551976 -51.211215) (xy 165.5868 -51.139088)
			(xy 165.627968 -51.070385) (xy 165.675146 -51.00566) (xy 165.701218 -50.97526) (xy 165.706983 -50.968171)
			(xy 165.713495 -50.951114) (xy 165.713918 -50.941986) (xy 165.713918 -50.912014) (xy 165.713484 -50.902891)
			(xy 165.706964 -50.885841) (xy 165.701218 -50.87874) (xy 165.675158 -50.848329) (xy 165.627979 -50.783606)
			(xy 165.586809 -50.714904) (xy 165.551981 -50.642779) (xy 165.523779 -50.567815) (xy 165.502429 -50.49062)
			(xy 165.488105 -50.411818) (xy 165.480923 -50.332047) (xy 165.480492 -50.292) (xy 165.48088 -50.253716)
			(xy 165.487419 -50.177427) (xy 165.5005 -50.101985) (xy 165.520027 -50.027948) (xy 165.532562 -49.991772)
			(xy 165.535213 -49.983335) (xy 165.535213 -49.965665) (xy 165.532562 -49.957228) (xy 165.520037 -49.92105)
			(xy 165.500529 -49.84701) (xy 165.487449 -49.771569) (xy 165.480894 -49.695283) (xy 165.480492 -49.657)
			(xy 165.480996 -49.614652) (xy 165.489047 -49.530338) (xy 165.505076 -49.447172) (xy 165.528937 -49.365905)
			(xy 165.560416 -49.287275) (xy 165.599227 -49.211994) (xy 165.645017 -49.140742) (xy 165.697373 -49.074166)
			(xy 165.755821 -49.012868) (xy 165.819831 -48.957403) (xy 165.888823 -48.908274) (xy 165.962173 -48.865925)
			(xy 166.039216 -48.830741) (xy 166.119255 -48.803039) (xy 166.201564 -48.783071) (xy 166.285399 -48.771018)
			(xy 166.37 -48.766988) (xy 166.454601 -48.771018) (xy 166.538436 -48.783071) (xy 166.620745 -48.803039)
			(xy 166.700784 -48.830741) (xy 166.777827 -48.865925) (xy 166.851177 -48.908274) (xy 166.920169 -48.957403)
			(xy 166.984179 -49.012868) (xy 167.042627 -49.074166) (xy 167.094983 -49.140742) (xy 167.140773 -49.211994)
			(xy 167.179584 -49.287275) (xy 167.211063 -49.365905) (xy 167.234924 -49.447172) (xy 167.250953 -49.530338)
			(xy 167.259004 -49.614652) (xy 167.259508 -49.657) (xy 167.25912 -49.695284) (xy 167.252581 -49.771573)
			(xy 167.2395 -49.847015) (xy 167.219973 -49.921052) (xy 167.207438 -49.957228) (xy 167.204787 -49.965665)
			(xy 167.204787 -49.983335) (xy 167.207438 -49.991772) (xy 167.219963 -50.02795) (xy 167.239471 -50.10199)
			(xy 167.252551 -50.177431) (xy 167.259106 -50.253717) (xy 167.259508 -50.292) (xy 167.259057 -50.332047)
			(xy 167.251883 -50.411819) (xy 167.237566 -50.490622) (xy 167.216222 -50.567819) (xy 167.188024 -50.642785)
			(xy 167.1532 -50.714912) (xy 167.112032 -50.783615) (xy 167.064854 -50.84834) (xy 167.038782 -50.87874)
			(xy 167.033017 -50.885829) (xy 167.026505 -50.902886) (xy 167.026082 -50.912014) (xy 167.026082 -50.941986)
			(xy 167.026516 -50.951109) (xy 167.033036 -50.968159) (xy 167.038782 -50.97526) (xy 167.064842 -51.005671)
			(xy 167.112021 -51.070394) (xy 167.153191 -51.139096) (xy 167.188019 -51.211221) (xy 167.216221 -51.286185)
			(xy 167.237571 -51.36338) (xy 167.251895 -51.442182) (xy 167.259077 -51.521953) (xy 167.259508 -51.562)
			(xy 167.25912 -51.600284) (xy 167.252581 -51.676573) (xy 167.2395 -51.752015) (xy 167.219973 -51.826052)
			(xy 167.207438 -51.862228) (xy 167.204787 -51.870665) (xy 167.204787 -51.888335) (xy 167.207438 -51.896772)
			(xy 167.219963 -51.93295) (xy 167.239471 -52.00699) (xy 167.252551 -52.082431) (xy 167.259106 -52.158717)
			(xy 167.259508 -52.197) (xy 170.941492 -52.197) (xy 170.94188 -52.158716) (xy 170.948419 -52.082427)
			(xy 170.9615 -52.006985) (xy 170.981027 -51.932948) (xy 170.993562 -51.896772) (xy 170.996213 -51.888335)
			(xy 170.996213 -51.870665) (xy 170.993562 -51.862228) (xy 170.981037 -51.82605) (xy 170.961529 -51.75201)
			(xy 170.948449 -51.676569) (xy 170.941894 -51.600283) (xy 170.941492 -51.562) (xy 170.941943 -51.521953)
			(xy 170.949117 -51.442181) (xy 170.963434 -51.363378) (xy 170.984778 -51.286181) (xy 171.012976 -51.211215)
			(xy 171.0478 -51.139088) (xy 171.088968 -51.070385) (xy 171.136146 -51.00566) (xy 171.162218 -50.97526)
			(xy 171.167983 -50.968171) (xy 171.174495 -50.951114) (xy 171.174918 -50.941986) (xy 171.174918 -50.912014)
			(xy 171.174484 -50.902891) (xy 171.167964 -50.885841) (xy 171.162218 -50.87874) (xy 171.136158 -50.848329)
			(xy 171.088979 -50.783606) (xy 171.047809 -50.714904) (xy 171.012981 -50.642779) (xy 170.984779 -50.567815)
			(xy 170.963429 -50.49062) (xy 170.949105 -50.411818) (xy 170.941923 -50.332047) (xy 170.941492 -50.292)
			(xy 170.94188 -50.253716) (xy 170.948419 -50.177427) (xy 170.9615 -50.101985) (xy 170.981027 -50.027948)
			(xy 170.993562 -49.991772) (xy 170.996213 -49.983335) (xy 170.996213 -49.965665) (xy 170.993562 -49.957228)
			(xy 170.981037 -49.92105) (xy 170.961529 -49.84701) (xy 170.948449 -49.771569) (xy 170.941894 -49.695283)
			(xy 170.941492 -49.657) (xy 170.941996 -49.614652) (xy 170.950047 -49.530338) (xy 170.966076 -49.447172)
			(xy 170.989937 -49.365905) (xy 171.021416 -49.287275) (xy 171.060227 -49.211994) (xy 171.106017 -49.140742)
			(xy 171.158373 -49.074166) (xy 171.216821 -49.012868) (xy 171.280831 -48.957403) (xy 171.349823 -48.908274)
			(xy 171.423173 -48.865925) (xy 171.500216 -48.830741) (xy 171.580255 -48.803039) (xy 171.662564 -48.783071)
			(xy 171.746399 -48.771018) (xy 171.831 -48.766988) (xy 171.915601 -48.771018) (xy 171.999436 -48.783071)
			(xy 172.081745 -48.803039) (xy 172.161784 -48.830741) (xy 172.238827 -48.865925) (xy 172.312177 -48.908274)
			(xy 172.381169 -48.957403) (xy 172.445179 -49.012868) (xy 172.503627 -49.074166) (xy 172.555983 -49.140742)
			(xy 172.601773 -49.211994) (xy 172.640584 -49.287275) (xy 172.672063 -49.365905) (xy 172.695924 -49.447172)
			(xy 172.711953 -49.530338) (xy 172.720004 -49.614652) (xy 172.720508 -49.657) (xy 172.72012 -49.695284)
			(xy 172.713581 -49.771573) (xy 172.7005 -49.847015) (xy 172.680973 -49.921052) (xy 172.668438 -49.957228)
			(xy 172.665787 -49.965665) (xy 172.665787 -49.983335) (xy 172.668438 -49.991772) (xy 172.680963 -50.02795)
			(xy 172.700471 -50.10199) (xy 172.713551 -50.177431) (xy 172.720106 -50.253717) (xy 172.720508 -50.292)
			(xy 172.720057 -50.332047) (xy 172.712883 -50.411819) (xy 172.698566 -50.490622) (xy 172.677222 -50.567819)
			(xy 172.649024 -50.642785) (xy 172.6142 -50.714912) (xy 172.573032 -50.783615) (xy 172.525854 -50.84834)
			(xy 172.499782 -50.87874) (xy 172.494017 -50.885829) (xy 172.487505 -50.902886) (xy 172.487082 -50.912014)
			(xy 172.487082 -50.941986) (xy 172.487516 -50.951109) (xy 172.494036 -50.968159) (xy 172.499782 -50.97526)
			(xy 172.525842 -51.005671) (xy 172.573021 -51.070394) (xy 172.614191 -51.139096) (xy 172.649019 -51.211221)
			(xy 172.677221 -51.286185) (xy 172.698571 -51.36338) (xy 172.712895 -51.442182) (xy 172.720077 -51.521953)
			(xy 172.720508 -51.562) (xy 172.72012 -51.600284) (xy 172.713581 -51.676573) (xy 172.7005 -51.752015)
			(xy 172.680973 -51.826052) (xy 172.668438 -51.862228) (xy 172.665787 -51.870665) (xy 172.665787 -51.888335)
			(xy 172.668438 -51.896772) (xy 172.680963 -51.93295) (xy 172.700471 -52.00699) (xy 172.713551 -52.082431)
			(xy 172.720106 -52.158717) (xy 172.720508 -52.197) (xy 176.399952 -52.197) (xy 176.400342 -52.158716)
			(xy 176.406881 -52.082427) (xy 176.419962 -52.006985) (xy 176.439487 -51.932948) (xy 176.452022 -51.896772)
			(xy 176.454674 -51.888335) (xy 176.454674 -51.870665) (xy 176.452022 -51.862228) (xy 176.439495 -51.82605)
			(xy 176.419988 -51.75201) (xy 176.406909 -51.676569) (xy 176.400354 -51.600283) (xy 176.399952 -51.562)
			(xy 176.400388 -51.521953) (xy 176.407563 -51.44218) (xy 176.421881 -51.363376) (xy 176.443226 -51.286178)
			(xy 176.471427 -51.211212) (xy 176.506253 -51.139086) (xy 176.547423 -51.070383) (xy 176.594604 -51.00566)
			(xy 176.620678 -50.97526) (xy 176.626439 -50.968167) (xy 176.632954 -50.951113) (xy 176.633378 -50.941986)
			(xy 176.633378 -50.912014) (xy 176.632931 -50.902892) (xy 176.626419 -50.885843) (xy 176.620678 -50.87874)
			(xy 176.594628 -50.84832) (xy 176.547447 -50.7836) (xy 176.506274 -50.714899) (xy 176.471445 -50.642776)
			(xy 176.443241 -50.567813) (xy 176.42189 -50.490618) (xy 176.407565 -50.411817) (xy 176.400383 -50.332047)
			(xy 176.399952 -50.292) (xy 176.400342 -50.253716) (xy 176.406881 -50.177427) (xy 176.419962 -50.101985)
			(xy 176.439487 -50.027948) (xy 176.452022 -49.991772) (xy 176.454674 -49.983335) (xy 176.454674 -49.965665)
			(xy 176.452022 -49.957228) (xy 176.439495 -49.92105) (xy 176.419988 -49.84701) (xy 176.406909 -49.771569)
			(xy 176.400354 -49.695283) (xy 176.399952 -49.657) (xy 176.400456 -49.614652) (xy 176.408507 -49.530338)
			(xy 176.424536 -49.447172) (xy 176.448397 -49.365905) (xy 176.479876 -49.287275) (xy 176.518687 -49.211994)
			(xy 176.564477 -49.140742) (xy 176.616833 -49.074166) (xy 176.675281 -49.012868) (xy 176.739291 -48.957403)
			(xy 176.808283 -48.908274) (xy 176.881633 -48.865925) (xy 176.958676 -48.830741) (xy 177.038715 -48.803039)
			(xy 177.121024 -48.783071) (xy 177.204859 -48.771018) (xy 177.28946 -48.766988) (xy 177.374061 -48.771018)
			(xy 177.457896 -48.783071) (xy 177.540205 -48.803039) (xy 177.620244 -48.830741) (xy 177.697287 -48.865925)
			(xy 177.770637 -48.908274) (xy 177.839629 -48.957403) (xy 177.903639 -49.012868) (xy 177.962087 -49.074166)
			(xy 178.014443 -49.140742) (xy 178.060233 -49.211994) (xy 178.099044 -49.287275) (xy 178.130523 -49.365905)
			(xy 178.154384 -49.447172) (xy 178.170413 -49.530338) (xy 178.178464 -49.614652) (xy 178.178968 -49.657)
			(xy 178.178577 -49.695284) (xy 178.172038 -49.771573) (xy 178.158958 -49.847015) (xy 178.139432 -49.921052)
			(xy 178.126898 -49.957228) (xy 178.124245 -49.965664) (xy 178.124245 -49.983336) (xy 178.126898 -49.991772)
			(xy 178.139422 -50.027951) (xy 178.15893 -50.10199) (xy 178.172011 -50.177431) (xy 178.178566 -50.253717)
			(xy 178.178968 -50.292) (xy 178.178527 -50.332047) (xy 178.171353 -50.411819) (xy 178.157035 -50.490623)
			(xy 178.13569 -50.567821) (xy 178.10749 -50.642787) (xy 178.072665 -50.714913) (xy 178.031495 -50.783617)
			(xy 177.984315 -50.84834) (xy 177.958242 -50.87874) (xy 177.952472 -50.885825) (xy 177.945964 -50.902886)
			(xy 177.945542 -50.912014) (xy 177.945542 -50.941986) (xy 177.945985 -50.951108) (xy 177.9525 -50.968158)
			(xy 177.958242 -50.97526) (xy 177.984295 -51.005677) (xy 178.031476 -51.070398) (xy 178.072647 -51.139099)
			(xy 178.107476 -51.211223) (xy 178.13568 -51.286186) (xy 178.15703 -51.363381) (xy 178.171355 -51.442183)
			(xy 178.178537 -51.521953) (xy 178.178968 -51.562) (xy 178.178577 -51.600284) (xy 178.172038 -51.676573)
			(xy 178.158958 -51.752015) (xy 178.139432 -51.826052) (xy 178.126898 -51.862228) (xy 178.124245 -51.870664)
			(xy 178.124245 -51.888336) (xy 178.126898 -51.896772) (xy 178.139422 -51.932951) (xy 178.15893 -52.00699)
			(xy 178.172011 -52.082431) (xy 178.178566 -52.158717) (xy 178.178968 -52.197) (xy 181.860952 -52.197)
			(xy 181.861342 -52.158716) (xy 181.867881 -52.082427) (xy 181.880962 -52.006985) (xy 181.900487 -51.932948)
			(xy 181.913022 -51.896772) (xy 181.915674 -51.888335) (xy 181.915674 -51.870665) (xy 181.913022 -51.862228)
			(xy 181.900495 -51.82605) (xy 181.880988 -51.75201) (xy 181.867909 -51.676569) (xy 181.861354 -51.600283)
			(xy 181.860952 -51.562) (xy 181.861388 -51.521953) (xy 181.868563 -51.44218) (xy 181.882881 -51.363376)
			(xy 181.904226 -51.286178) (xy 181.932427 -51.211212) (xy 181.967253 -51.139086) (xy 182.008423 -51.070383)
			(xy 182.055604 -51.00566) (xy 182.081678 -50.97526) (xy 182.087439 -50.968167) (xy 182.093954 -50.951113)
			(xy 182.094378 -50.941986) (xy 182.094378 -50.912014) (xy 182.093931 -50.902892) (xy 182.087419 -50.885843)
			(xy 182.081678 -50.87874) (xy 182.055628 -50.84832) (xy 182.008447 -50.7836) (xy 181.967274 -50.714899)
			(xy 181.932445 -50.642776) (xy 181.904241 -50.567813) (xy 181.88289 -50.490618) (xy 181.868565 -50.411817)
			(xy 181.861383 -50.332047) (xy 181.860952 -50.292) (xy 181.861342 -50.253716) (xy 181.867881 -50.177427)
			(xy 181.880962 -50.101985) (xy 181.900487 -50.027948) (xy 181.913022 -49.991772) (xy 181.915674 -49.983335)
			(xy 181.915674 -49.965665) (xy 181.913022 -49.957228) (xy 181.900495 -49.92105) (xy 181.880988 -49.84701)
			(xy 181.867909 -49.771569) (xy 181.861354 -49.695283) (xy 181.860952 -49.657) (xy 181.861456 -49.614652)
			(xy 181.869507 -49.530338) (xy 181.885536 -49.447172) (xy 181.909397 -49.365905) (xy 181.940876 -49.287275)
			(xy 181.979687 -49.211994) (xy 182.025477 -49.140742) (xy 182.077833 -49.074166) (xy 182.136281 -49.012868)
			(xy 182.200291 -48.957403) (xy 182.269283 -48.908274) (xy 182.342633 -48.865925) (xy 182.419676 -48.830741)
			(xy 182.499715 -48.803039) (xy 182.582024 -48.783071) (xy 182.665859 -48.771018) (xy 182.75046 -48.766988)
			(xy 182.835061 -48.771018) (xy 182.918896 -48.783071) (xy 183.001205 -48.803039) (xy 183.081244 -48.830741)
			(xy 183.158287 -48.865925) (xy 183.231637 -48.908274) (xy 183.300629 -48.957403) (xy 183.364639 -49.012868)
			(xy 183.423087 -49.074166) (xy 183.475443 -49.140742) (xy 183.521233 -49.211994) (xy 183.560044 -49.287275)
			(xy 183.591523 -49.365905) (xy 183.615384 -49.447172) (xy 183.631413 -49.530338) (xy 183.639464 -49.614652)
			(xy 183.639968 -49.657) (xy 183.639577 -49.695284) (xy 183.633038 -49.771573) (xy 183.619958 -49.847015)
			(xy 183.600432 -49.921052) (xy 183.587898 -49.957228) (xy 183.585245 -49.965664) (xy 183.585245 -49.983336)
			(xy 183.587898 -49.991772) (xy 183.600422 -50.027951) (xy 183.61993 -50.10199) (xy 183.633011 -50.177431)
			(xy 183.639566 -50.253717) (xy 183.639791 -50.275179) (xy 257.330698 -50.275179) (xy 257.330698 -50.190457)
			(xy 257.338751 -50.10612) (xy 257.354785 -50.02293) (xy 257.378653 -49.94164) (xy 257.410141 -49.862988)
			(xy 257.448963 -49.787685) (xy 257.494766 -49.716413) (xy 257.547137 -49.649817) (xy 257.605602 -49.588502)
			(xy 257.66963 -49.533021) (xy 257.738642 -49.483878) (xy 257.812012 -49.441518) (xy 257.889077 -49.406323)
			(xy 257.969139 -49.378614) (xy 258.051472 -49.35864) (xy 258.135331 -49.346583) (xy 258.219956 -49.342552)
			(xy 258.304581 -49.346583) (xy 258.38844 -49.35864) (xy 258.470773 -49.378614) (xy 258.550835 -49.406323)
			(xy 258.6279 -49.441518) (xy 258.70127 -49.483878) (xy 258.770282 -49.533021) (xy 258.83431 -49.588502)
			(xy 258.892775 -49.649817) (xy 258.945146 -49.716413) (xy 258.990949 -49.787685) (xy 259.029771 -49.862988)
			(xy 259.061259 -49.94164) (xy 259.085127 -50.02293) (xy 259.101161 -50.10612) (xy 259.109214 -50.190457)
			(xy 259.109718 -50.232818) (xy 259.109214 -50.275179) (xy 259.101161 -50.359516) (xy 259.085127 -50.442706)
			(xy 259.061259 -50.523996) (xy 259.029771 -50.602648) (xy 258.990949 -50.677951) (xy 258.945146 -50.749223)
			(xy 258.892775 -50.815819) (xy 258.83431 -50.877134) (xy 258.770282 -50.932615) (xy 258.70127 -50.981758)
			(xy 258.6279 -51.024118) (xy 258.562469 -51.054) (xy 275.335492 -51.054) (xy 275.336075 -51.007604)
			(xy 275.34572 -50.915316) (xy 275.364916 -50.824532) (xy 275.393454 -50.736239) (xy 275.411692 -50.693574)
			(xy 275.415498 -50.683632) (xy 275.415498 -50.662368) (xy 275.411692 -50.652426) (xy 275.393447 -50.609764)
			(xy 275.364903 -50.521471) (xy 275.34571 -50.430686) (xy 275.336077 -50.338396) (xy 275.335492 -50.292)
			(xy 275.335996 -50.249652) (xy 275.344047 -50.165338) (xy 275.360076 -50.082172) (xy 275.383937 -50.000905)
			(xy 275.415416 -49.922275) (xy 275.454227 -49.846994) (xy 275.500017 -49.775742) (xy 275.552373 -49.709166)
			(xy 275.610821 -49.647868) (xy 275.674831 -49.592403) (xy 275.743823 -49.543274) (xy 275.817173 -49.500925)
			(xy 275.894216 -49.465741) (xy 275.974255 -49.438039) (xy 276.056564 -49.418071) (xy 276.140399 -49.406018)
			(xy 276.225 -49.401988) (xy 276.309601 -49.406018) (xy 276.393436 -49.418071) (xy 276.475745 -49.438039)
			(xy 276.555784 -49.465741) (xy 276.632827 -49.500925) (xy 276.706177 -49.543274) (xy 276.775169 -49.592403)
			(xy 276.839179 -49.647868) (xy 276.897627 -49.709166) (xy 276.949983 -49.775742) (xy 276.995773 -49.846994)
			(xy 277.034584 -49.922275) (xy 277.066063 -50.000905) (xy 277.089924 -50.082172) (xy 277.105953 -50.165338)
			(xy 277.114004 -50.249652) (xy 277.114508 -50.292) (xy 277.113925 -50.338396) (xy 277.10428 -50.430684)
			(xy 277.085084 -50.521468) (xy 277.056546 -50.609761) (xy 277.038308 -50.652426) (xy 277.034502 -50.662368)
			(xy 277.034502 -50.683632) (xy 277.038308 -50.693574) (xy 277.056553 -50.736236) (xy 277.085097 -50.824529)
			(xy 277.10429 -50.915314) (xy 277.113923 -51.007604) (xy 277.114508 -51.054) (xy 277.114004 -51.096348)
			(xy 277.105953 -51.180662) (xy 277.089924 -51.263828) (xy 277.066063 -51.345095) (xy 277.034584 -51.423725)
			(xy 276.995773 -51.499006) (xy 276.949983 -51.570258) (xy 276.897627 -51.636834) (xy 276.839179 -51.698132)
			(xy 276.775169 -51.753597) (xy 276.706177 -51.802726) (xy 276.632827 -51.845075) (xy 276.555784 -51.880259)
			(xy 276.475745 -51.907961) (xy 276.393436 -51.927929) (xy 276.309601 -51.939982) (xy 276.225 -51.944013)
			(xy 276.140399 -51.939982) (xy 276.056564 -51.927929) (xy 275.974255 -51.907961) (xy 275.894216 -51.880259)
			(xy 275.817173 -51.845075) (xy 275.743823 -51.802726) (xy 275.674831 -51.753597) (xy 275.610821 -51.698132)
			(xy 275.552373 -51.636834) (xy 275.500017 -51.570258) (xy 275.454227 -51.499006) (xy 275.415416 -51.423725)
			(xy 275.383937 -51.345095) (xy 275.360076 -51.263828) (xy 275.344047 -51.180662) (xy 275.335996 -51.096348)
			(xy 275.335492 -51.054) (xy 258.562469 -51.054) (xy 258.550835 -51.059313) (xy 258.470773 -51.087022)
			(xy 258.38844 -51.106996) (xy 258.304581 -51.119053) (xy 258.219956 -51.123085) (xy 258.135331 -51.119053)
			(xy 258.051472 -51.106996) (xy 257.969139 -51.087022) (xy 257.889077 -51.059313) (xy 257.812012 -51.024118)
			(xy 257.738642 -50.981758) (xy 257.66963 -50.932615) (xy 257.605602 -50.877134) (xy 257.547137 -50.815819)
			(xy 257.494766 -50.749223) (xy 257.448963 -50.677951) (xy 257.410141 -50.602648) (xy 257.378653 -50.523996)
			(xy 257.354785 -50.442706) (xy 257.338751 -50.359516) (xy 257.330698 -50.275179) (xy 183.639791 -50.275179)
			(xy 183.639968 -50.292) (xy 183.639527 -50.332047) (xy 183.632353 -50.411819) (xy 183.618035 -50.490623)
			(xy 183.59669 -50.567821) (xy 183.56849 -50.642787) (xy 183.533665 -50.714913) (xy 183.492495 -50.783617)
			(xy 183.445315 -50.84834) (xy 183.419242 -50.87874) (xy 183.413472 -50.885825) (xy 183.406964 -50.902886)
			(xy 183.406542 -50.912014) (xy 183.406542 -50.941986) (xy 183.406985 -50.951108) (xy 183.4135 -50.968158)
			(xy 183.419242 -50.97526) (xy 183.445295 -51.005677) (xy 183.492476 -51.070398) (xy 183.533647 -51.139099)
			(xy 183.568476 -51.211223) (xy 183.59668 -51.286186) (xy 183.61803 -51.363381) (xy 183.632355 -51.442183)
			(xy 183.639537 -51.521953) (xy 183.639968 -51.562) (xy 183.639577 -51.600284) (xy 183.633038 -51.676573)
			(xy 183.619958 -51.752015) (xy 183.600432 -51.826052) (xy 183.587898 -51.862228) (xy 183.585245 -51.870664)
			(xy 183.585245 -51.888336) (xy 183.587898 -51.896772) (xy 183.600422 -51.932951) (xy 183.61993 -52.00699)
			(xy 183.633011 -52.082431) (xy 183.639566 -52.158717) (xy 183.639968 -52.197) (xy 183.639464 -52.239348)
			(xy 183.631413 -52.323662) (xy 183.615384 -52.406828) (xy 183.591523 -52.488095) (xy 183.560044 -52.566725)
			(xy 183.521233 -52.642006) (xy 183.475443 -52.713258) (xy 183.423087 -52.779834) (xy 183.364639 -52.841132)
			(xy 183.300629 -52.896597) (xy 183.231637 -52.945726) (xy 183.158287 -52.988075) (xy 183.081244 -53.023259)
			(xy 183.001205 -53.050961) (xy 182.918896 -53.070929) (xy 182.835061 -53.082982) (xy 182.75046 -53.087013)
			(xy 182.665859 -53.082982) (xy 182.582024 -53.070929) (xy 182.499715 -53.050961) (xy 182.419676 -53.023259)
			(xy 182.342633 -52.988075) (xy 182.269283 -52.945726) (xy 182.200291 -52.896597) (xy 182.136281 -52.841132)
			(xy 182.077833 -52.779834) (xy 182.025477 -52.713258) (xy 181.979687 -52.642006) (xy 181.940876 -52.566725)
			(xy 181.909397 -52.488095) (xy 181.885536 -52.406828) (xy 181.869507 -52.323662) (xy 181.861456 -52.239348)
			(xy 181.860952 -52.197) (xy 178.178968 -52.197) (xy 178.178464 -52.239348) (xy 178.170413 -52.323662)
			(xy 178.154384 -52.406828) (xy 178.130523 -52.488095) (xy 178.099044 -52.566725) (xy 178.060233 -52.642006)
			(xy 178.014443 -52.713258) (xy 177.962087 -52.779834) (xy 177.903639 -52.841132) (xy 177.839629 -52.896597)
			(xy 177.770637 -52.945726) (xy 177.697287 -52.988075) (xy 177.620244 -53.023259) (xy 177.540205 -53.050961)
			(xy 177.457896 -53.070929) (xy 177.374061 -53.082982) (xy 177.28946 -53.087013) (xy 177.204859 -53.082982)
			(xy 177.121024 -53.070929) (xy 177.038715 -53.050961) (xy 176.958676 -53.023259) (xy 176.881633 -52.988075)
			(xy 176.808283 -52.945726) (xy 176.739291 -52.896597) (xy 176.675281 -52.841132) (xy 176.616833 -52.779834)
			(xy 176.564477 -52.713258) (xy 176.518687 -52.642006) (xy 176.479876 -52.566725) (xy 176.448397 -52.488095)
			(xy 176.424536 -52.406828) (xy 176.408507 -52.323662) (xy 176.400456 -52.239348) (xy 176.399952 -52.197)
			(xy 172.720508 -52.197) (xy 172.720004 -52.239348) (xy 172.711953 -52.323662) (xy 172.695924 -52.406828)
			(xy 172.672063 -52.488095) (xy 172.640584 -52.566725) (xy 172.601773 -52.642006) (xy 172.555983 -52.713258)
			(xy 172.503627 -52.779834) (xy 172.445179 -52.841132) (xy 172.381169 -52.896597) (xy 172.312177 -52.945726)
			(xy 172.238827 -52.988075) (xy 172.161784 -53.023259) (xy 172.081745 -53.050961) (xy 171.999436 -53.070929)
			(xy 171.915601 -53.082982) (xy 171.831 -53.087013) (xy 171.746399 -53.082982) (xy 171.662564 -53.070929)
			(xy 171.580255 -53.050961) (xy 171.500216 -53.023259) (xy 171.423173 -52.988075) (xy 171.349823 -52.945726)
			(xy 171.280831 -52.896597) (xy 171.216821 -52.841132) (xy 171.158373 -52.779834) (xy 171.106017 -52.713258)
			(xy 171.060227 -52.642006) (xy 171.021416 -52.566725) (xy 170.989937 -52.488095) (xy 170.966076 -52.406828)
			(xy 170.950047 -52.323662) (xy 170.941996 -52.239348) (xy 170.941492 -52.197) (xy 167.259508 -52.197)
			(xy 167.259004 -52.239348) (xy 167.250953 -52.323662) (xy 167.234924 -52.406828) (xy 167.211063 -52.488095)
			(xy 167.179584 -52.566725) (xy 167.140773 -52.642006) (xy 167.094983 -52.713258) (xy 167.042627 -52.779834)
			(xy 166.984179 -52.841132) (xy 166.920169 -52.896597) (xy 166.851177 -52.945726) (xy 166.777827 -52.988075)
			(xy 166.700784 -53.023259) (xy 166.620745 -53.050961) (xy 166.538436 -53.070929) (xy 166.454601 -53.082982)
			(xy 166.37 -53.087013) (xy 166.285399 -53.082982) (xy 166.201564 -53.070929) (xy 166.119255 -53.050961)
			(xy 166.039216 -53.023259) (xy 165.962173 -52.988075) (xy 165.888823 -52.945726) (xy 165.819831 -52.896597)
			(xy 165.755821 -52.841132) (xy 165.697373 -52.779834) (xy 165.645017 -52.713258) (xy 165.599227 -52.642006)
			(xy 165.560416 -52.566725) (xy 165.528937 -52.488095) (xy 165.505076 -52.406828) (xy 165.489047 -52.323662)
			(xy 165.480996 -52.239348) (xy 165.480492 -52.197) (xy 161.798508 -52.197) (xy 161.798004 -52.239348)
			(xy 161.789953 -52.323662) (xy 161.773924 -52.406828) (xy 161.750063 -52.488095) (xy 161.718584 -52.566725)
			(xy 161.679773 -52.642006) (xy 161.633983 -52.713258) (xy 161.581627 -52.779834) (xy 161.523179 -52.841132)
			(xy 161.459169 -52.896597) (xy 161.390177 -52.945726) (xy 161.316827 -52.988075) (xy 161.239784 -53.023259)
			(xy 161.159745 -53.050961) (xy 161.077436 -53.070929) (xy 160.993601 -53.082982) (xy 160.909 -53.087013)
			(xy 160.824399 -53.082982) (xy 160.740564 -53.070929) (xy 160.658255 -53.050961) (xy 160.578216 -53.023259)
			(xy 160.501173 -52.988075) (xy 160.427823 -52.945726) (xy 160.358831 -52.896597) (xy 160.294821 -52.841132)
			(xy 160.236373 -52.779834) (xy 160.184017 -52.713258) (xy 160.138227 -52.642006) (xy 160.099416 -52.566725)
			(xy 160.067937 -52.488095) (xy 160.044076 -52.406828) (xy 160.028047 -52.323662) (xy 160.019996 -52.239348)
			(xy 160.019492 -52.197) (xy 156.337508 -52.197) (xy 156.337004 -52.239348) (xy 156.328953 -52.323662)
			(xy 156.312924 -52.406828) (xy 156.289063 -52.488095) (xy 156.257584 -52.566725) (xy 156.218773 -52.642006)
			(xy 156.172983 -52.713258) (xy 156.120627 -52.779834) (xy 156.062179 -52.841132) (xy 155.998169 -52.896597)
			(xy 155.929177 -52.945726) (xy 155.855827 -52.988075) (xy 155.778784 -53.023259) (xy 155.698745 -53.050961)
			(xy 155.616436 -53.070929) (xy 155.532601 -53.082982) (xy 155.448 -53.087013) (xy 155.363399 -53.082982)
			(xy 155.279564 -53.070929) (xy 155.197255 -53.050961) (xy 155.117216 -53.023259) (xy 155.040173 -52.988075)
			(xy 154.966823 -52.945726) (xy 154.897831 -52.896597) (xy 154.833821 -52.841132) (xy 154.775373 -52.779834)
			(xy 154.723017 -52.713258) (xy 154.677227 -52.642006) (xy 154.638416 -52.566725) (xy 154.606937 -52.488095)
			(xy 154.583076 -52.406828) (xy 154.567047 -52.323662) (xy 154.558996 -52.239348) (xy 154.558492 -52.197)
			(xy 150.876508 -52.197) (xy 150.876004 -52.239348) (xy 150.867953 -52.323662) (xy 150.851924 -52.406828)
			(xy 150.828063 -52.488095) (xy 150.796584 -52.566725) (xy 150.757773 -52.642006) (xy 150.711983 -52.713258)
			(xy 150.659627 -52.779834) (xy 150.601179 -52.841132) (xy 150.537169 -52.896597) (xy 150.468177 -52.945726)
			(xy 150.394827 -52.988075) (xy 150.317784 -53.023259) (xy 150.237745 -53.050961) (xy 150.155436 -53.070929)
			(xy 150.071601 -53.082982) (xy 149.987 -53.087013) (xy 149.902399 -53.082982) (xy 149.818564 -53.070929)
			(xy 149.736255 -53.050961) (xy 149.656216 -53.023259) (xy 149.579173 -52.988075) (xy 149.505823 -52.945726)
			(xy 149.436831 -52.896597) (xy 149.372821 -52.841132) (xy 149.314373 -52.779834) (xy 149.262017 -52.713258)
			(xy 149.216227 -52.642006) (xy 149.177416 -52.566725) (xy 149.145937 -52.488095) (xy 149.122076 -52.406828)
			(xy 149.106047 -52.323662) (xy 149.097996 -52.239348) (xy 149.097492 -52.197) (xy 105.528396 -52.197)
			(xy 105.530551 -52.209431) (xy 105.537106 -52.285717) (xy 105.537508 -52.324) (xy 105.537004 -52.366348)
			(xy 105.528953 -52.450662) (xy 105.512924 -52.533828) (xy 105.489063 -52.615095) (xy 105.457584 -52.693725)
			(xy 105.418773 -52.769006) (xy 105.372983 -52.840258) (xy 105.320627 -52.906834) (xy 105.262179 -52.968132)
			(xy 105.198169 -53.023597) (xy 105.129177 -53.072726) (xy 105.055827 -53.115075) (xy 104.978784 -53.150259)
			(xy 104.898745 -53.177961) (xy 104.816436 -53.197929) (xy 104.732601 -53.209982) (xy 104.648 -53.214013)
			(xy 104.563399 -53.209982) (xy 104.479564 -53.197929) (xy 104.397255 -53.177961) (xy 104.317216 -53.150259)
			(xy 104.240173 -53.115075) (xy 104.166823 -53.072726) (xy 104.097831 -53.023597) (xy 104.033821 -52.968132)
			(xy 103.975373 -52.906834) (xy 103.923017 -52.840258) (xy 103.877227 -52.769006) (xy 103.838416 -52.693725)
			(xy 103.806937 -52.615095) (xy 103.783076 -52.533828) (xy 103.767047 -52.450662) (xy 103.758996 -52.366348)
			(xy 103.758492 -52.324) (xy 100.076508 -52.324) (xy 100.076004 -52.366348) (xy 100.067953 -52.450662)
			(xy 100.051924 -52.533828) (xy 100.028063 -52.615095) (xy 99.996584 -52.693725) (xy 99.957773 -52.769006)
			(xy 99.911983 -52.840258) (xy 99.859627 -52.906834) (xy 99.801179 -52.968132) (xy 99.737169 -53.023597)
			(xy 99.668177 -53.072726) (xy 99.594827 -53.115075) (xy 99.517784 -53.150259) (xy 99.437745 -53.177961)
			(xy 99.355436 -53.197929) (xy 99.271601 -53.209982) (xy 99.187 -53.214013) (xy 99.102399 -53.209982)
			(xy 99.018564 -53.197929) (xy 98.936255 -53.177961) (xy 98.856216 -53.150259) (xy 98.779173 -53.115075)
			(xy 98.705823 -53.072726) (xy 98.636831 -53.023597) (xy 98.572821 -52.968132) (xy 98.514373 -52.906834)
			(xy 98.462017 -52.840258) (xy 98.416227 -52.769006) (xy 98.377416 -52.693725) (xy 98.345937 -52.615095)
			(xy 98.322076 -52.533828) (xy 98.306047 -52.450662) (xy 98.297996 -52.366348) (xy 98.297492 -52.324)
			(xy 94.615508 -52.324) (xy 94.615004 -52.366348) (xy 94.606953 -52.450662) (xy 94.590924 -52.533828)
			(xy 94.567063 -52.615095) (xy 94.535584 -52.693725) (xy 94.496773 -52.769006) (xy 94.450983 -52.840258)
			(xy 94.398627 -52.906834) (xy 94.340179 -52.968132) (xy 94.276169 -53.023597) (xy 94.207177 -53.072726)
			(xy 94.133827 -53.115075) (xy 94.056784 -53.150259) (xy 93.976745 -53.177961) (xy 93.894436 -53.197929)
			(xy 93.810601 -53.209982) (xy 93.726 -53.214013) (xy 93.641399 -53.209982) (xy 93.557564 -53.197929)
			(xy 93.475255 -53.177961) (xy 93.395216 -53.150259) (xy 93.318173 -53.115075) (xy 93.244823 -53.072726)
			(xy 93.175831 -53.023597) (xy 93.111821 -52.968132) (xy 93.053373 -52.906834) (xy 93.001017 -52.840258)
			(xy 92.955227 -52.769006) (xy 92.916416 -52.693725) (xy 92.884937 -52.615095) (xy 92.861076 -52.533828)
			(xy 92.845047 -52.450662) (xy 92.836996 -52.366348) (xy 92.836492 -52.324) (xy 89.154508 -52.324)
			(xy 89.154004 -52.366348) (xy 89.145953 -52.450662) (xy 89.129924 -52.533828) (xy 89.106063 -52.615095)
			(xy 89.074584 -52.693725) (xy 89.035773 -52.769006) (xy 88.989983 -52.840258) (xy 88.937627 -52.906834)
			(xy 88.879179 -52.968132) (xy 88.815169 -53.023597) (xy 88.746177 -53.072726) (xy 88.672827 -53.115075)
			(xy 88.595784 -53.150259) (xy 88.515745 -53.177961) (xy 88.433436 -53.197929) (xy 88.349601 -53.209982)
			(xy 88.265 -53.214013) (xy 88.180399 -53.209982) (xy 88.096564 -53.197929) (xy 88.014255 -53.177961)
			(xy 87.934216 -53.150259) (xy 87.857173 -53.115075) (xy 87.783823 -53.072726) (xy 87.714831 -53.023597)
			(xy 87.650821 -52.968132) (xy 87.592373 -52.906834) (xy 87.540017 -52.840258) (xy 87.494227 -52.769006)
			(xy 87.455416 -52.693725) (xy 87.423937 -52.615095) (xy 87.400076 -52.533828) (xy 87.384047 -52.450662)
			(xy 87.375996 -52.366348) (xy 87.375492 -52.324) (xy 83.693508 -52.324) (xy 83.693004 -52.366348)
			(xy 83.684953 -52.450662) (xy 83.668924 -52.533828) (xy 83.645063 -52.615095) (xy 83.613584 -52.693725)
			(xy 83.574773 -52.769006) (xy 83.528983 -52.840258) (xy 83.476627 -52.906834) (xy 83.418179 -52.968132)
			(xy 83.354169 -53.023597) (xy 83.285177 -53.072726) (xy 83.211827 -53.115075) (xy 83.134784 -53.150259)
			(xy 83.054745 -53.177961) (xy 82.972436 -53.197929) (xy 82.888601 -53.209982) (xy 82.804 -53.214013)
			(xy 82.719399 -53.209982) (xy 82.635564 -53.197929) (xy 82.553255 -53.177961) (xy 82.473216 -53.150259)
			(xy 82.396173 -53.115075) (xy 82.322823 -53.072726) (xy 82.253831 -53.023597) (xy 82.189821 -52.968132)
			(xy 82.131373 -52.906834) (xy 82.079017 -52.840258) (xy 82.033227 -52.769006) (xy 81.994416 -52.693725)
			(xy 81.962937 -52.615095) (xy 81.939076 -52.533828) (xy 81.923047 -52.450662) (xy 81.914996 -52.366348)
			(xy 81.914492 -52.324) (xy 78.232508 -52.324) (xy 78.232004 -52.366348) (xy 78.223953 -52.450662)
			(xy 78.207924 -52.533828) (xy 78.184063 -52.615095) (xy 78.152584 -52.693725) (xy 78.113773 -52.769006)
			(xy 78.067983 -52.840258) (xy 78.015627 -52.906834) (xy 77.957179 -52.968132) (xy 77.893169 -53.023597)
			(xy 77.824177 -53.072726) (xy 77.750827 -53.115075) (xy 77.673784 -53.150259) (xy 77.593745 -53.177961)
			(xy 77.511436 -53.197929) (xy 77.427601 -53.209982) (xy 77.343 -53.214013) (xy 77.258399 -53.209982)
			(xy 77.174564 -53.197929) (xy 77.092255 -53.177961) (xy 77.012216 -53.150259) (xy 76.935173 -53.115075)
			(xy 76.861823 -53.072726) (xy 76.792831 -53.023597) (xy 76.728821 -52.968132) (xy 76.670373 -52.906834)
			(xy 76.618017 -52.840258) (xy 76.572227 -52.769006) (xy 76.533416 -52.693725) (xy 76.501937 -52.615095)
			(xy 76.478076 -52.533828) (xy 76.462047 -52.450662) (xy 76.453996 -52.366348) (xy 76.453492 -52.324)
			(xy 72.771508 -52.324) (xy 72.771004 -52.366348) (xy 72.762953 -52.450662) (xy 72.746924 -52.533828)
			(xy 72.723063 -52.615095) (xy 72.691584 -52.693725) (xy 72.652773 -52.769006) (xy 72.606983 -52.840258)
			(xy 72.554627 -52.906834) (xy 72.496179 -52.968132) (xy 72.432169 -53.023597) (xy 72.363177 -53.072726)
			(xy 72.289827 -53.115075) (xy 72.212784 -53.150259) (xy 72.132745 -53.177961) (xy 72.050436 -53.197929)
			(xy 71.966601 -53.209982) (xy 71.882 -53.214013) (xy 71.797399 -53.209982) (xy 71.713564 -53.197929)
			(xy 71.631255 -53.177961) (xy 71.551216 -53.150259) (xy 71.474173 -53.115075) (xy 71.400823 -53.072726)
			(xy 71.331831 -53.023597) (xy 71.267821 -52.968132) (xy 71.209373 -52.906834) (xy 71.157017 -52.840258)
			(xy 71.111227 -52.769006) (xy 71.072416 -52.693725) (xy 71.040937 -52.615095) (xy 71.017076 -52.533828)
			(xy 71.001047 -52.450662) (xy 70.992996 -52.366348) (xy 70.992492 -52.324) (xy 51.706282 -52.324)
			(xy 51.700727 -52.350268) (xy 51.672187 -52.438562) (xy 51.653948 -52.481226) (xy 51.65014 -52.491168)
			(xy 51.65014 -52.512432) (xy 51.653948 -52.522374) (xy 51.672195 -52.565035) (xy 51.700738 -52.653328)
			(xy 51.71993 -52.744113) (xy 51.729563 -52.836404) (xy 51.730148 -52.8828) (xy 51.729633 -52.923901)
			(xy 51.722049 -53.005753) (xy 51.706945 -53.086556) (xy 51.684449 -53.165621) (xy 51.654755 -53.242273)
			(xy 51.618115 -53.315858) (xy 51.574842 -53.385749) (xy 51.525305 -53.451349) (xy 51.469927 -53.512099)
			(xy 51.40918 -53.56748) (xy 51.343582 -53.61702) (xy 51.273693 -53.660296) (xy 51.20011 -53.696939)
			(xy 51.123459 -53.726637) (xy 51.044395 -53.749136) (xy 50.963593 -53.764243) (xy 50.881741 -53.771832)
			(xy 50.84064 -53.772308) (xy 50.794245 -53.771711) (xy 50.701957 -53.76207) (xy 50.611173 -53.742878)
			(xy 50.522879 -53.714344) (xy 50.480214 -53.696108) (xy 50.470272 -53.692302) (xy 50.449008 -53.692302)
			(xy 50.439066 -53.696108) (xy 50.396398 -53.71434) (xy 50.308108 -53.742887) (xy 50.217325 -53.762084)
			(xy 50.125036 -53.771721) (xy 50.07864 -53.772308) (xy 50.032245 -53.771711) (xy 49.939957 -53.76207)
			(xy 49.849173 -53.742878) (xy 49.760879 -53.714344) (xy 49.718214 -53.696108) (xy 49.708272 -53.692302)
			(xy 49.687008 -53.692302) (xy 49.677066 -53.696108) (xy 49.634398 -53.71434) (xy 49.546108 -53.742887)
			(xy 49.455325 -53.762084) (xy 49.363036 -53.771721) (xy 49.31664 -53.772308) (xy 49.275537 -53.77181)
			(xy 49.193683 -53.764228) (xy 49.112877 -53.749126) (xy 49.033809 -53.726633) (xy 48.957154 -53.69694)
			(xy 48.883566 -53.6603) (xy 48.813673 -53.617027) (xy 48.748071 -53.567489) (xy 48.687319 -53.512109)
			(xy 48.631937 -53.45136) (xy 48.582396 -53.38576) (xy 48.53912 -53.315869) (xy 48.502477 -53.242282)
			(xy 48.47278 -53.165629) (xy 48.450283 -53.086562) (xy 48.435177 -53.005757) (xy 48.427592 -52.923902)
			(xy 48.427132 -52.8828) (xy 47.945068 -52.8828) (xy 47.945548 -52.9209) (xy 47.945044 -52.963248)
			(xy 47.936993 -53.047562) (xy 47.920964 -53.130728) (xy 47.897103 -53.211995) (xy 47.865624 -53.290625)
			(xy 47.826813 -53.365906) (xy 47.781023 -53.437158) (xy 47.728667 -53.503734) (xy 47.670219 -53.565032)
			(xy 47.606209 -53.620497) (xy 47.537217 -53.669626) (xy 47.463867 -53.711975) (xy 47.386824 -53.747159)
			(xy 47.306785 -53.774861) (xy 47.224476 -53.794829) (xy 47.140641 -53.806882) (xy 47.05604 -53.810913)
			(xy 46.971439 -53.806882) (xy 46.887604 -53.794829) (xy 46.805295 -53.774861) (xy 46.725256 -53.747159)
			(xy 46.648213 -53.711975) (xy 46.574863 -53.669626) (xy 46.505871 -53.620497) (xy 46.441861 -53.565032)
			(xy 46.383413 -53.503734) (xy 46.331057 -53.437158) (xy 46.285267 -53.365906) (xy 46.246456 -53.290625)
			(xy 46.214977 -53.211995) (xy 46.191116 -53.130728) (xy 46.175087 -53.047562) (xy 46.167036 -52.963248)
			(xy 46.166532 -52.9209) (xy 44.986526 -52.9209) (xy 44.977819 -52.930032) (xy 44.913809 -52.985497)
			(xy 44.844817 -53.034626) (xy 44.771467 -53.076975) (xy 44.694424 -53.112159) (xy 44.614385 -53.139861)
			(xy 44.532076 -53.159829) (xy 44.448241 -53.171882) (xy 44.36364 -53.175913) (xy 44.279039 -53.171882)
			(xy 44.195204 -53.159829) (xy 44.112895 -53.139861) (xy 44.032856 -53.112159) (xy 43.955813 -53.076975)
			(xy 43.882463 -53.034626) (xy 43.813471 -52.985497) (xy 43.749461 -52.930032) (xy 43.691013 -52.868734)
			(xy 43.638657 -52.802158) (xy 43.592867 -52.730906) (xy 43.554056 -52.655625) (xy 43.522577 -52.576995)
			(xy 43.498716 -52.495728) (xy 43.482687 -52.412562) (xy 43.474636 -52.328248) (xy 43.474132 -52.2859)
			(xy 0.509016 -52.2859) (xy 0.509016 -54.399942) (xy 3.446023 -54.399942) (xy 3.450044 -54.28608)
			(xy 3.462086 -54.172786) (xy 3.482091 -54.060624) (xy 3.509957 -53.950152) (xy 3.545546 -53.84192)
			(xy 3.588681 -53.736469) (xy 3.639147 -53.634323) (xy 3.696693 -53.535992) (xy 3.761032 -53.441964)
			(xy 3.831843 -53.352709) (xy 3.908773 -53.268672) (xy 3.99144 -53.19027) (xy 4.079431 -53.117895)
			(xy 4.172308 -53.051907) (xy 4.269609 -52.992635) (xy 4.370848 -52.940374) (xy 4.475522 -52.895384)
			(xy 4.583108 -52.85789) (xy 4.693071 -52.828079) (xy 4.804864 -52.806098) (xy 4.917928 -52.792058)
			(xy 5.0317 -52.786028) (xy 5.145615 -52.788039) (xy 5.259104 -52.79808) (xy 5.371603 -52.816102)
			(xy 5.482549 -52.842014) (xy 5.591392 -52.875688) (xy 5.697588 -52.916955) (xy 5.800608 -52.965611)
			(xy 5.89994 -53.021412) (xy 5.995089 -53.084081) (xy 6.085579 -53.153306) (xy 6.170961 -53.228741)
			(xy 6.25081 -53.310012) (xy 6.324727 -53.396712) (xy 6.392343 -53.48841) (xy 6.453324 -53.584649)
			(xy 6.507363 -53.684951) (xy 6.554193 -53.788814) (xy 6.59358 -53.895722) (xy 6.625327 -54.005142)
			(xy 6.649277 -54.116528) (xy 6.665311 -54.229327) (xy 6.673347 -54.342976) (xy 6.67385 -54.399942)
			(xy 6.673347 -54.456908) (xy 6.665311 -54.570557) (xy 6.649277 -54.683356) (xy 6.625327 -54.794742)
			(xy 6.59358 -54.904162) (xy 6.554193 -55.01107) (xy 6.507363 -55.114933) (xy 6.453324 -55.215235)
			(xy 6.392343 -55.311474) (xy 6.324727 -55.403172) (xy 6.25081 -55.489872) (xy 6.170961 -55.571143)
			(xy 6.090758 -55.642002) (xy 37.371528 -55.642002) (xy 37.372032 -55.599654) (xy 37.380083 -55.51534)
			(xy 37.396112 -55.432174) (xy 37.419973 -55.350907) (xy 37.451452 -55.272277) (xy 37.490263 -55.196996)
			(xy 37.536053 -55.125744) (xy 37.588409 -55.059168) (xy 37.646857 -54.99787) (xy 37.710867 -54.942405)
			(xy 37.779859 -54.893276) (xy 37.853209 -54.850927) (xy 37.930252 -54.815743) (xy 38.010291 -54.788041)
			(xy 38.0926 -54.768073) (xy 38.176435 -54.75602) (xy 38.261036 -54.75199) (xy 38.345637 -54.75602)
			(xy 38.429472 -54.768073) (xy 38.511781 -54.788041) (xy 38.59182 -54.815743) (xy 38.668863 -54.850927)
			(xy 38.742213 -54.893276) (xy 38.811205 -54.942405) (xy 38.875215 -54.99787) (xy 38.933663 -55.059168)
			(xy 38.986019 -55.125744) (xy 39.031809 -55.196996) (xy 39.07062 -55.272277) (xy 39.102099 -55.350907)
			(xy 39.12596 -55.432174) (xy 39.141989 -55.51534) (xy 39.15004 -55.599654) (xy 39.150544 -55.642002)
			(xy 39.149888 -55.692156) (xy 39.13869 -55.791837) (xy 39.128192 -55.840884) (xy 39.126403 -55.851401)
			(xy 39.130519 -55.872305) (xy 39.142729 -55.889765) (xy 39.15156 -55.895748) (xy 39.188993 -55.918893)
			(xy 39.259542 -55.971521) (xy 39.324556 -56.030851) (xy 39.383399 -56.096306) (xy 39.409878 -56.13146)
			(xy 39.416788 -56.140033) (xy 39.436031 -56.150694) (xy 39.446962 -56.152034) (xy 39.488331 -56.155768)
			(xy 39.570195 -56.169853) (xy 39.65039 -56.191507) (xy 39.728218 -56.220543) (xy 39.802999 -56.256707)
			(xy 39.874084 -56.299685) (xy 39.940853 -56.349102) (xy 40.002725 -56.404528) (xy 40.05916 -56.465481)
			(xy 40.109668 -56.531428) (xy 40.153809 -56.601797) (xy 40.191198 -56.675974) (xy 40.221509 -56.753314)
			(xy 40.244479 -56.833142) (xy 40.259907 -56.914764) (xy 40.267659 -56.997468) (xy 40.268144 -57.039002)
			(xy 40.267664 -57.082792) (xy 40.259099 -57.169952) (xy 40.242002 -57.255846) (xy 40.216539 -57.339643)
			(xy 40.182958 -57.420528) (xy 40.162734 -57.459372) (xy 40.157312 -57.470837) (xy 40.157313 -57.496166)
			(xy 40.162734 -57.507632) (xy 40.182954 -57.546475) (xy 40.216507 -57.627369) (xy 40.241955 -57.711167)
			(xy 40.259051 -57.797058) (xy 40.267631 -57.884214) (xy 40.268144 -57.928002) (xy 40.267664 -57.971792)
			(xy 40.259099 -58.058952) (xy 40.242002 -58.144846) (xy 40.216539 -58.228643) (xy 40.182958 -58.309528)
			(xy 40.162734 -58.348372) (xy 40.157312 -58.359837) (xy 40.157313 -58.385166) (xy 40.162734 -58.396632)
			(xy 40.182954 -58.435475) (xy 40.216507 -58.516369) (xy 40.241955 -58.600167) (xy 40.242899 -58.604912)
			(xy 40.474392 -58.604912) (xy 40.474903 -58.560519) (xy 40.483698 -58.472169) (xy 40.50125 -58.385135)
			(xy 40.527387 -58.300283) (xy 40.561847 -58.218457) (xy 40.582596 -58.179208) (xy 40.586434 -58.171656)
			(xy 40.589251 -58.154957) (xy 40.586406 -58.138263) (xy 40.582596 -58.130694) (xy 40.561847 -58.091445)
			(xy 40.527387 -58.009619) (xy 40.501251 -57.924767) (xy 40.483698 -57.837733) (xy 40.474903 -57.749383)
			(xy 40.474392 -57.70499) (xy 40.474894 -57.660596) (xy 40.48369 -57.572247) (xy 40.501245 -57.485213)
			(xy 40.527384 -57.400361) (xy 40.561846 -57.318535) (xy 40.582596 -57.279286) (xy 40.586376 -57.271708)
			(xy 40.589213 -57.255026) (xy 40.586393 -57.23834) (xy 40.582596 -57.230772) (xy 40.561839 -57.191527)
			(xy 40.52738 -57.1097) (xy 40.501246 -57.024847) (xy 40.483694 -56.937812) (xy 40.474902 -56.849462)
			(xy 40.474392 -56.805068) (xy 40.474941 -56.760669) (xy 40.483788 -56.672313) (xy 40.501391 -56.585278)
			(xy 40.527575 -56.500428) (xy 40.562079 -56.418608) (xy 40.58285 -56.379364) (xy 40.586655 -56.371754)
			(xy 40.589465 -56.354982) (xy 40.586644 -56.338212) (xy 40.58285 -56.330596) (xy 40.56208 -56.291351)
			(xy 40.527568 -56.209533) (xy 40.501379 -56.124684) (xy 40.483774 -56.037648) (xy 40.474928 -55.949291)
			(xy 40.474392 -55.904892) (xy 40.474795 -55.863896) (xy 40.482332 -55.782251) (xy 40.497352 -55.701646)
			(xy 40.519727 -55.622766) (xy 40.549266 -55.546279) (xy 40.585719 -55.472836) (xy 40.628776 -55.40306)
			(xy 40.678073 -55.337542) (xy 40.73319 -55.276839) (xy 40.79366 -55.221467) (xy 40.85897 -55.171895)
			(xy 40.928564 -55.128544) (xy 41.001853 -55.091782) (xy 41.078215 -55.061921) (xy 41.157 -55.039215)
			(xy 41.237541 -55.023856) (xy 41.278302 -55.019448) (xy 41.294304 -55.017924) (xy 41.318434 -54.997604)
			(xy 41.351708 -54.874922) (xy 41.341294 -54.845204) (xy 41.328086 -54.835806) (xy 41.294308 -54.810762)
			(xy 41.231103 -54.755296) (xy 41.173413 -54.694112) (xy 41.121754 -54.627759) (xy 41.076587 -54.556826)
			(xy 41.038314 -54.481948) (xy 41.007278 -54.403793) (xy 40.983755 -54.323058) (xy 40.967956 -54.240463)
			(xy 40.960021 -54.156746) (xy 40.959532 -54.1147) (xy 40.95995 -54.074933) (xy 40.96699 -53.995711)
			(xy 40.981077 -53.917434) (xy 41.002099 -53.840728) (xy 41.029886 -53.766206) (xy 41.046654 -53.730144)
			(xy 41.050985 -53.719643) (xy 41.050985 -53.696957) (xy 41.046654 -53.686456) (xy 41.029913 -53.650383)
			(xy 41.002132 -53.57586) (xy 40.981109 -53.499157) (xy 40.967012 -53.420884) (xy 40.959954 -53.341666)
			(xy 40.959532 -53.3019) (xy 40.959952 -53.260796) (xy 40.967538 -53.178938) (xy 40.982644 -53.098129)
			(xy 41.005142 -53.019059) (xy 41.03484 -52.942402) (xy 41.071485 -52.868812) (xy 41.114763 -52.798917)
			(xy 41.164306 -52.733314) (xy 41.219691 -52.672563) (xy 41.280445 -52.61718) (xy 41.34605 -52.56764)
			(xy 41.415947 -52.524365) (xy 41.489538 -52.487724) (xy 41.566197 -52.458029) (xy 41.645268 -52.435535)
			(xy 41.726077 -52.420432) (xy 41.807936 -52.41285) (xy 41.84904 -52.412392) (xy 41.893805 -52.412911)
			(xy 41.982887 -52.421844) (xy 42.07062 -52.439686) (xy 42.156115 -52.466255) (xy 42.197528 -52.483258)
			(xy 42.207119 -52.486823) (xy 42.227561 -52.486823) (xy 42.237152 -52.483258) (xy 42.278569 -52.466265)
			(xy 42.364066 -52.439708) (xy 42.451797 -52.421867) (xy 42.540876 -52.412923) (xy 42.58564 -52.412392)
			(xy 42.626743 -52.412828) (xy 42.708598 -52.420417) (xy 42.789404 -52.435526) (xy 42.868472 -52.458025)
			(xy 42.945126 -52.487724) (xy 43.018713 -52.524369) (xy 43.088605 -52.567647) (xy 43.154206 -52.617189)
			(xy 43.214955 -52.672573) (xy 43.270336 -52.733325) (xy 43.319875 -52.798928) (xy 43.36315 -52.868822)
			(xy 43.399792 -52.942411) (xy 43.429487 -53.019066) (xy 43.451984 -53.098134) (xy 43.467089 -53.178941)
			(xy 43.474673 -53.260797) (xy 43.475148 -53.3019) (xy 43.474732 -53.341667) (xy 43.467691 -53.42089)
			(xy 43.453604 -53.499166) (xy 43.432582 -53.575872) (xy 43.404794 -53.650394) (xy 43.388026 -53.686456)
			(xy 43.383691 -53.696957) (xy 43.383691 -53.719643) (xy 43.388026 -53.730144) (xy 43.404773 -53.766215)
			(xy 43.432551 -53.840738) (xy 43.453572 -53.917442) (xy 43.467668 -53.995715) (xy 43.474726 -54.074934)
			(xy 43.475148 -54.1147) (xy 43.474633 -54.155801) (xy 43.467049 -54.237653) (xy 43.451945 -54.318456)
			(xy 43.441263 -54.356) (xy 296.671492 -54.356) (xy 296.672075 -54.309604) (xy 296.68172 -54.217316)
			(xy 296.700916 -54.126532) (xy 296.729454 -54.038239) (xy 296.747692 -53.995574) (xy 296.751498 -53.985632)
			(xy 296.751498 -53.964368) (xy 296.747692 -53.954426) (xy 296.729447 -53.911764) (xy 296.700903 -53.823471)
			(xy 296.68171 -53.732686) (xy 296.672077 -53.640396) (xy 296.671492 -53.594) (xy 296.672075 -53.547604)
			(xy 296.68172 -53.455316) (xy 296.700916 -53.364532) (xy 296.729454 -53.276239) (xy 296.747692 -53.233574)
			(xy 296.751498 -53.223632) (xy 296.751498 -53.202368) (xy 296.747692 -53.192426) (xy 296.729447 -53.149764)
			(xy 296.700903 -53.061471) (xy 296.68171 -52.970686) (xy 296.672077 -52.878396) (xy 296.671492 -52.832)
			(xy 296.672075 -52.785604) (xy 296.68172 -52.693316) (xy 296.700916 -52.602532) (xy 296.729454 -52.514239)
			(xy 296.747692 -52.471574) (xy 296.751498 -52.461632) (xy 296.751498 -52.440368) (xy 296.747692 -52.430426)
			(xy 296.729447 -52.387764) (xy 296.700903 -52.299471) (xy 296.68171 -52.208686) (xy 296.672077 -52.116396)
			(xy 296.671492 -52.07) (xy 296.671967 -52.028898) (xy 296.679552 -51.947043) (xy 296.694657 -51.866238)
			(xy 296.717153 -51.787171) (xy 296.746849 -51.710517) (xy 296.783491 -51.63693) (xy 296.826766 -51.567038)
			(xy 296.876306 -51.501437) (xy 296.931687 -51.440687) (xy 296.992437 -51.385306) (xy 297.058038 -51.335766)
			(xy 297.12793 -51.292491) (xy 297.201517 -51.255849) (xy 297.278171 -51.226153) (xy 297.357238 -51.203657)
			(xy 297.438043 -51.188552) (xy 297.519898 -51.180967) (xy 297.561 -51.180492) (xy 297.607396 -51.181075)
			(xy 297.699684 -51.19072) (xy 297.790468 -51.209916) (xy 297.878761 -51.238454) (xy 297.921426 -51.256692)
			(xy 297.931368 -51.260498) (xy 297.952632 -51.260498) (xy 297.962574 -51.256692) (xy 298.005236 -51.238447)
			(xy 298.093529 -51.209903) (xy 298.184314 -51.19071) (xy 298.276604 -51.181077) (xy 298.323 -51.180492)
			(xy 298.364102 -51.180967) (xy 298.445957 -51.188552) (xy 298.526762 -51.203657) (xy 298.605829 -51.226153)
			(xy 298.682483 -51.255849) (xy 298.75607 -51.292491) (xy 298.825962 -51.335766) (xy 298.891563 -51.385306)
			(xy 298.952313 -51.440687) (xy 299.007694 -51.501437) (xy 299.057234 -51.567038) (xy 299.100509 -51.63693)
			(xy 299.137151 -51.710517) (xy 299.166847 -51.787171) (xy 299.189343 -51.866238) (xy 299.204448 -51.947043)
			(xy 299.212033 -52.028898) (xy 299.212508 -52.07) (xy 299.211925 -52.116396) (xy 299.20228 -52.208684)
			(xy 299.183084 -52.299468) (xy 299.154546 -52.387761) (xy 299.136308 -52.430426) (xy 299.132502 -52.440368)
			(xy 299.132502 -52.461632) (xy 299.136308 -52.471574) (xy 299.154553 -52.514236) (xy 299.183097 -52.602529)
			(xy 299.20229 -52.693314) (xy 299.211923 -52.785604) (xy 299.212508 -52.832) (xy 299.211925 -52.878396)
			(xy 299.20228 -52.970684) (xy 299.183084 -53.061468) (xy 299.154546 -53.149761) (xy 299.136308 -53.192426)
			(xy 299.132502 -53.202368) (xy 299.132502 -53.223632) (xy 299.136308 -53.233574) (xy 299.154553 -53.276236)
			(xy 299.183097 -53.364529) (xy 299.20229 -53.455314) (xy 299.211923 -53.547604) (xy 299.212508 -53.594)
			(xy 299.211925 -53.640396) (xy 299.20228 -53.732684) (xy 299.183084 -53.823468) (xy 299.154546 -53.911761)
			(xy 299.136308 -53.954426) (xy 299.132502 -53.964368) (xy 299.132502 -53.985632) (xy 299.136308 -53.995574)
			(xy 299.154553 -54.038236) (xy 299.183097 -54.126529) (xy 299.20229 -54.217314) (xy 299.211923 -54.309604)
			(xy 299.212508 -54.356) (xy 299.212033 -54.397102) (xy 299.204448 -54.478957) (xy 299.189343 -54.559762)
			(xy 299.166847 -54.638829) (xy 299.137151 -54.715483) (xy 299.100509 -54.78907) (xy 299.057234 -54.858962)
			(xy 299.007694 -54.924563) (xy 298.952313 -54.985313) (xy 298.891563 -55.040694) (xy 298.825962 -55.090234)
			(xy 298.75607 -55.133509) (xy 298.682483 -55.170151) (xy 298.605829 -55.199847) (xy 298.526762 -55.222343)
			(xy 298.445957 -55.237448) (xy 298.364102 -55.245033) (xy 298.323 -55.245508) (xy 298.276604 -55.244925)
			(xy 298.184316 -55.23528) (xy 298.093532 -55.216084) (xy 298.005239 -55.187546) (xy 297.962574 -55.169308)
			(xy 297.952632 -55.165502) (xy 297.931368 -55.165502) (xy 297.921426 -55.169308) (xy 297.878764 -55.187553)
			(xy 297.790471 -55.216097) (xy 297.699686 -55.23529) (xy 297.607396 -55.244923) (xy 297.561 -55.245508)
			(xy 297.519898 -55.245033) (xy 297.438043 -55.237448) (xy 297.357238 -55.222343) (xy 297.278171 -55.199847)
			(xy 297.201517 -55.170151) (xy 297.12793 -55.133509) (xy 297.058038 -55.090234) (xy 296.992437 -55.040694)
			(xy 296.931687 -54.985313) (xy 296.876306 -54.924563) (xy 296.826766 -54.858962) (xy 296.783491 -54.78907)
			(xy 296.746849 -54.715483) (xy 296.717153 -54.638829) (xy 296.694657 -54.559762) (xy 296.679552 -54.478957)
			(xy 296.671967 -54.397102) (xy 296.671492 -54.356) (xy 43.441263 -54.356) (xy 43.429449 -54.397521)
			(xy 43.399755 -54.474173) (xy 43.363115 -54.547758) (xy 43.319842 -54.617649) (xy 43.270305 -54.683249)
			(xy 43.214927 -54.743999) (xy 43.15418 -54.79938) (xy 43.088582 -54.84892) (xy 43.018693 -54.892196)
			(xy 42.94511 -54.928839) (xy 42.868459 -54.958537) (xy 42.789395 -54.981036) (xy 42.708593 -54.996143)
			(xy 42.626741 -55.003732) (xy 42.58564 -55.004208) (xy 42.540875 -55.003695) (xy 42.451793 -54.994761)
			(xy 42.36406 -54.976917) (xy 42.278565 -54.950346) (xy 42.237152 -54.933342) (xy 42.227561 -54.929777)
			(xy 42.207119 -54.929777) (xy 42.197528 -54.933342) (xy 42.182542 -54.939438) (xy 42.17275 -54.944035)
			(xy 42.157834 -54.959663) (xy 42.150643 -54.980036) (xy 42.152446 -55.001564) (xy 42.162924 -55.020457)
			(xy 42.180232 -55.033387) (xy 42.19067 -55.036212) (xy 42.232544 -55.046034) (xy 42.314349 -55.072611)
			(xy 42.393207 -55.106959) (xy 42.468382 -55.148756) (xy 42.539173 -55.197614) (xy 42.604918 -55.253075)
			(xy 42.665004 -55.314623) (xy 42.718869 -55.381682) (xy 42.766012 -55.453626) (xy 42.805991 -55.529784)
			(xy 42.838434 -55.609444) (xy 42.863037 -55.691864) (xy 42.879572 -55.776274) (xy 42.887883 -55.861885)
			(xy 42.888408 -55.904892) (xy 42.887885 -55.949292) (xy 42.879032 -56.037648) (xy 42.861423 -56.124684)
			(xy 42.835233 -56.209533) (xy 42.800723 -56.291352) (xy 42.77995 -56.330596) (xy 42.776174 -56.338218)
			(xy 42.773354 -56.354982) (xy 42.776163 -56.371748) (xy 42.77995 -56.379364) (xy 42.800704 -56.418617)
			(xy 42.835219 -56.500433) (xy 42.861411 -56.585279) (xy 42.87902 -56.672314) (xy 42.88787 -56.760669)
			(xy 42.888408 -56.805068) (xy 42.887888 -56.849461) (xy 42.879096 -56.93781) (xy 42.861545 -57.024844)
			(xy 42.83541 -57.109696) (xy 42.800952 -57.191523) (xy 42.780204 -57.230772) (xy 42.774742 -57.242292)
			(xy 42.774755 -57.267758) (xy 42.780204 -57.279286) (xy 42.800945 -57.318539) (xy 42.835407 -57.400364)
			(xy 42.861545 -57.485215) (xy 42.8791 -57.572248) (xy 42.887896 -57.660597) (xy 42.888408 -57.70499)
			(xy 42.887898 -57.749383) (xy 42.879103 -57.837733) (xy 42.86155 -57.924767) (xy 42.835413 -58.009619)
			(xy 42.800953 -58.091445) (xy 42.780204 -58.130694) (xy 42.774796 -58.142234) (xy 42.774774 -58.167681)
			(xy 42.780204 -58.179208) (xy 42.800954 -58.218457) (xy 42.835413 -58.300283) (xy 42.86155 -58.385135)
			(xy 42.879103 -58.472169) (xy 42.887897 -58.560519) (xy 42.888408 -58.604912) (xy 42.887945 -58.646015)
			(xy 42.880359 -58.727869) (xy 42.865253 -58.808675) (xy 42.842755 -58.887742) (xy 42.813058 -58.964396)
			(xy 42.776416 -59.037983) (xy 42.733139 -59.107875) (xy 42.683599 -59.173476) (xy 42.628217 -59.234226)
			(xy 42.567466 -59.289607) (xy 42.501865 -59.339146) (xy 42.431972 -59.382421) (xy 42.358385 -59.419063)
			(xy 42.28173 -59.448759) (xy 42.202663 -59.471255) (xy 42.121857 -59.48636) (xy 42.040003 -59.493945)
			(xy 41.9989 -59.49442) (xy 41.960616 -59.494032) (xy 41.884327 -59.487493) (xy 41.808885 -59.474411)
			(xy 41.734848 -59.454885) (xy 41.698672 -59.44235) (xy 41.690235 -59.439699) (xy 41.672565 -59.439699)
			(xy 41.664128 -59.44235) (xy 41.62795 -59.454876) (xy 41.55391 -59.474383) (xy 41.478469 -59.487463)
			(xy 41.402183 -59.494018) (xy 41.3639 -59.49442) (xy 41.322798 -59.493933) (xy 41.240944 -59.486349)
			(xy 41.16014 -59.471244) (xy 41.081073 -59.448748) (xy 41.00442 -59.419052) (xy 40.930834 -59.382411)
			(xy 40.860942 -59.339136) (xy 40.795341 -59.289598) (xy 40.734591 -59.234217) (xy 40.67921 -59.173468)
			(xy 40.62967 -59.107868) (xy 40.586395 -59.037977) (xy 40.549753 -58.964391) (xy 40.520056 -58.887738)
			(xy 40.497559 -58.808672) (xy 40.482453 -58.727868) (xy 40.474867 -58.646014) (xy 40.474392 -58.604912)
			(xy 40.242899 -58.604912) (xy 40.259051 -58.686058) (xy 40.267631 -58.773214) (xy 40.268144 -58.817002)
			(xy 40.267689 -58.858109) (xy 40.260105 -58.939973) (xy 40.245 -59.020789) (xy 40.222505 -59.099866)
			(xy 40.19281 -59.17653) (xy 40.156169 -59.250129) (xy 40.112895 -59.320033) (xy 40.063357 -59.385647)
			(xy 40.007977 -59.446411) (xy 39.947227 -59.501807) (xy 39.881626 -59.551363) (xy 39.811733 -59.594655)
			(xy 39.738145 -59.631315) (xy 39.661488 -59.66103) (xy 39.582416 -59.683546) (xy 39.501605 -59.698672)
			(xy 39.419743 -59.706279) (xy 39.378636 -59.706764) (xy 39.336929 -59.706247) (xy 39.253882 -59.698432)
			(xy 39.17193 -59.682877) (xy 39.091796 -59.659718) (xy 39.014181 -59.629158) (xy 38.939768 -59.591467)
			(xy 38.86921 -59.546974) (xy 38.803128 -59.496072) (xy 38.742101 -59.439206) (xy 38.686666 -59.376878)
			(xy 38.661594 -59.343544) (xy 38.654652 -59.335001) (xy 38.635433 -59.324324) (xy 38.62451 -59.32297)
			(xy 38.583139 -59.319256) (xy 38.501275 -59.305169) (xy 38.42108 -59.283512) (xy 38.343252 -59.254474)
			(xy 38.268471 -59.218308) (xy 38.197386 -59.175329) (xy 38.130618 -59.12591) (xy 38.068746 -59.070482)
			(xy 38.012311 -59.009529) (xy 37.961804 -58.94358) (xy 37.917663 -58.873211) (xy 37.880275 -58.799033)
			(xy 37.849964 -58.721692) (xy 37.826994 -58.641864) (xy 37.811565 -58.560241) (xy 37.803813 -58.477536)
			(xy 37.803328 -58.436002) (xy 37.803813 -58.392212) (xy 37.812377 -58.305053) (xy 37.829473 -58.219158)
			(xy 37.854935 -58.135362) (xy 37.888515 -58.054476) (xy 37.908738 -58.015632) (xy 37.914152 -58.004165)
			(xy 37.914153 -57.978839) (xy 37.908738 -57.967372) (xy 37.888517 -57.928529) (xy 37.854964 -57.847635)
			(xy 37.829517 -57.763837) (xy 37.812421 -57.677946) (xy 37.803841 -57.59079) (xy 37.803328 -57.547002)
			(xy 37.803813 -57.503212) (xy 37.812377 -57.416053) (xy 37.829473 -57.330158) (xy 37.854935 -57.246362)
			(xy 37.888515 -57.165476) (xy 37.908738 -57.126632) (xy 37.914152 -57.115165) (xy 37.914153 -57.089839)
			(xy 37.908738 -57.078372) (xy 37.888517 -57.039529) (xy 37.854964 -56.958635) (xy 37.829517 -56.874837)
			(xy 37.812421 -56.788946) (xy 37.803841 -56.70179) (xy 37.803328 -56.658002) (xy 37.803969 -56.607847)
			(xy 37.815177 -56.508167) (xy 37.82568 -56.45912) (xy 37.827479 -56.448604) (xy 37.823362 -56.427696)
			(xy 37.811147 -56.410236) (xy 37.802312 -56.404256) (xy 37.766912 -56.382369) (xy 37.699929 -56.332962)
			(xy 37.637853 -56.277515) (xy 37.581226 -56.216513) (xy 37.530544 -56.15049) (xy 37.48625 -56.080021)
			(xy 37.44873 -56.005724) (xy 37.418313 -55.928248) (xy 37.395264 -55.84827) (xy 37.379785 -55.766488)
			(xy 37.372012 -55.683619) (xy 37.371528 -55.642002) (xy 6.090758 -55.642002) (xy 6.085579 -55.646578)
			(xy 5.995089 -55.715803) (xy 5.89994 -55.778472) (xy 5.800608 -55.834273) (xy 5.697588 -55.882929)
			(xy 5.591392 -55.924196) (xy 5.482549 -55.95787) (xy 5.371603 -55.983782) (xy 5.259104 -56.001804)
			(xy 5.145615 -56.011845) (xy 5.0317 -56.013856) (xy 4.917928 -56.007826) (xy 4.804864 -55.993786)
			(xy 4.693071 -55.971805) (xy 4.583108 -55.941994) (xy 4.475522 -55.9045) (xy 4.370848 -55.85951)
			(xy 4.269609 -55.807249) (xy 4.172308 -55.747977) (xy 4.079431 -55.681989) (xy 3.99144 -55.609614)
			(xy 3.908773 -55.531212) (xy 3.831843 -55.447175) (xy 3.761032 -55.35792) (xy 3.696693 -55.263892)
			(xy 3.639147 -55.165561) (xy 3.588681 -55.063415) (xy 3.545546 -54.957964) (xy 3.509957 -54.849732)
			(xy 3.482091 -54.73926) (xy 3.462086 -54.627098) (xy 3.450044 -54.513804) (xy 3.446023 -54.399942)
			(xy 0.509016 -54.399942) (xy 0.509016 -60.96) (xy 66.673737 -60.96) (xy 66.677742 -60.854251) (xy 66.689732 -60.749108)
			(xy 66.709641 -60.645173) (xy 66.737352 -60.543041) (xy 66.772709 -60.443297) (xy 66.815507 -60.346513)
			(xy 66.865503 -60.253243) (xy 66.92241 -60.164022) (xy 66.985901 -60.079359) (xy 67.055613 -59.999741)
			(xy 67.131147 -59.925623) (xy 67.21207 -59.85743) (xy 67.297919 -59.795552) (xy 67.388202 -59.740345)
			(xy 67.482401 -59.692123) (xy 67.579978 -59.651163) (xy 67.680373 -59.617701) (xy 67.783011 -59.591927)
			(xy 67.887304 -59.573989) (xy 67.992655 -59.56399) (xy 68.098461 -59.561987) (xy 68.204115 -59.567992)
			(xy 68.309012 -59.581971) (xy 68.412552 -59.603842) (xy 68.514141 -59.633482) (xy 68.613198 -59.67072)
			(xy 68.709155 -59.715342) (xy 68.801462 -59.767094) (xy 68.889591 -59.825679) (xy 68.973037 -59.890761)
			(xy 69.051321 -59.961967) (xy 69.123996 -60.03889) (xy 69.190646 -60.12109) (xy 69.250888 -60.208094)
			(xy 69.304377 -60.299405) (xy 69.350808 -60.3945) (xy 69.389913 -60.492834) (xy 69.42147 -60.593845)
			(xy 69.445297 -60.696952) (xy 69.461258 -60.801566) (xy 69.469262 -60.907088) (xy 69.469762 -60.96)
			(xy 77.976737 -60.96) (xy 77.980742 -60.854251) (xy 77.992732 -60.749108) (xy 78.012641 -60.645173)
			(xy 78.040352 -60.543041) (xy 78.075709 -60.443297) (xy 78.118507 -60.346513) (xy 78.168503 -60.253243)
			(xy 78.22541 -60.164022) (xy 78.288901 -60.079359) (xy 78.358613 -59.999741) (xy 78.434147 -59.925623)
			(xy 78.51507 -59.85743) (xy 78.600919 -59.795552) (xy 78.691202 -59.740345) (xy 78.785401 -59.692123)
			(xy 78.882978 -59.651163) (xy 78.983373 -59.617701) (xy 79.086011 -59.591927) (xy 79.190304 -59.573989)
			(xy 79.295655 -59.56399) (xy 79.401461 -59.561987) (xy 79.507115 -59.567992) (xy 79.612012 -59.581971)
			(xy 79.715552 -59.603842) (xy 79.817141 -59.633482) (xy 79.916198 -59.67072) (xy 80.012155 -59.715342)
			(xy 80.104462 -59.767094) (xy 80.192591 -59.825679) (xy 80.276037 -59.890761) (xy 80.354321 -59.961967)
			(xy 80.426996 -60.03889) (xy 80.493646 -60.12109) (xy 80.553888 -60.208094) (xy 80.607377 -60.299405)
			(xy 80.653808 -60.3945) (xy 80.692913 -60.492834) (xy 80.72447 -60.593845) (xy 80.748297 -60.696952)
			(xy 80.764258 -60.801566) (xy 80.772262 -60.907088) (xy 80.772762 -60.96) (xy 89.279737 -60.96) (xy 89.283742 -60.854251)
			(xy 89.295732 -60.749108) (xy 89.315641 -60.645173) (xy 89.343352 -60.543041) (xy 89.378709 -60.443297)
			(xy 89.421507 -60.346513) (xy 89.471503 -60.253243) (xy 89.52841 -60.164022) (xy 89.591901 -60.079359)
			(xy 89.661613 -59.999741) (xy 89.737147 -59.925623) (xy 89.81807 -59.85743) (xy 89.903919 -59.795552)
			(xy 89.994202 -59.740345) (xy 90.088401 -59.692123) (xy 90.185978 -59.651163) (xy 90.286373 -59.617701)
			(xy 90.389011 -59.591927) (xy 90.493304 -59.573989) (xy 90.598655 -59.56399) (xy 90.704461 -59.561987)
			(xy 90.810115 -59.567992) (xy 90.915012 -59.581971) (xy 91.018552 -59.603842) (xy 91.120141 -59.633482)
			(xy 91.219198 -59.67072) (xy 91.315155 -59.715342) (xy 91.407462 -59.767094) (xy 91.495591 -59.825679)
			(xy 91.579037 -59.890761) (xy 91.657321 -59.961967) (xy 91.729996 -60.03889) (xy 91.796646 -60.12109)
			(xy 91.856888 -60.208094) (xy 91.910377 -60.299405) (xy 91.956808 -60.3945) (xy 91.995913 -60.492834)
			(xy 92.02747 -60.593845) (xy 92.051297 -60.696952) (xy 92.067258 -60.801566) (xy 92.075262 -60.907088)
			(xy 92.075762 -60.96) (xy 107.440737 -60.96) (xy 107.444742 -60.854251) (xy 107.456732 -60.749108)
			(xy 107.476641 -60.645173) (xy 107.504352 -60.543041) (xy 107.539709 -60.443297) (xy 107.582507 -60.346513)
			(xy 107.632503 -60.253243) (xy 107.68941 -60.164022) (xy 107.752901 -60.079359) (xy 107.822613 -59.999741)
			(xy 107.898147 -59.925623) (xy 107.97907 -59.85743) (xy 108.064919 -59.795552) (xy 108.155202 -59.740345)
			(xy 108.249401 -59.692123) (xy 108.346978 -59.651163) (xy 108.447373 -59.617701) (xy 108.550011 -59.591927)
			(xy 108.654304 -59.573989) (xy 108.759655 -59.56399) (xy 108.865461 -59.561987) (xy 108.971115 -59.567992)
			(xy 109.076012 -59.581971) (xy 109.179552 -59.603842) (xy 109.281141 -59.633482) (xy 109.380198 -59.67072)
			(xy 109.476155 -59.715342) (xy 109.568462 -59.767094) (xy 109.656591 -59.825679) (xy 109.740037 -59.890761)
			(xy 109.818321 -59.961967) (xy 109.890996 -60.03889) (xy 109.957646 -60.12109) (xy 110.017888 -60.208094)
			(xy 110.071377 -60.299405) (xy 110.117808 -60.3945) (xy 110.156913 -60.492834) (xy 110.18847 -60.593845)
			(xy 110.212297 -60.696952) (xy 110.228258 -60.801566) (xy 110.236262 -60.907088) (xy 110.236762 -60.96)
			(xy 118.616737 -60.96) (xy 118.620742 -60.854251) (xy 118.632732 -60.749108) (xy 118.652641 -60.645173)
			(xy 118.680352 -60.543041) (xy 118.715709 -60.443297) (xy 118.758507 -60.346513) (xy 118.808503 -60.253243)
			(xy 118.86541 -60.164022) (xy 118.928901 -60.079359) (xy 118.998613 -59.999741) (xy 119.074147 -59.925623)
			(xy 119.15507 -59.85743) (xy 119.240919 -59.795552) (xy 119.331202 -59.740345) (xy 119.425401 -59.692123)
			(xy 119.522978 -59.651163) (xy 119.623373 -59.617701) (xy 119.726011 -59.591927) (xy 119.830304 -59.573989)
			(xy 119.935655 -59.56399) (xy 120.041461 -59.561987) (xy 120.147115 -59.567992) (xy 120.252012 -59.581971)
			(xy 120.355552 -59.603842) (xy 120.457141 -59.633482) (xy 120.556198 -59.67072) (xy 120.652155 -59.715342)
			(xy 120.744462 -59.767094) (xy 120.832591 -59.825679) (xy 120.916037 -59.890761) (xy 120.994321 -59.961967)
			(xy 121.066996 -60.03889) (xy 121.133646 -60.12109) (xy 121.193888 -60.208094) (xy 121.247377 -60.299405)
			(xy 121.293808 -60.3945) (xy 121.332913 -60.492834) (xy 121.36447 -60.593845) (xy 121.388297 -60.696952)
			(xy 121.404258 -60.801566) (xy 121.412262 -60.907088) (xy 121.412762 -60.96) (xy 129.792737 -60.96)
			(xy 129.796742 -60.854251) (xy 129.808732 -60.749108) (xy 129.828641 -60.645173) (xy 129.856352 -60.543041)
			(xy 129.891709 -60.443297) (xy 129.934507 -60.346513) (xy 129.984503 -60.253243) (xy 130.04141 -60.164022)
			(xy 130.104901 -60.079359) (xy 130.174613 -59.999741) (xy 130.250147 -59.925623) (xy 130.33107 -59.85743)
			(xy 130.416919 -59.795552) (xy 130.507202 -59.740345) (xy 130.601401 -59.692123) (xy 130.698978 -59.651163)
			(xy 130.799373 -59.617701) (xy 130.902011 -59.591927) (xy 131.006304 -59.573989) (xy 131.111655 -59.56399)
			(xy 131.217461 -59.561987) (xy 131.323115 -59.567992) (xy 131.428012 -59.581971) (xy 131.531552 -59.603842)
			(xy 131.633141 -59.633482) (xy 131.732198 -59.67072) (xy 131.828155 -59.715342) (xy 131.920462 -59.767094)
			(xy 132.008591 -59.825679) (xy 132.092037 -59.890761) (xy 132.170321 -59.961967) (xy 132.242996 -60.03889)
			(xy 132.309646 -60.12109) (xy 132.369888 -60.208094) (xy 132.423377 -60.299405) (xy 132.469808 -60.3945)
			(xy 132.508913 -60.492834) (xy 132.54047 -60.593845) (xy 132.564297 -60.696952) (xy 132.580258 -60.801566)
			(xy 132.588262 -60.907088) (xy 132.588762 -60.96) (xy 145.540737 -60.96) (xy 145.544742 -60.854251)
			(xy 145.556732 -60.749108) (xy 145.576641 -60.645173) (xy 145.604352 -60.543041) (xy 145.639709 -60.443297)
			(xy 145.682507 -60.346513) (xy 145.732503 -60.253243) (xy 145.78941 -60.164022) (xy 145.852901 -60.079359)
			(xy 145.922613 -59.999741) (xy 145.998147 -59.925623) (xy 146.07907 -59.85743) (xy 146.164919 -59.795552)
			(xy 146.255202 -59.740345) (xy 146.349401 -59.692123) (xy 146.446978 -59.651163) (xy 146.547373 -59.617701)
			(xy 146.650011 -59.591927) (xy 146.754304 -59.573989) (xy 146.859655 -59.56399) (xy 146.965461 -59.561987)
			(xy 147.071115 -59.567992) (xy 147.176012 -59.581971) (xy 147.279552 -59.603842) (xy 147.381141 -59.633482)
			(xy 147.480198 -59.67072) (xy 147.576155 -59.715342) (xy 147.668462 -59.767094) (xy 147.756591 -59.825679)
			(xy 147.840037 -59.890761) (xy 147.918321 -59.961967) (xy 147.990996 -60.03889) (xy 148.057646 -60.12109)
			(xy 148.117888 -60.208094) (xy 148.171377 -60.299405) (xy 148.217808 -60.3945) (xy 148.256913 -60.492834)
			(xy 148.28847 -60.593845) (xy 148.312297 -60.696952) (xy 148.328258 -60.801566) (xy 148.336262 -60.907088)
			(xy 148.336762 -60.96) (xy 156.716737 -60.96) (xy 156.720742 -60.854251) (xy 156.732732 -60.749108)
			(xy 156.752641 -60.645173) (xy 156.780352 -60.543041) (xy 156.815709 -60.443297) (xy 156.858507 -60.346513)
			(xy 156.908503 -60.253243) (xy 156.96541 -60.164022) (xy 157.028901 -60.079359) (xy 157.098613 -59.999741)
			(xy 157.174147 -59.925623) (xy 157.25507 -59.85743) (xy 157.340919 -59.795552) (xy 157.431202 -59.740345)
			(xy 157.525401 -59.692123) (xy 157.622978 -59.651163) (xy 157.723373 -59.617701) (xy 157.826011 -59.591927)
			(xy 157.930304 -59.573989) (xy 158.035655 -59.56399) (xy 158.141461 -59.561987) (xy 158.247115 -59.567992)
			(xy 158.352012 -59.581971) (xy 158.455552 -59.603842) (xy 158.557141 -59.633482) (xy 158.656198 -59.67072)
			(xy 158.752155 -59.715342) (xy 158.844462 -59.767094) (xy 158.932591 -59.825679) (xy 159.016037 -59.890761)
			(xy 159.094321 -59.961967) (xy 159.166996 -60.03889) (xy 159.233646 -60.12109) (xy 159.293888 -60.208094)
			(xy 159.347377 -60.299405) (xy 159.393808 -60.3945) (xy 159.432913 -60.492834) (xy 159.46447 -60.593845)
			(xy 159.488297 -60.696952) (xy 159.504258 -60.801566) (xy 159.512262 -60.907088) (xy 159.512762 -60.96)
			(xy 167.892737 -60.96) (xy 167.896742 -60.854251) (xy 167.908732 -60.749108) (xy 167.928641 -60.645173)
			(xy 167.956352 -60.543041) (xy 167.991709 -60.443297) (xy 168.034507 -60.346513) (xy 168.084503 -60.253243)
			(xy 168.14141 -60.164022) (xy 168.204901 -60.079359) (xy 168.274613 -59.999741) (xy 168.350147 -59.925623)
			(xy 168.43107 -59.85743) (xy 168.516919 -59.795552) (xy 168.607202 -59.740345) (xy 168.701401 -59.692123)
			(xy 168.798978 -59.651163) (xy 168.899373 -59.617701) (xy 169.002011 -59.591927) (xy 169.106304 -59.573989)
			(xy 169.211655 -59.56399) (xy 169.317461 -59.561987) (xy 169.423115 -59.567992) (xy 169.528012 -59.581971)
			(xy 169.631552 -59.603842) (xy 169.733141 -59.633482) (xy 169.832198 -59.67072) (xy 169.928155 -59.715342)
			(xy 170.020462 -59.767094) (xy 170.108591 -59.825679) (xy 170.192037 -59.890761) (xy 170.270321 -59.961967)
			(xy 170.342996 -60.03889) (xy 170.409646 -60.12109) (xy 170.469888 -60.208094) (xy 170.523377 -60.299405)
			(xy 170.569808 -60.3945) (xy 170.608913 -60.492834) (xy 170.64047 -60.593845) (xy 170.664297 -60.696952)
			(xy 170.680258 -60.801566) (xy 170.688262 -60.907088) (xy 170.688762 -60.96) (xy 185.540911 -60.96)
			(xy 185.544916 -60.854251) (xy 185.556906 -60.749108) (xy 185.576815 -60.645173) (xy 185.604526 -60.543041)
			(xy 185.639883 -60.443297) (xy 185.682681 -60.346513) (xy 185.732677 -60.253243) (xy 185.789584 -60.164022)
			(xy 185.853075 -60.079359) (xy 185.922787 -59.999741) (xy 185.998321 -59.925623) (xy 186.079244 -59.85743)
			(xy 186.165093 -59.795552) (xy 186.255376 -59.740345) (xy 186.349575 -59.692123) (xy 186.447152 -59.651163)
			(xy 186.547547 -59.617701) (xy 186.650185 -59.591927) (xy 186.754478 -59.573989) (xy 186.859829 -59.56399)
			(xy 186.965635 -59.561987) (xy 187.071289 -59.567992) (xy 187.176186 -59.581971) (xy 187.279726 -59.603842)
			(xy 187.381315 -59.633482) (xy 187.480372 -59.67072) (xy 187.576329 -59.715342) (xy 187.668636 -59.767094)
			(xy 187.756765 -59.825679) (xy 187.840211 -59.890761) (xy 187.918495 -59.961967) (xy 187.99117 -60.03889)
			(xy 188.05782 -60.12109) (xy 188.118062 -60.208094) (xy 188.171551 -60.299405) (xy 188.217982 -60.3945)
			(xy 188.257087 -60.492834) (xy 188.288644 -60.593845) (xy 188.312471 -60.696952) (xy 188.328432 -60.801566)
			(xy 188.336436 -60.907088) (xy 188.336936 -60.96) (xy 196.716911 -60.96) (xy 196.720916 -60.854251)
			(xy 196.732906 -60.749108) (xy 196.752815 -60.645173) (xy 196.780526 -60.543041) (xy 196.815883 -60.443297)
			(xy 196.858681 -60.346513) (xy 196.908677 -60.253243) (xy 196.965584 -60.164022) (xy 197.029075 -60.079359)
			(xy 197.098787 -59.999741) (xy 197.174321 -59.925623) (xy 197.255244 -59.85743) (xy 197.341093 -59.795552)
			(xy 197.431376 -59.740345) (xy 197.525575 -59.692123) (xy 197.623152 -59.651163) (xy 197.723547 -59.617701)
			(xy 197.826185 -59.591927) (xy 197.930478 -59.573989) (xy 198.035829 -59.56399) (xy 198.141635 -59.561987)
			(xy 198.247289 -59.567992) (xy 198.352186 -59.581971) (xy 198.455726 -59.603842) (xy 198.557315 -59.633482)
			(xy 198.656372 -59.67072) (xy 198.752329 -59.715342) (xy 198.844636 -59.767094) (xy 198.932765 -59.825679)
			(xy 199.016211 -59.890761) (xy 199.094495 -59.961967) (xy 199.16717 -60.03889) (xy 199.23382 -60.12109)
			(xy 199.294062 -60.208094) (xy 199.347551 -60.299405) (xy 199.393982 -60.3945) (xy 199.433087 -60.492834)
			(xy 199.464644 -60.593845) (xy 199.488471 -60.696952) (xy 199.504432 -60.801566) (xy 199.512436 -60.907088)
			(xy 199.512936 -60.96) (xy 207.892911 -60.96) (xy 207.896916 -60.854251) (xy 207.908906 -60.749108)
			(xy 207.928815 -60.645173) (xy 207.956526 -60.543041) (xy 207.991883 -60.443297) (xy 208.034681 -60.346513)
			(xy 208.084677 -60.253243) (xy 208.141584 -60.164022) (xy 208.205075 -60.079359) (xy 208.274787 -59.999741)
			(xy 208.350321 -59.925623) (xy 208.431244 -59.85743) (xy 208.517093 -59.795552) (xy 208.607376 -59.740345)
			(xy 208.701575 -59.692123) (xy 208.799152 -59.651163) (xy 208.899547 -59.617701) (xy 209.002185 -59.591927)
			(xy 209.106478 -59.573989) (xy 209.211829 -59.56399) (xy 209.317635 -59.561987) (xy 209.423289 -59.567992)
			(xy 209.528186 -59.581971) (xy 209.631726 -59.603842) (xy 209.733315 -59.633482) (xy 209.832372 -59.67072)
			(xy 209.928329 -59.715342) (xy 210.020636 -59.767094) (xy 210.108765 -59.825679) (xy 210.192211 -59.890761)
			(xy 210.270495 -59.961967) (xy 210.34317 -60.03889) (xy 210.40982 -60.12109) (xy 210.470062 -60.208094)
			(xy 210.523551 -60.299405) (xy 210.569982 -60.3945) (xy 210.609087 -60.492834) (xy 210.640644 -60.593845)
			(xy 210.664471 -60.696952) (xy 210.680432 -60.801566) (xy 210.688436 -60.907088) (xy 210.688936 -60.96)
			(xy 210.688436 -61.012912) (xy 210.680432 -61.118434) (xy 210.664471 -61.223048) (xy 210.640644 -61.326155)
			(xy 210.609087 -61.427166) (xy 210.569982 -61.5255) (xy 210.523551 -61.620595) (xy 210.470062 -61.711906)
			(xy 210.40982 -61.79891) (xy 210.34317 -61.88111) (xy 210.270495 -61.958033) (xy 210.192211 -62.029239)
			(xy 210.108765 -62.094321) (xy 210.020636 -62.152906) (xy 209.928329 -62.204658) (xy 209.832372 -62.24928)
			(xy 209.733315 -62.286518) (xy 209.631726 -62.316158) (xy 209.528186 -62.338029) (xy 209.423289 -62.352008)
			(xy 209.317635 -62.358013) (xy 209.211829 -62.35601) (xy 209.106478 -62.346011) (xy 209.002185 -62.328073)
			(xy 208.899547 -62.302299) (xy 208.799152 -62.268837) (xy 208.701575 -62.227877) (xy 208.607376 -62.179655)
			(xy 208.517093 -62.124448) (xy 208.431244 -62.06257) (xy 208.350321 -61.994377) (xy 208.274787 -61.920259)
			(xy 208.205075 -61.840641) (xy 208.141584 -61.755978) (xy 208.084677 -61.666757) (xy 208.034681 -61.573487)
			(xy 207.991883 -61.476703) (xy 207.956526 -61.376959) (xy 207.928815 -61.274827) (xy 207.908906 -61.170892)
			(xy 207.896916 -61.065749) (xy 207.892911 -60.96) (xy 199.512936 -60.96) (xy 199.512436 -61.012912)
			(xy 199.504432 -61.118434) (xy 199.488471 -61.223048) (xy 199.464644 -61.326155) (xy 199.433087 -61.427166)
			(xy 199.393982 -61.5255) (xy 199.347551 -61.620595) (xy 199.294062 -61.711906) (xy 199.23382 -61.79891)
			(xy 199.16717 -61.88111) (xy 199.094495 -61.958033) (xy 199.016211 -62.029239) (xy 198.932765 -62.094321)
			(xy 198.844636 -62.152906) (xy 198.752329 -62.204658) (xy 198.656372 -62.24928) (xy 198.557315 -62.286518)
			(xy 198.455726 -62.316158) (xy 198.352186 -62.338029) (xy 198.247289 -62.352008) (xy 198.141635 -62.358013)
			(xy 198.035829 -62.35601) (xy 197.930478 -62.346011) (xy 197.826185 -62.328073) (xy 197.723547 -62.302299)
			(xy 197.623152 -62.268837) (xy 197.525575 -62.227877) (xy 197.431376 -62.179655) (xy 197.341093 -62.124448)
			(xy 197.255244 -62.06257) (xy 197.174321 -61.994377) (xy 197.098787 -61.920259) (xy 197.029075 -61.840641)
			(xy 196.965584 -61.755978) (xy 196.908677 -61.666757) (xy 196.858681 -61.573487) (xy 196.815883 -61.476703)
			(xy 196.780526 -61.376959) (xy 196.752815 -61.274827) (xy 196.732906 -61.170892) (xy 196.720916 -61.065749)
			(xy 196.716911 -60.96) (xy 188.336936 -60.96) (xy 188.336436 -61.012912) (xy 188.328432 -61.118434)
			(xy 188.312471 -61.223048) (xy 188.288644 -61.326155) (xy 188.257087 -61.427166) (xy 188.217982 -61.5255)
			(xy 188.171551 -61.620595) (xy 188.118062 -61.711906) (xy 188.05782 -61.79891) (xy 187.99117 -61.88111)
			(xy 187.918495 -61.958033) (xy 187.840211 -62.029239) (xy 187.756765 -62.094321) (xy 187.668636 -62.152906)
			(xy 187.576329 -62.204658) (xy 187.480372 -62.24928) (xy 187.381315 -62.286518) (xy 187.279726 -62.316158)
			(xy 187.176186 -62.338029) (xy 187.071289 -62.352008) (xy 186.965635 -62.358013) (xy 186.859829 -62.35601)
			(xy 186.754478 -62.346011) (xy 186.650185 -62.328073) (xy 186.547547 -62.302299) (xy 186.447152 -62.268837)
			(xy 186.349575 -62.227877) (xy 186.255376 -62.179655) (xy 186.165093 -62.124448) (xy 186.079244 -62.06257)
			(xy 185.998321 -61.994377) (xy 185.922787 -61.920259) (xy 185.853075 -61.840641) (xy 185.789584 -61.755978)
			(xy 185.732677 -61.666757) (xy 185.682681 -61.573487) (xy 185.639883 -61.476703) (xy 185.604526 -61.376959)
			(xy 185.576815 -61.274827) (xy 185.556906 -61.170892) (xy 185.544916 -61.065749) (xy 185.540911 -60.96)
			(xy 170.688762 -60.96) (xy 170.688262 -61.012912) (xy 170.680258 -61.118434) (xy 170.664297 -61.223048)
			(xy 170.64047 -61.326155) (xy 170.608913 -61.427166) (xy 170.569808 -61.5255) (xy 170.523377 -61.620595)
			(xy 170.469888 -61.711906) (xy 170.409646 -61.79891) (xy 170.342996 -61.88111) (xy 170.270321 -61.958033)
			(xy 170.192037 -62.029239) (xy 170.108591 -62.094321) (xy 170.020462 -62.152906) (xy 169.928155 -62.204658)
			(xy 169.832198 -62.24928) (xy 169.733141 -62.286518) (xy 169.631552 -62.316158) (xy 169.528012 -62.338029)
			(xy 169.423115 -62.352008) (xy 169.317461 -62.358013) (xy 169.211655 -62.35601) (xy 169.106304 -62.346011)
			(xy 169.002011 -62.328073) (xy 168.899373 -62.302299) (xy 168.798978 -62.268837) (xy 168.701401 -62.227877)
			(xy 168.607202 -62.179655) (xy 168.516919 -62.124448) (xy 168.43107 -62.06257) (xy 168.350147 -61.994377)
			(xy 168.274613 -61.920259) (xy 168.204901 -61.840641) (xy 168.14141 -61.755978) (xy 168.084503 -61.666757)
			(xy 168.034507 -61.573487) (xy 167.991709 -61.476703) (xy 167.956352 -61.376959) (xy 167.928641 -61.274827)
			(xy 167.908732 -61.170892) (xy 167.896742 -61.065749) (xy 167.892737 -60.96) (xy 159.512762 -60.96)
			(xy 159.512262 -61.012912) (xy 159.504258 -61.118434) (xy 159.488297 -61.223048) (xy 159.46447 -61.326155)
			(xy 159.432913 -61.427166) (xy 159.393808 -61.5255) (xy 159.347377 -61.620595) (xy 159.293888 -61.711906)
			(xy 159.233646 -61.79891) (xy 159.166996 -61.88111) (xy 159.094321 -61.958033) (xy 159.016037 -62.029239)
			(xy 158.932591 -62.094321) (xy 158.844462 -62.152906) (xy 158.752155 -62.204658) (xy 158.656198 -62.24928)
			(xy 158.557141 -62.286518) (xy 158.455552 -62.316158) (xy 158.352012 -62.338029) (xy 158.247115 -62.352008)
			(xy 158.141461 -62.358013) (xy 158.035655 -62.35601) (xy 157.930304 -62.346011) (xy 157.826011 -62.328073)
			(xy 157.723373 -62.302299) (xy 157.622978 -62.268837) (xy 157.525401 -62.227877) (xy 157.431202 -62.179655)
			(xy 157.340919 -62.124448) (xy 157.25507 -62.06257) (xy 157.174147 -61.994377) (xy 157.098613 -61.920259)
			(xy 157.028901 -61.840641) (xy 156.96541 -61.755978) (xy 156.908503 -61.666757) (xy 156.858507 -61.573487)
			(xy 156.815709 -61.476703) (xy 156.780352 -61.376959) (xy 156.752641 -61.274827) (xy 156.732732 -61.170892)
			(xy 156.720742 -61.065749) (xy 156.716737 -60.96) (xy 148.336762 -60.96) (xy 148.336262 -61.012912)
			(xy 148.328258 -61.118434) (xy 148.312297 -61.223048) (xy 148.28847 -61.326155) (xy 148.256913 -61.427166)
			(xy 148.217808 -61.5255) (xy 148.171377 -61.620595) (xy 148.117888 -61.711906) (xy 148.057646 -61.79891)
			(xy 147.990996 -61.88111) (xy 147.918321 -61.958033) (xy 147.840037 -62.029239) (xy 147.756591 -62.094321)
			(xy 147.668462 -62.152906) (xy 147.576155 -62.204658) (xy 147.480198 -62.24928) (xy 147.381141 -62.286518)
			(xy 147.279552 -62.316158) (xy 147.176012 -62.338029) (xy 147.071115 -62.352008) (xy 146.965461 -62.358013)
			(xy 146.859655 -62.35601) (xy 146.754304 -62.346011) (xy 146.650011 -62.328073) (xy 146.547373 -62.302299)
			(xy 146.446978 -62.268837) (xy 146.349401 -62.227877) (xy 146.255202 -62.179655) (xy 146.164919 -62.124448)
			(xy 146.07907 -62.06257) (xy 145.998147 -61.994377) (xy 145.922613 -61.920259) (xy 145.852901 -61.840641)
			(xy 145.78941 -61.755978) (xy 145.732503 -61.666757) (xy 145.682507 -61.573487) (xy 145.639709 -61.476703)
			(xy 145.604352 -61.376959) (xy 145.576641 -61.274827) (xy 145.556732 -61.170892) (xy 145.544742 -61.065749)
			(xy 145.540737 -60.96) (xy 132.588762 -60.96) (xy 132.588262 -61.012912) (xy 132.580258 -61.118434)
			(xy 132.564297 -61.223048) (xy 132.54047 -61.326155) (xy 132.508913 -61.427166) (xy 132.469808 -61.5255)
			(xy 132.423377 -61.620595) (xy 132.369888 -61.711906) (xy 132.309646 -61.79891) (xy 132.242996 -61.88111)
			(xy 132.170321 -61.958033) (xy 132.092037 -62.029239) (xy 132.008591 -62.094321) (xy 131.920462 -62.152906)
			(xy 131.828155 -62.204658) (xy 131.732198 -62.24928) (xy 131.633141 -62.286518) (xy 131.531552 -62.316158)
			(xy 131.428012 -62.338029) (xy 131.323115 -62.352008) (xy 131.217461 -62.358013) (xy 131.111655 -62.35601)
			(xy 131.006304 -62.346011) (xy 130.902011 -62.328073) (xy 130.799373 -62.302299) (xy 130.698978 -62.268837)
			(xy 130.601401 -62.227877) (xy 130.507202 -62.179655) (xy 130.416919 -62.124448) (xy 130.33107 -62.06257)
			(xy 130.250147 -61.994377) (xy 130.174613 -61.920259) (xy 130.104901 -61.840641) (xy 130.04141 -61.755978)
			(xy 129.984503 -61.666757) (xy 129.934507 -61.573487) (xy 129.891709 -61.476703) (xy 129.856352 -61.376959)
			(xy 129.828641 -61.274827) (xy 129.808732 -61.170892) (xy 129.796742 -61.065749) (xy 129.792737 -60.96)
			(xy 121.412762 -60.96) (xy 121.412262 -61.012912) (xy 121.404258 -61.118434) (xy 121.388297 -61.223048)
			(xy 121.36447 -61.326155) (xy 121.332913 -61.427166) (xy 121.293808 -61.5255) (xy 121.247377 -61.620595)
			(xy 121.193888 -61.711906) (xy 121.133646 -61.79891) (xy 121.066996 -61.88111) (xy 120.994321 -61.958033)
			(xy 120.916037 -62.029239) (xy 120.832591 -62.094321) (xy 120.744462 -62.152906) (xy 120.652155 -62.204658)
			(xy 120.556198 -62.24928) (xy 120.457141 -62.286518) (xy 120.355552 -62.316158) (xy 120.252012 -62.338029)
			(xy 120.147115 -62.352008) (xy 120.041461 -62.358013) (xy 119.935655 -62.35601) (xy 119.830304 -62.346011)
			(xy 119.726011 -62.328073) (xy 119.623373 -62.302299) (xy 119.522978 -62.268837) (xy 119.425401 -62.227877)
			(xy 119.331202 -62.179655) (xy 119.240919 -62.124448) (xy 119.15507 -62.06257) (xy 119.074147 -61.994377)
			(xy 118.998613 -61.920259) (xy 118.928901 -61.840641) (xy 118.86541 -61.755978) (xy 118.808503 -61.666757)
			(xy 118.758507 -61.573487) (xy 118.715709 -61.476703) (xy 118.680352 -61.376959) (xy 118.652641 -61.274827)
			(xy 118.632732 -61.170892) (xy 118.620742 -61.065749) (xy 118.616737 -60.96) (xy 110.236762 -60.96)
			(xy 110.236262 -61.012912) (xy 110.228258 -61.118434) (xy 110.212297 -61.223048) (xy 110.18847 -61.326155)
			(xy 110.156913 -61.427166) (xy 110.117808 -61.5255) (xy 110.071377 -61.620595) (xy 110.017888 -61.711906)
			(xy 109.957646 -61.79891) (xy 109.890996 -61.88111) (xy 109.818321 -61.958033) (xy 109.740037 -62.029239)
			(xy 109.656591 -62.094321) (xy 109.568462 -62.152906) (xy 109.476155 -62.204658) (xy 109.380198 -62.24928)
			(xy 109.281141 -62.286518) (xy 109.179552 -62.316158) (xy 109.076012 -62.338029) (xy 108.971115 -62.352008)
			(xy 108.865461 -62.358013) (xy 108.759655 -62.35601) (xy 108.654304 -62.346011) (xy 108.550011 -62.328073)
			(xy 108.447373 -62.302299) (xy 108.346978 -62.268837) (xy 108.249401 -62.227877) (xy 108.155202 -62.179655)
			(xy 108.064919 -62.124448) (xy 107.97907 -62.06257) (xy 107.898147 -61.994377) (xy 107.822613 -61.920259)
			(xy 107.752901 -61.840641) (xy 107.68941 -61.755978) (xy 107.632503 -61.666757) (xy 107.582507 -61.573487)
			(xy 107.539709 -61.476703) (xy 107.504352 -61.376959) (xy 107.476641 -61.274827) (xy 107.456732 -61.170892)
			(xy 107.444742 -61.065749) (xy 107.440737 -60.96) (xy 92.075762 -60.96) (xy 92.075262 -61.012912)
			(xy 92.067258 -61.118434) (xy 92.051297 -61.223048) (xy 92.02747 -61.326155) (xy 91.995913 -61.427166)
			(xy 91.956808 -61.5255) (xy 91.910377 -61.620595) (xy 91.856888 -61.711906) (xy 91.796646 -61.79891)
			(xy 91.729996 -61.88111) (xy 91.657321 -61.958033) (xy 91.579037 -62.029239) (xy 91.495591 -62.094321)
			(xy 91.407462 -62.152906) (xy 91.315155 -62.204658) (xy 91.219198 -62.24928) (xy 91.120141 -62.286518)
			(xy 91.018552 -62.316158) (xy 90.915012 -62.338029) (xy 90.810115 -62.352008) (xy 90.704461 -62.358013)
			(xy 90.598655 -62.35601) (xy 90.493304 -62.346011) (xy 90.389011 -62.328073) (xy 90.286373 -62.302299)
			(xy 90.185978 -62.268837) (xy 90.088401 -62.227877) (xy 89.994202 -62.179655) (xy 89.903919 -62.124448)
			(xy 89.81807 -62.06257) (xy 89.737147 -61.994377) (xy 89.661613 -61.920259) (xy 89.591901 -61.840641)
			(xy 89.52841 -61.755978) (xy 89.471503 -61.666757) (xy 89.421507 -61.573487) (xy 89.378709 -61.476703)
			(xy 89.343352 -61.376959) (xy 89.315641 -61.274827) (xy 89.295732 -61.170892) (xy 89.283742 -61.065749)
			(xy 89.279737 -60.96) (xy 80.772762 -60.96) (xy 80.772262 -61.012912) (xy 80.764258 -61.118434) (xy 80.748297 -61.223048)
			(xy 80.72447 -61.326155) (xy 80.692913 -61.427166) (xy 80.653808 -61.5255) (xy 80.607377 -61.620595)
			(xy 80.553888 -61.711906) (xy 80.493646 -61.79891) (xy 80.426996 -61.88111) (xy 80.354321 -61.958033)
			(xy 80.276037 -62.029239) (xy 80.192591 -62.094321) (xy 80.104462 -62.152906) (xy 80.012155 -62.204658)
			(xy 79.916198 -62.24928) (xy 79.817141 -62.286518) (xy 79.715552 -62.316158) (xy 79.612012 -62.338029)
			(xy 79.507115 -62.352008) (xy 79.401461 -62.358013) (xy 79.295655 -62.35601) (xy 79.190304 -62.346011)
			(xy 79.086011 -62.328073) (xy 78.983373 -62.302299) (xy 78.882978 -62.268837) (xy 78.785401 -62.227877)
			(xy 78.691202 -62.179655) (xy 78.600919 -62.124448) (xy 78.51507 -62.06257) (xy 78.434147 -61.994377)
			(xy 78.358613 -61.920259) (xy 78.288901 -61.840641) (xy 78.22541 -61.755978) (xy 78.168503 -61.666757)
			(xy 78.118507 -61.573487) (xy 78.075709 -61.476703) (xy 78.040352 -61.376959) (xy 78.012641 -61.274827)
			(xy 77.992732 -61.170892) (xy 77.980742 -61.065749) (xy 77.976737 -60.96) (xy 69.469762 -60.96) (xy 69.469262 -61.012912)
			(xy 69.461258 -61.118434) (xy 69.445297 -61.223048) (xy 69.42147 -61.326155) (xy 69.389913 -61.427166)
			(xy 69.350808 -61.5255) (xy 69.304377 -61.620595) (xy 69.250888 -61.711906) (xy 69.190646 -61.79891)
			(xy 69.123996 -61.88111) (xy 69.051321 -61.958033) (xy 68.973037 -62.029239) (xy 68.889591 -62.094321)
			(xy 68.801462 -62.152906) (xy 68.709155 -62.204658) (xy 68.613198 -62.24928) (xy 68.514141 -62.286518)
			(xy 68.412552 -62.316158) (xy 68.309012 -62.338029) (xy 68.204115 -62.352008) (xy 68.098461 -62.358013)
			(xy 67.992655 -62.35601) (xy 67.887304 -62.346011) (xy 67.783011 -62.328073) (xy 67.680373 -62.302299)
			(xy 67.579978 -62.268837) (xy 67.482401 -62.227877) (xy 67.388202 -62.179655) (xy 67.297919 -62.124448)
			(xy 67.21207 -62.06257) (xy 67.131147 -61.994377) (xy 67.055613 -61.920259) (xy 66.985901 -61.840641)
			(xy 66.92241 -61.755978) (xy 66.865503 -61.666757) (xy 66.815507 -61.573487) (xy 66.772709 -61.476703)
			(xy 66.737352 -61.376959) (xy 66.709641 -61.274827) (xy 66.689732 -61.170892) (xy 66.677742 -61.065749)
			(xy 66.673737 -60.96) (xy 0.509016 -60.96) (xy 0.509016 -62.203781) (xy 38.440102 -62.203781) (xy 38.440102 -62.119059)
			(xy 38.448155 -62.034722) (xy 38.464189 -61.951532) (xy 38.488057 -61.870242) (xy 38.519545 -61.79159)
			(xy 38.558367 -61.716287) (xy 38.60417 -61.645015) (xy 38.656541 -61.578419) (xy 38.715006 -61.517104)
			(xy 38.779034 -61.461623) (xy 38.848046 -61.41248) (xy 38.921416 -61.37012) (xy 38.998481 -61.334925)
			(xy 39.078543 -61.307216) (xy 39.160876 -61.287242) (xy 39.244735 -61.275185) (xy 39.32936 -61.271154)
			(xy 39.413985 -61.275185) (xy 39.497844 -61.287242) (xy 39.580177 -61.307216) (xy 39.660239 -61.334925)
			(xy 39.737304 -61.37012) (xy 39.810674 -61.41248) (xy 39.879686 -61.461623) (xy 39.943714 -61.517104)
			(xy 40.002179 -61.578419) (xy 40.05455 -61.645015) (xy 40.100353 -61.716287) (xy 40.139175 -61.79159)
			(xy 40.170663 -61.870242) (xy 40.194531 -61.951532) (xy 40.210565 -62.034722) (xy 40.218618 -62.119059)
			(xy 40.219122 -62.16142) (xy 40.218618 -62.203781) (xy 40.210565 -62.288118) (xy 40.194531 -62.371308)
			(xy 40.170663 -62.452598) (xy 40.139175 -62.53125) (xy 40.100353 -62.606553) (xy 40.05455 -62.677825)
			(xy 40.002179 -62.744421) (xy 39.943714 -62.805736) (xy 39.879686 -62.861217) (xy 39.810674 -62.91036)
			(xy 39.737304 -62.95272) (xy 39.660239 -62.987915) (xy 39.580177 -63.015624) (xy 39.497844 -63.035598)
			(xy 39.413985 -63.047655) (xy 39.32936 -63.051687) (xy 39.244735 -63.047655) (xy 39.160876 -63.035598)
			(xy 39.078543 -63.015624) (xy 38.998481 -62.987915) (xy 38.921416 -62.95272) (xy 38.848046 -62.91036)
			(xy 38.779034 -62.861217) (xy 38.715006 -62.805736) (xy 38.656541 -62.744421) (xy 38.60417 -62.677825)
			(xy 38.558367 -62.606553) (xy 38.519545 -62.53125) (xy 38.488057 -62.452598) (xy 38.464189 -62.371308)
			(xy 38.448155 -62.288118) (xy 38.440102 -62.203781) (xy 0.509016 -62.203781) (xy 0.509016 -66.43624)
			(xy 26.694892 -66.43624) (xy 26.695489 -66.389845) (xy 26.70513 -66.297557) (xy 26.724322 -66.206773)
			(xy 26.752856 -66.118479) (xy 26.771092 -66.075814) (xy 26.774874 -66.065864) (xy 26.774889 -66.044608)
			(xy 26.771092 -66.034666) (xy 26.75286 -65.991998) (xy 26.724313 -65.903708) (xy 26.705116 -65.812925)
			(xy 26.695479 -65.720636) (xy 26.694892 -65.67424) (xy 26.695489 -65.627845) (xy 26.70513 -65.535557)
			(xy 26.724322 -65.444773) (xy 26.752856 -65.356479) (xy 26.771092 -65.313814) (xy 26.774874 -65.303864)
			(xy 26.774889 -65.282608) (xy 26.771092 -65.272666) (xy 26.75286 -65.229998) (xy 26.724313 -65.141708)
			(xy 26.705116 -65.050925) (xy 26.695479 -64.958636) (xy 26.694892 -64.91224) (xy 26.69539 -64.871137)
			(xy 26.702972 -64.789283) (xy 26.718074 -64.708477) (xy 26.740567 -64.629409) (xy 26.77026 -64.552754)
			(xy 26.8069 -64.479166) (xy 26.850173 -64.409273) (xy 26.899711 -64.343671) (xy 26.955091 -64.282919)
			(xy 27.01584 -64.227537) (xy 27.08144 -64.177996) (xy 27.151331 -64.13472) (xy 27.224918 -64.098077)
			(xy 27.301571 -64.06838) (xy 27.380638 -64.045883) (xy 27.461443 -64.030777) (xy 27.543298 -64.023192)
			(xy 27.5844 -64.022732) (xy 27.630796 -64.023311) (xy 27.723084 -64.032957) (xy 27.813868 -64.052154)
			(xy 27.902161 -64.080693) (xy 27.944826 -64.098932) (xy 27.954768 -64.102738) (xy 27.976032 -64.102738)
			(xy 27.985974 -64.098932) (xy 28.028637 -64.08069) (xy 28.116929 -64.052144) (xy 28.207714 -64.032951)
			(xy 28.300004 -64.023317) (xy 28.3464 -64.022732) (xy 28.387504 -64.023152) (xy 28.469362 -64.030738)
			(xy 28.550171 -64.045844) (xy 28.629241 -64.068342) (xy 28.705898 -64.09804) (xy 28.779488 -64.134685)
			(xy 28.849383 -64.177963) (xy 28.914986 -64.227506) (xy 28.975737 -64.282891) (xy 29.03112 -64.343645)
			(xy 29.08066 -64.40925) (xy 29.123935 -64.479147) (xy 29.160576 -64.552738) (xy 29.190271 -64.629397)
			(xy 29.212765 -64.708468) (xy 29.227868 -64.789277) (xy 29.23545 -64.871136) (xy 29.235908 -64.91224)
			(xy 29.235304 -64.958635) (xy 29.225665 -65.050923) (xy 29.206475 -65.141707) (xy 29.177943 -65.230001)
			(xy 29.159708 -65.272666) (xy 29.155879 -65.282601) (xy 29.155894 -65.303871) (xy 29.159708 -65.313814)
			(xy 29.177966 -65.356471) (xy 29.206507 -65.444765) (xy 29.224945 -65.532) (xy 268.350492 -65.532)
			(xy 268.351075 -65.485604) (xy 268.36072 -65.393316) (xy 268.379916 -65.302532) (xy 268.408454 -65.214239)
			(xy 268.426692 -65.171574) (xy 268.430498 -65.161632) (xy 268.430498 -65.140368) (xy 268.426692 -65.130426)
			(xy 268.408447 -65.087764) (xy 268.379903 -64.999471) (xy 268.36071 -64.908686) (xy 268.351077 -64.816396)
			(xy 268.350492 -64.77) (xy 268.351075 -64.723604) (xy 268.36072 -64.631316) (xy 268.379916 -64.540532)
			(xy 268.408454 -64.452239) (xy 268.426692 -64.409574) (xy 268.430498 -64.399632) (xy 268.430498 -64.378368)
			(xy 268.426692 -64.368426) (xy 268.408447 -64.325764) (xy 268.379903 -64.237471) (xy 268.36071 -64.146686)
			(xy 268.351077 -64.054396) (xy 268.350492 -64.008) (xy 268.351075 -63.961604) (xy 268.36072 -63.869316)
			(xy 268.379916 -63.778532) (xy 268.408454 -63.690239) (xy 268.426692 -63.647574) (xy 268.430498 -63.637632)
			(xy 268.430498 -63.616368) (xy 268.426692 -63.606426) (xy 268.408447 -63.563764) (xy 268.379903 -63.475471)
			(xy 268.36071 -63.384686) (xy 268.351077 -63.292396) (xy 268.350492 -63.246) (xy 268.351075 -63.199604)
			(xy 268.36072 -63.107316) (xy 268.379916 -63.016532) (xy 268.408454 -62.928239) (xy 268.426692 -62.885574)
			(xy 268.430498 -62.875632) (xy 268.430498 -62.854368) (xy 268.426692 -62.844426) (xy 268.408447 -62.801764)
			(xy 268.379903 -62.713471) (xy 268.36071 -62.622686) (xy 268.351077 -62.530396) (xy 268.350492 -62.484)
			(xy 268.351075 -62.437604) (xy 268.36072 -62.345316) (xy 268.379916 -62.254532) (xy 268.408454 -62.166239)
			(xy 268.426692 -62.123574) (xy 268.430498 -62.113632) (xy 268.430498 -62.092368) (xy 268.426692 -62.082426)
			(xy 268.408447 -62.039764) (xy 268.379903 -61.951471) (xy 268.36071 -61.860686) (xy 268.351077 -61.768396)
			(xy 268.350492 -61.722) (xy 268.350967 -61.680898) (xy 268.358552 -61.599043) (xy 268.373657 -61.518238)
			(xy 268.396153 -61.439171) (xy 268.425849 -61.362517) (xy 268.462491 -61.28893) (xy 268.505766 -61.219038)
			(xy 268.555306 -61.153437) (xy 268.610687 -61.092687) (xy 268.671437 -61.037306) (xy 268.737038 -60.987766)
			(xy 268.80693 -60.944491) (xy 268.880517 -60.907849) (xy 268.957171 -60.878153) (xy 269.036238 -60.855657)
			(xy 269.117043 -60.840552) (xy 269.198898 -60.832967) (xy 269.24 -60.832492) (xy 269.286396 -60.833075)
			(xy 269.378684 -60.84272) (xy 269.469468 -60.861916) (xy 269.557761 -60.890454) (xy 269.600426 -60.908692)
			(xy 269.610368 -60.912498) (xy 269.631632 -60.912498) (xy 269.641574 -60.908692) (xy 269.684236 -60.890447)
			(xy 269.772529 -60.861903) (xy 269.863314 -60.84271) (xy 269.955604 -60.833077) (xy 270.002 -60.832492)
			(xy 270.048396 -60.833075) (xy 270.140684 -60.84272) (xy 270.231468 -60.861916) (xy 270.319761 -60.890454)
			(xy 270.362426 -60.908692) (xy 270.372368 -60.912498) (xy 270.393632 -60.912498) (xy 270.403574 -60.908692)
			(xy 270.446236 -60.890447) (xy 270.534529 -60.861903) (xy 270.625314 -60.84271) (xy 270.717604 -60.833077)
			(xy 270.764 -60.832492) (xy 270.810396 -60.833075) (xy 270.902684 -60.84272) (xy 270.993468 -60.861916)
			(xy 271.081761 -60.890454) (xy 271.124426 -60.908692) (xy 271.134368 -60.912498) (xy 271.155632 -60.912498)
			(xy 271.165574 -60.908692) (xy 271.208236 -60.890447) (xy 271.296529 -60.861903) (xy 271.387314 -60.84271)
			(xy 271.479604 -60.833077) (xy 271.526 -60.832492) (xy 271.572396 -60.833075) (xy 271.664684 -60.84272)
			(xy 271.755468 -60.861916) (xy 271.843761 -60.890454) (xy 271.886426 -60.908692) (xy 271.896368 -60.912498)
			(xy 271.917632 -60.912498) (xy 271.927574 -60.908692) (xy 271.970236 -60.890447) (xy 272.058529 -60.861903)
			(xy 272.149314 -60.84271) (xy 272.241604 -60.833077) (xy 272.288 -60.832492) (xy 272.329102 -60.832967)
			(xy 272.410957 -60.840552) (xy 272.491762 -60.855657) (xy 272.570829 -60.878153) (xy 272.647483 -60.907849)
			(xy 272.72107 -60.944491) (xy 272.790962 -60.987766) (xy 272.856563 -61.037306) (xy 272.917313 -61.092687)
			(xy 272.972694 -61.153437) (xy 273.022234 -61.219038) (xy 273.065509 -61.28893) (xy 273.102151 -61.362517)
			(xy 273.131847 -61.439171) (xy 273.154343 -61.518238) (xy 273.169448 -61.599043) (xy 273.177033 -61.680898)
			(xy 273.177508 -61.722) (xy 273.176925 -61.768396) (xy 273.16728 -61.860684) (xy 273.148084 -61.951468)
			(xy 273.119546 -62.039761) (xy 273.101308 -62.082426) (xy 273.097502 -62.092368) (xy 273.097502 -62.113632)
			(xy 273.101308 -62.123574) (xy 273.119553 -62.166236) (xy 273.148097 -62.254529) (xy 273.16729 -62.345314)
			(xy 273.176923 -62.437604) (xy 273.177508 -62.484) (xy 273.177033 -62.525102) (xy 273.169448 -62.606957)
			(xy 273.154343 -62.687762) (xy 273.131847 -62.766829) (xy 273.102151 -62.843483) (xy 273.065509 -62.91707)
			(xy 273.022234 -62.986962) (xy 272.972694 -63.052563) (xy 272.917313 -63.113313) (xy 272.856563 -63.168694)
			(xy 272.790962 -63.218234) (xy 272.72107 -63.261509) (xy 272.647483 -63.298151) (xy 272.570829 -63.327847)
			(xy 272.491762 -63.350343) (xy 272.410957 -63.365448) (xy 272.329102 -63.373033) (xy 272.288 -63.373508)
			(xy 272.241604 -63.372925) (xy 272.149316 -63.36328) (xy 272.058532 -63.344084) (xy 271.970239 -63.315546)
			(xy 271.927574 -63.297308) (xy 271.917632 -63.293502) (xy 271.896368 -63.293502) (xy 271.886426 -63.297308)
			(xy 271.853507 -63.311537) (xy 271.785822 -63.335257) (xy 271.716442 -63.353437) (xy 271.681194 -63.360046)
			(xy 271.67107 -63.362344) (xy 271.653749 -63.373749) (xy 271.642344 -63.39107) (xy 271.640046 -63.401194)
			(xy 271.633416 -63.436437) (xy 271.61522 -63.50581) (xy 271.591513 -63.573498) (xy 271.577308 -63.606426)
			(xy 271.573502 -63.616368) (xy 271.573502 -63.637632) (xy 271.577308 -63.647574) (xy 271.591537 -63.680493)
			(xy 271.615257 -63.748178) (xy 271.633437 -63.817558) (xy 271.640046 -63.852806) (xy 271.642344 -63.86293)
			(xy 271.653749 -63.880251) (xy 271.67107 -63.891656) (xy 271.681194 -63.893954) (xy 271.716437 -63.900584)
			(xy 271.78581 -63.91878) (xy 271.853498 -63.942487) (xy 271.886426 -63.956692) (xy 271.896368 -63.960498)
			(xy 271.917632 -63.960498) (xy 271.927574 -63.956692) (xy 271.970236 -63.938447) (xy 272.058529 -63.909903)
			(xy 272.149314 -63.89071) (xy 272.241604 -63.881077) (xy 272.288 -63.880492) (xy 272.329102 -63.880967)
			(xy 272.410957 -63.888552) (xy 272.491762 -63.903657) (xy 272.570829 -63.926153) (xy 272.647483 -63.955849)
			(xy 272.72107 -63.992491) (xy 272.790962 -64.035766) (xy 272.856563 -64.085306) (xy 272.917313 -64.140687)
			(xy 272.972694 -64.201437) (xy 273.022234 -64.267038) (xy 273.065509 -64.33693) (xy 273.102151 -64.410517)
			(xy 273.131847 -64.487171) (xy 273.154343 -64.566238) (xy 273.169448 -64.647043) (xy 273.177033 -64.728898)
			(xy 273.177508 -64.77) (xy 273.176925 -64.816396) (xy 273.16728 -64.908684) (xy 273.148084 -64.999468)
			(xy 273.119546 -65.087761) (xy 273.101308 -65.130426) (xy 273.097502 -65.140368) (xy 273.097502 -65.161632)
			(xy 273.101308 -65.171574) (xy 273.119553 -65.214236) (xy 273.148097 -65.302529) (xy 273.16729 -65.393314)
			(xy 273.176923 -65.485604) (xy 273.177508 -65.532) (xy 273.177033 -65.573102) (xy 273.169448 -65.654957)
			(xy 273.154343 -65.735762) (xy 273.131847 -65.814829) (xy 273.102151 -65.891483) (xy 273.065509 -65.96507)
			(xy 273.022234 -66.034962) (xy 272.972694 -66.100563) (xy 272.917313 -66.161313) (xy 272.856563 -66.216694)
			(xy 272.790962 -66.266234) (xy 272.72107 -66.309509) (xy 272.647483 -66.346151) (xy 272.570829 -66.375847)
			(xy 272.491762 -66.398343) (xy 272.410957 -66.413448) (xy 272.329102 -66.421033) (xy 272.288 -66.421508)
			(xy 272.241604 -66.420925) (xy 272.149316 -66.41128) (xy 272.058532 -66.392084) (xy 271.970239 -66.363546)
			(xy 271.927574 -66.345308) (xy 271.917632 -66.341502) (xy 271.896368 -66.341502) (xy 271.886426 -66.345308)
			(xy 271.843764 -66.363553) (xy 271.755471 -66.392097) (xy 271.664686 -66.41129) (xy 271.572396 -66.420923)
			(xy 271.526 -66.421508) (xy 271.479604 -66.420925) (xy 271.387316 -66.41128) (xy 271.296532 -66.392084)
			(xy 271.208239 -66.363546) (xy 271.165574 -66.345308) (xy 271.155632 -66.341502) (xy 271.134368 -66.341502)
			(xy 271.124426 -66.345308) (xy 271.081764 -66.363553) (xy 270.993471 -66.392097) (xy 270.902686 -66.41129)
			(xy 270.810396 -66.420923) (xy 270.764 -66.421508) (xy 270.717604 -66.420925) (xy 270.625316 -66.41128)
			(xy 270.534532 -66.392084) (xy 270.446239 -66.363546) (xy 270.403574 -66.345308) (xy 270.393632 -66.341502)
			(xy 270.372368 -66.341502) (xy 270.362426 -66.345308) (xy 270.319764 -66.363553) (xy 270.231471 -66.392097)
			(xy 270.140686 -66.41129) (xy 270.048396 -66.420923) (xy 270.002 -66.421508) (xy 269.955604 -66.420925)
			(xy 269.863316 -66.41128) (xy 269.772532 -66.392084) (xy 269.684239 -66.363546) (xy 269.641574 -66.345308)
			(xy 269.631632 -66.341502) (xy 269.610368 -66.341502) (xy 269.600426 -66.345308) (xy 269.557764 -66.363553)
			(xy 269.469471 -66.392097) (xy 269.378686 -66.41129) (xy 269.286396 -66.420923) (xy 269.24 -66.421508)
			(xy 269.198898 -66.421033) (xy 269.117043 -66.413448) (xy 269.036238 -66.398343) (xy 268.957171 -66.375847)
			(xy 268.880517 -66.346151) (xy 268.80693 -66.309509) (xy 268.737038 -66.266234) (xy 268.671437 -66.216694)
			(xy 268.610687 -66.161313) (xy 268.555306 -66.100563) (xy 268.505766 -66.034962) (xy 268.462491 -65.96507)
			(xy 268.425849 -65.891483) (xy 268.396153 -65.814829) (xy 268.373657 -65.735762) (xy 268.358552 -65.654957)
			(xy 268.350967 -65.573102) (xy 268.350492 -65.532) (xy 29.224945 -65.532) (xy 29.225696 -65.535552)
			(xy 29.235325 -65.627843) (xy 29.235908 -65.67424) (xy 29.235304 -65.720635) (xy 29.225665 -65.812923)
			(xy 29.206475 -65.903707) (xy 29.177943 -65.992001) (xy 29.159708 -66.034666) (xy 29.155879 -66.044601)
			(xy 29.155894 -66.065871) (xy 29.159708 -66.075814) (xy 29.177966 -66.118471) (xy 29.206507 -66.206765)
			(xy 29.225696 -66.297552) (xy 29.235325 -66.389843) (xy 29.235908 -66.43624) (xy 29.235472 -66.477343)
			(xy 29.227883 -66.559198) (xy 29.212774 -66.640004) (xy 29.190275 -66.719072) (xy 29.160576 -66.795726)
			(xy 29.123931 -66.869313) (xy 29.080653 -66.939205) (xy 29.031111 -67.004806) (xy 28.975727 -67.065555)
			(xy 28.914975 -67.120936) (xy 28.849372 -67.170475) (xy 28.779478 -67.21375) (xy 28.705889 -67.250392)
			(xy 28.629234 -67.280087) (xy 28.550166 -67.302584) (xy 28.469359 -67.317689) (xy 28.387503 -67.325273)
			(xy 28.3464 -67.325748) (xy 28.300004 -67.32517) (xy 28.207716 -67.315524) (xy 28.116932 -67.296327)
			(xy 28.028638 -67.267787) (xy 27.985974 -67.249548) (xy 27.976032 -67.245742) (xy 27.954768 -67.245742)
			(xy 27.944826 -67.249548) (xy 27.902165 -67.267795) (xy 27.813872 -67.296338) (xy 27.723087 -67.31553)
			(xy 27.630796 -67.325163) (xy 27.5844 -67.325748) (xy 27.543299 -67.325233) (xy 27.461447 -67.317649)
			(xy 27.380644 -67.302545) (xy 27.301579 -67.280049) (xy 27.224927 -67.250355) (xy 27.151342 -67.213715)
			(xy 27.081451 -67.170442) (xy 27.015851 -67.120905) (xy 26.955101 -67.065527) (xy 26.89972 -67.00478)
			(xy 26.85018 -66.939182) (xy 26.806904 -66.869293) (xy 26.770261 -66.79571) (xy 26.740563 -66.719059)
			(xy 26.718064 -66.639995) (xy 26.702957 -66.559193) (xy 26.695368 -66.477341) (xy 26.694892 -66.43624)
			(xy 0.509016 -66.43624) (xy 0.509016 -70.939914) (xy 8.478012 -70.939914) (xy 8.478545 -70.885007)
			(xy 8.487299 -70.775543) (xy 8.504775 -70.667129) (xy 8.530863 -70.56046) (xy 8.565395 -70.456217)
			(xy 8.608149 -70.355068) (xy 8.658854 -70.257662) (xy 8.717182 -70.16462) (xy 8.749538 -70.120256)
			(xy 8.755682 -70.111222) (xy 8.760349 -70.089902) (xy 8.755684 -70.068582) (xy 8.749538 -70.05955)
			(xy 8.717186 -70.015184) (xy 8.65886 -69.922141) (xy 8.608158 -69.824733) (xy 8.565404 -69.723585)
			(xy 8.530872 -69.619343) (xy 8.504782 -69.512674) (xy 8.487302 -69.404262) (xy 8.478544 -69.294799)
			(xy 8.478012 -69.239892) (xy 8.478453 -69.188568) (xy 8.486124 -69.086208) (xy 8.501424 -68.984707)
			(xy 8.524266 -68.884633) (xy 8.554522 -68.786547) (xy 8.592024 -68.690995) (xy 8.636562 -68.598513)
			(xy 8.687887 -68.509618) (xy 8.745711 -68.424808) (xy 8.809711 -68.344555) (xy 8.87953 -68.26931)
			(xy 8.954776 -68.199493) (xy 9.03503 -68.135494) (xy 9.119842 -68.077672) (xy 9.208738 -68.026349)
			(xy 9.301221 -67.981813) (xy 9.396773 -67.944313) (xy 9.49486 -67.914058) (xy 9.594935 -67.891218)
			(xy 9.696436 -67.875921) (xy 9.798796 -67.868252) (xy 9.85012 -67.867784) (xy 9.901023 -67.868245)
			(xy 10.00255 -67.875789) (xy 10.103239 -67.890838) (xy 10.202535 -67.913308) (xy 10.299893 -67.943077)
			(xy 10.394776 -67.97998) (xy 10.486663 -68.023815) (xy 10.575047 -68.074339) (xy 10.659444 -68.131276)
			(xy 10.739389 -68.194313) (xy 10.814441 -68.263101) (xy 10.884187 -68.337263) (xy 10.948245 -68.416391)
			(xy 11.006262 -68.500049) (xy 11.03249 -68.543678) (xy 11.039348 -68.555362) (xy 11.062716 -68.56857)
			(xy 11.177524 -68.56857) (xy 11.200892 -68.555362) (xy 11.20775 -68.543678) (xy 11.233971 -68.500045)
			(xy 11.291989 -68.416388) (xy 11.356048 -68.337261) (xy 11.425796 -68.2631) (xy 11.500849 -68.194313)
			(xy 11.580794 -68.131277) (xy 11.665192 -68.074341) (xy 11.753577 -68.023817) (xy 11.845464 -67.979983)
			(xy 11.940347 -67.94308) (xy 12.037705 -67.913311) (xy 12.137001 -67.890841) (xy 12.23769 -67.875792)
			(xy 12.339217 -67.868247) (xy 12.39012 -67.867784) (xy 12.441443 -67.868253) (xy 12.462296 -67.869816)
			(xy 61.553852 -67.869816) (xy 61.554352 -67.818909) (xy 61.56234 -67.71741) (xy 61.578267 -67.61685)
			(xy 61.602035 -67.517849) (xy 61.633497 -67.421019) (xy 61.672459 -67.326956) (xy 61.718682 -67.236239)
			(xy 61.771879 -67.149429) (xy 61.831723 -67.06706) (xy 61.897846 -66.989641) (xy 61.969839 -66.917648)
			(xy 62.047258 -66.851525) (xy 62.129627 -66.791681) (xy 62.216437 -66.738484) (xy 62.307154 -66.692261)
			(xy 62.401217 -66.653299) (xy 62.498047 -66.621837) (xy 62.597048 -66.598069) (xy 62.697608 -66.582142)
			(xy 62.799107 -66.574154) (xy 62.900921 -66.574154) (xy 63.00242 -66.582142) (xy 63.10298 -66.598069)
			(xy 63.201981 -66.621837) (xy 63.298811 -66.653299) (xy 63.392874 -66.692261) (xy 63.483591 -66.738484)
			(xy 63.570401 -66.791681) (xy 63.65277 -66.851525) (xy 63.730189 -66.917648) (xy 63.802182 -66.989641)
			(xy 63.868305 -67.06706) (xy 63.928149 -67.149429) (xy 63.981346 -67.236239) (xy 64.027569 -67.326956)
			(xy 64.066531 -67.421019) (xy 64.097993 -67.517849) (xy 64.121761 -67.61685) (xy 64.137688 -67.71741)
			(xy 64.145676 -67.818909) (xy 64.146176 -67.869816) (xy 101.553772 -67.869816) (xy 101.554272 -67.818909)
			(xy 101.56226 -67.71741) (xy 101.578187 -67.61685) (xy 101.601955 -67.517849) (xy 101.633417 -67.421019)
			(xy 101.672379 -67.326956) (xy 101.718602 -67.236239) (xy 101.771799 -67.149429) (xy 101.831643 -67.06706)
			(xy 101.897766 -66.989641) (xy 101.969759 -66.917648) (xy 102.047178 -66.851525) (xy 102.129547 -66.791681)
			(xy 102.216357 -66.738484) (xy 102.307074 -66.692261) (xy 102.401137 -66.653299) (xy 102.497967 -66.621837)
			(xy 102.596968 -66.598069) (xy 102.697528 -66.582142) (xy 102.799027 -66.574154) (xy 102.900841 -66.574154)
			(xy 103.00234 -66.582142) (xy 103.1029 -66.598069) (xy 103.201901 -66.621837) (xy 103.298731 -66.653299)
			(xy 103.392794 -66.692261) (xy 103.483511 -66.738484) (xy 103.570321 -66.791681) (xy 103.65269 -66.851525)
			(xy 103.730109 -66.917648) (xy 103.802102 -66.989641) (xy 103.868225 -67.06706) (xy 103.928069 -67.149429)
			(xy 103.981266 -67.236239) (xy 104.027489 -67.326956) (xy 104.066451 -67.421019) (xy 104.097913 -67.517849)
			(xy 104.121681 -67.61685) (xy 104.137608 -67.71741) (xy 104.145596 -67.818909) (xy 104.146096 -67.869816)
			(xy 141.5542 -67.869816) (xy 141.554699 -67.818919) (xy 141.562686 -67.71744) (xy 141.57861 -67.616899)
			(xy 141.602373 -67.517918) (xy 141.633829 -67.421107) (xy 141.672784 -67.327062) (xy 141.718997 -67.236364)
			(xy 141.772184 -67.14957) (xy 141.832017 -67.067218) (xy 141.898126 -66.989813) (xy 141.970105 -66.917834)
			(xy 142.04751 -66.851725) (xy 142.129862 -66.791892) (xy 142.216656 -66.738705) (xy 142.307354 -66.692492)
			(xy 142.401399 -66.653537) (xy 142.49821 -66.622081) (xy 142.597191 -66.598318) (xy 142.697732 -66.582394)
			(xy 142.799211 -66.574407) (xy 142.901005 -66.574407) (xy 143.002484 -66.582394) (xy 143.103025 -66.598318)
			(xy 143.202006 -66.622081) (xy 143.298817 -66.653537) (xy 143.392862 -66.692492) (xy 143.48356 -66.738705)
			(xy 143.570354 -66.791892) (xy 143.652706 -66.851725) (xy 143.730111 -66.917834) (xy 143.80209 -66.989813)
			(xy 143.868199 -67.067218) (xy 143.928032 -67.14957) (xy 143.981219 -67.236364) (xy 144.027432 -67.327062)
			(xy 144.066387 -67.421107) (xy 144.097843 -67.517918) (xy 144.121606 -67.616899) (xy 144.13753 -67.71744)
			(xy 144.145517 -67.818919) (xy 144.146016 -67.869816) (xy 181.55412 -67.869816) (xy 181.55462 -67.818909)
			(xy 181.562608 -67.71741) (xy 181.578535 -67.61685) (xy 181.602303 -67.517849) (xy 181.633765 -67.421019)
			(xy 181.672727 -67.326956) (xy 181.71895 -67.236239) (xy 181.772147 -67.149429) (xy 181.831991 -67.06706)
			(xy 181.898114 -66.989641) (xy 181.970107 -66.917648) (xy 182.047526 -66.851525) (xy 182.129895 -66.791681)
			(xy 182.216705 -66.738484) (xy 182.307422 -66.692261) (xy 182.401485 -66.653299) (xy 182.498315 -66.621837)
			(xy 182.597316 -66.598069) (xy 182.697876 -66.582142) (xy 182.799375 -66.574154) (xy 182.901189 -66.574154)
			(xy 183.002688 -66.582142) (xy 183.103248 -66.598069) (xy 183.202249 -66.621837) (xy 183.299079 -66.653299)
			(xy 183.393142 -66.692261) (xy 183.483859 -66.738484) (xy 183.570669 -66.791681) (xy 183.653038 -66.851525)
			(xy 183.730457 -66.917648) (xy 183.80245 -66.989641) (xy 183.868573 -67.06706) (xy 183.928417 -67.149429)
			(xy 183.981614 -67.236239) (xy 184.027837 -67.326956) (xy 184.066799 -67.421019) (xy 184.098261 -67.517849)
			(xy 184.122029 -67.61685) (xy 184.137956 -67.71741) (xy 184.145944 -67.818909) (xy 184.146444 -67.869816)
			(xy 184.145789 -67.929021) (xy 184.134974 -68.046936) (xy 184.124854 -68.105274) (xy 184.122568 -68.117212)
			(xy 184.129172 -68.140072) (xy 184.201308 -68.217796) (xy 184.223406 -68.225924) (xy 184.235598 -68.224654)
			(xy 184.294095 -68.218798) (xy 184.411506 -68.212572) (xy 184.470294 -68.212208) (xy 184.537362 -68.212707)
			(xy 184.671248 -68.220881) (xy 184.804386 -68.237206) (xy 184.936281 -68.26162) (xy 185.066442 -68.294033)
			(xy 185.194383 -68.334324) (xy 185.319629 -68.382343) (xy 185.441713 -68.437912) (xy 185.56018 -68.500822)
			(xy 185.674591 -68.570841) (xy 185.784518 -68.647707) (xy 185.889552 -68.731135) (xy 185.989302 -68.820813)
			(xy 186.083398 -68.916407) (xy 186.171488 -69.017563) (xy 186.253245 -69.123903) (xy 186.29122 -69.179186)
			(xy 186.298332 -69.1896) (xy 186.32043 -69.201538) (xy 186.430158 -69.201538) (xy 186.452256 -69.1896)
			(xy 186.459368 -69.179186) (xy 186.497355 -69.12391) (xy 186.579103 -69.017561) (xy 186.667186 -68.916397)
			(xy 186.761276 -68.820795) (xy 186.861022 -68.731111) (xy 186.966054 -68.647678) (xy 187.07598 -68.570807)
			(xy 187.19039 -68.500785) (xy 187.308858 -68.437873) (xy 187.430944 -68.382304) (xy 187.556192 -68.334287)
			(xy 187.684136 -68.293999) (xy 187.814299 -68.26159) (xy 187.946196 -68.237182) (xy 188.079337 -68.220866)
			(xy 188.213225 -68.212701) (xy 188.280294 -68.212208) (xy 188.346684 -68.212667) (xy 188.479223 -68.220684)
			(xy 188.611036 -68.236689) (xy 188.741642 -68.260623) (xy 188.870565 -68.292399) (xy 188.997333 -68.331901)
			(xy 189.121486 -68.378986) (xy 189.242569 -68.433481) (xy 189.360141 -68.495187) (xy 189.473772 -68.563879)
			(xy 189.583049 -68.639307) (xy 189.687572 -68.721195) (xy 189.702736 -68.734629) (xy 270.306796 -68.734629)
			(xy 270.306796 -68.649907) (xy 270.314849 -68.56557) (xy 270.330883 -68.48238) (xy 270.354751 -68.40109)
			(xy 270.386239 -68.322438) (xy 270.425061 -68.247135) (xy 270.470864 -68.175863) (xy 270.523235 -68.109267)
			(xy 270.5817 -68.047952) (xy 270.645728 -67.992471) (xy 270.71474 -67.943328) (xy 270.78811 -67.900968)
			(xy 270.865175 -67.865773) (xy 270.945237 -67.838064) (xy 271.02757 -67.81809) (xy 271.111429 -67.806033)
			(xy 271.196054 -67.802002) (xy 271.280679 -67.806033) (xy 271.364538 -67.81809) (xy 271.446871 -67.838064)
			(xy 271.526933 -67.865773) (xy 271.603998 -67.900968) (xy 271.677368 -67.943328) (xy 271.74638 -67.992471)
			(xy 271.810408 -68.047952) (xy 271.868873 -68.109267) (xy 271.921244 -68.175863) (xy 271.967047 -68.247135)
			(xy 272.005869 -68.322438) (xy 272.037357 -68.40109) (xy 272.061225 -68.48238) (xy 272.077259 -68.56557)
			(xy 272.085312 -68.649907) (xy 272.085816 -68.692268) (xy 272.085312 -68.734629) (xy 272.077259 -68.818966)
			(xy 272.061225 -68.902156) (xy 272.037357 -68.983446) (xy 272.005869 -69.062098) (xy 271.967047 -69.137401)
			(xy 271.921244 -69.208673) (xy 271.868873 -69.275269) (xy 271.810408 -69.336584) (xy 271.74638 -69.392065)
			(xy 271.677368 -69.441208) (xy 271.603998 -69.483568) (xy 271.526933 -69.518763) (xy 271.446871 -69.546472)
			(xy 271.364538 -69.566446) (xy 271.280679 -69.578503) (xy 271.196054 -69.582535) (xy 271.111429 -69.578503)
			(xy 271.02757 -69.566446) (xy 270.945237 -69.546472) (xy 270.865175 -69.518763) (xy 270.78811 -69.483568)
			(xy 270.71474 -69.441208) (xy 270.645728 -69.392065) (xy 270.5817 -69.336584) (xy 270.523235 -69.275269)
			(xy 270.470864 -69.208673) (xy 270.425061 -69.137401) (xy 270.386239 -69.062098) (xy 270.354751 -68.983446)
			(xy 270.330883 -68.902156) (xy 270.314849 -68.818966) (xy 270.306796 -68.734629) (xy 189.702736 -68.734629)
			(xy 189.78696 -68.809245) (xy 189.880851 -68.903136) (xy 189.968901 -69.002523) (xy 190.050789 -69.107046)
			(xy 190.126218 -69.216323) (xy 190.19491 -69.329954) (xy 190.256617 -69.447526) (xy 190.311112 -69.568609)
			(xy 190.358197 -69.692761) (xy 190.397699 -69.81953) (xy 190.429476 -69.948452) (xy 190.453411 -70.079058)
			(xy 190.469047 -70.207829) (xy 268.757142 -70.207829) (xy 268.757142 -70.123107) (xy 268.765195 -70.03877)
			(xy 268.781229 -69.95558) (xy 268.805097 -69.87429) (xy 268.836585 -69.795638) (xy 268.875407 -69.720335)
			(xy 268.92121 -69.649063) (xy 268.973581 -69.582467) (xy 269.032046 -69.521152) (xy 269.096074 -69.465671)
			(xy 269.165086 -69.416528) (xy 269.238456 -69.374168) (xy 269.315521 -69.338973) (xy 269.395583 -69.311264)
			(xy 269.477916 -69.29129) (xy 269.561775 -69.279233) (xy 269.6464 -69.275202) (xy 269.731025 -69.279233)
			(xy 269.814884 -69.29129) (xy 269.897217 -69.311264) (xy 269.977279 -69.338973) (xy 270.054344 -69.374168)
			(xy 270.127714 -69.416528) (xy 270.196726 -69.465671) (xy 270.260754 -69.521152) (xy 270.319219 -69.582467)
			(xy 270.37159 -69.649063) (xy 270.417393 -69.720335) (xy 270.456215 -69.795638) (xy 270.487703 -69.87429)
			(xy 270.511571 -69.95558) (xy 270.527605 -70.03877) (xy 270.535658 -70.123107) (xy 270.536162 -70.165468)
			(xy 270.535658 -70.207829) (xy 270.527605 -70.292166) (xy 270.511571 -70.375356) (xy 270.487703 -70.456646)
			(xy 270.456215 -70.535298) (xy 270.417393 -70.610601) (xy 270.37159 -70.681873) (xy 270.319219 -70.748469)
			(xy 270.260754 -70.809784) (xy 270.196726 -70.865265) (xy 270.127714 -70.914408) (xy 270.054344 -70.956768)
			(xy 269.977279 -70.991963) (xy 269.897217 -71.019672) (xy 269.814884 -71.039646) (xy 269.731025 -71.051703)
			(xy 269.6464 -71.055735) (xy 269.561775 -71.051703) (xy 269.477916 -71.039646) (xy 269.395583 -71.019672)
			(xy 269.315521 -70.991963) (xy 269.238456 -70.956768) (xy 269.165086 -70.914408) (xy 269.096074 -70.865265)
			(xy 269.032046 -70.809784) (xy 268.973581 -70.748469) (xy 268.92121 -70.681873) (xy 268.875407 -70.610601)
			(xy 268.836585 -70.535298) (xy 268.805097 -70.456646) (xy 268.781229 -70.375356) (xy 268.765195 -70.292166)
			(xy 268.757142 -70.207829) (xy 190.469047 -70.207829) (xy 190.469416 -70.210871) (xy 190.477433 -70.34341)
			(xy 190.477433 -70.47619) (xy 190.469416 -70.608729) (xy 190.453411 -70.740542) (xy 190.429476 -70.871148)
			(xy 190.397699 -71.00007) (xy 190.358197 -71.126839) (xy 190.311112 -71.250991) (xy 190.256617 -71.372074)
			(xy 190.19491 -71.489646) (xy 190.126218 -71.603277) (xy 190.050789 -71.712554) (xy 189.968901 -71.817077)
			(xy 189.880851 -71.916464) (xy 189.78696 -72.010355) (xy 189.687572 -72.098405) (xy 189.583049 -72.180293)
			(xy 189.473772 -72.255721) (xy 189.360141 -72.324413) (xy 189.242569 -72.386119) (xy 189.121486 -72.440614)
			(xy 188.997333 -72.487699) (xy 188.870565 -72.527201) (xy 188.741642 -72.558977) (xy 188.611036 -72.582911)
			(xy 188.479223 -72.598916) (xy 188.346684 -72.606933) (xy 188.280294 -72.607424) (xy 188.213225 -72.606965)
			(xy 188.079338 -72.598789) (xy 187.946198 -72.582463) (xy 187.814302 -72.558047) (xy 187.684141 -72.525633)
			(xy 187.556198 -72.485339) (xy 187.430952 -72.437318) (xy 187.308867 -72.381747) (xy 187.1904 -72.318834)
			(xy 187.075989 -72.248812) (xy 186.966063 -72.171943) (xy 186.861029 -72.088513) (xy 186.76128 -71.998831)
			(xy 186.667185 -71.903233) (xy 186.579097 -71.802074) (xy 186.497342 -71.695731) (xy 186.459368 -71.640446)
			(xy 186.452256 -71.630032) (xy 186.430158 -71.618094) (xy 186.32043 -71.618094) (xy 186.298332 -71.630032)
			(xy 186.29122 -71.640446) (xy 186.253252 -71.695735) (xy 186.171502 -71.802083) (xy 186.083417 -71.903246)
			(xy 185.989326 -71.998848) (xy 185.889577 -72.088531) (xy 185.784544 -72.171964) (xy 185.674617 -72.248833)
			(xy 185.560206 -72.318854) (xy 185.441736 -72.381766) (xy 185.319649 -72.437333) (xy 185.194401 -72.48535)
			(xy 185.066456 -72.525637) (xy 184.936292 -72.558045) (xy 184.804393 -72.582452) (xy 184.671252 -72.598768)
			(xy 184.537363 -72.606931) (xy 184.470294 -72.607424) (xy 184.403901 -72.606967) (xy 184.271357 -72.598949)
			(xy 184.139539 -72.582944) (xy 184.008927 -72.55901) (xy 183.879999 -72.527234) (xy 183.753224 -72.487732)
			(xy 183.629066 -72.440648) (xy 183.507977 -72.386153) (xy 183.390399 -72.324448) (xy 183.276761 -72.255756)
			(xy 183.167477 -72.180329) (xy 183.062946 -72.098441) (xy 182.963551 -72.010392) (xy 182.869652 -71.916502)
			(xy 182.781593 -71.817115) (xy 182.699696 -71.712592) (xy 182.624258 -71.603316) (xy 182.555555 -71.489684)
			(xy 182.493839 -71.372112) (xy 182.439333 -71.251028) (xy 182.392237 -71.126874) (xy 182.352723 -71.000103)
			(xy 182.320934 -70.871178) (xy 182.296987 -70.740569) (xy 182.28097 -70.608752) (xy 182.27294 -70.476209)
			(xy 182.272432 -70.409816) (xy 182.27291 -70.34359) (xy 182.280893 -70.211378) (xy 182.296826 -70.079888)
			(xy 182.32065 -69.949596) (xy 182.35228 -69.820975) (xy 182.391599 -69.694494) (xy 182.438466 -69.57061)
			(xy 182.49271 -69.449775) (xy 182.554135 -69.332426) (xy 182.5879 -69.275452) (xy 182.59425 -69.265038)
			(xy 182.596028 -69.241416) (xy 182.555896 -69.143372) (xy 182.538116 -69.127878) (xy 182.526178 -69.124576)
			(xy 182.477646 -69.111541) (xy 182.382574 -69.078966) (xy 182.290311 -69.039123) (xy 182.201411 -68.992253)
			(xy 182.116409 -68.938637) (xy 182.035816 -68.878598) (xy 181.960117 -68.812496) (xy 181.889765 -68.740729)
			(xy 181.825184 -68.663727) (xy 181.766762 -68.581954) (xy 181.71485 -68.495901) (xy 181.66976 -68.406086)
			(xy 181.631763 -68.313047) (xy 181.601088 -68.217345) (xy 181.577918 -68.119554) (xy 181.562394 -68.020262)
			(xy 181.554607 -67.920065) (xy 181.55412 -67.869816) (xy 144.146016 -67.869816) (xy 144.145413 -67.929016)
			(xy 144.134729 -68.04693) (xy 144.12468 -68.105274) (xy 144.122394 -68.117212) (xy 144.128998 -68.140072)
			(xy 144.201134 -68.217796) (xy 144.223232 -68.225924) (xy 144.235424 -68.224654) (xy 144.293921 -68.218796)
			(xy 144.411332 -68.212571) (xy 144.47012 -68.212208) (xy 144.537188 -68.212686) (xy 144.671075 -68.220862)
			(xy 144.804214 -68.237188) (xy 144.936109 -68.261604) (xy 145.066269 -68.294019) (xy 145.194211 -68.334311)
			(xy 145.319457 -68.382332) (xy 145.441541 -68.437901) (xy 145.560008 -68.500813) (xy 145.674419 -68.570833)
			(xy 145.784345 -68.647701) (xy 145.889379 -68.73113) (xy 145.98913 -68.820809) (xy 146.083225 -68.916405)
			(xy 146.171315 -69.017562) (xy 146.253071 -69.123902) (xy 146.291046 -69.179186) (xy 146.298158 -69.1896)
			(xy 146.320256 -69.201538) (xy 146.429984 -69.201538) (xy 146.452082 -69.1896) (xy 146.459194 -69.179186)
			(xy 146.497163 -69.123898) (xy 146.578913 -69.017549) (xy 146.666997 -68.916385) (xy 146.761088 -68.820783)
			(xy 146.860836 -68.731099) (xy 146.965869 -68.647667) (xy 147.075796 -68.570797) (xy 147.190207 -68.500775)
			(xy 147.308677 -68.437864) (xy 147.430764 -68.382296) (xy 147.556013 -68.334279) (xy 147.683957 -68.293992)
			(xy 147.814122 -68.261585) (xy 147.94602 -68.237179) (xy 148.079162 -68.220863) (xy 148.213051 -68.2127)
			(xy 148.28012 -68.212208) (xy 148.34651 -68.212678) (xy 148.479047 -68.220696) (xy 148.610858 -68.236702)
			(xy 148.741462 -68.260637) (xy 148.870383 -68.292414) (xy 148.99715 -68.331918) (xy 149.1213 -68.379003)
			(xy 149.242381 -68.433498) (xy 149.359951 -68.495204) (xy 149.473581 -68.563897) (xy 149.582855 -68.639324)
			(xy 149.687377 -68.721212) (xy 149.786763 -68.809262) (xy 149.880652 -68.903152) (xy 149.9687 -69.002539)
			(xy 150.050587 -69.107061) (xy 150.126014 -69.216336) (xy 150.194706 -69.329966) (xy 150.256411 -69.447537)
			(xy 150.310905 -69.568618) (xy 150.357989 -69.692769) (xy 150.397491 -69.819537) (xy 150.429267 -69.948458)
			(xy 150.453201 -70.079062) (xy 150.469206 -70.210873) (xy 150.477223 -70.34341) (xy 150.477223 -70.47619)
			(xy 150.469206 -70.608727) (xy 150.453201 -70.740538) (xy 150.429267 -70.871142) (xy 150.397491 -71.000063)
			(xy 150.357989 -71.126831) (xy 150.310905 -71.250982) (xy 150.256411 -71.372063) (xy 150.194706 -71.489634)
			(xy 150.126014 -71.603264) (xy 150.050587 -71.712539) (xy 149.9687 -71.817061) (xy 149.880652 -71.916448)
			(xy 149.786763 -72.010338) (xy 149.687377 -72.098388) (xy 149.582855 -72.180276) (xy 149.473581 -72.255703)
			(xy 149.359951 -72.324396) (xy 149.242381 -72.386102) (xy 149.1213 -72.440597) (xy 148.99715 -72.487682)
			(xy 148.870383 -72.527186) (xy 148.741462 -72.558963) (xy 148.610858 -72.582898) (xy 148.479047 -72.598904)
			(xy 148.34651 -72.606922) (xy 148.28012 -72.607424) (xy 148.213052 -72.606944) (xy 148.079165 -72.59877)
			(xy 147.946025 -72.582446) (xy 147.81413 -72.558031) (xy 147.683968 -72.525618) (xy 147.556026 -72.485326)
			(xy 147.43078 -72.437306) (xy 147.308695 -72.381737) (xy 147.190228 -72.318825) (xy 147.075817 -72.248805)
			(xy 146.96589 -72.171937) (xy 146.860857 -72.088508) (xy 146.761107 -71.998827) (xy 146.667012 -71.90323)
			(xy 146.578923 -71.802072) (xy 146.497168 -71.69573) (xy 146.459194 -71.640446) (xy 146.452082 -71.630032)
			(xy 146.429984 -71.618094) (xy 146.320256 -71.618094) (xy 146.298158 -71.630032) (xy 146.291046 -71.640446)
			(xy 146.253061 -71.695723) (xy 146.171312 -71.802071) (xy 146.083229 -71.903234) (xy 145.989138 -71.998836)
			(xy 145.889391 -72.08852) (xy 145.784359 -72.171952) (xy 145.674433 -72.248823) (xy 145.560023 -72.318844)
			(xy 145.441555 -72.381756) (xy 145.319469 -72.437325) (xy 145.194221 -72.485343) (xy 145.066278 -72.525631)
			(xy 144.936115 -72.55804) (xy 144.804217 -72.582448) (xy 144.671077 -72.598765) (xy 144.537189 -72.606931)
			(xy 144.47012 -72.607424) (xy 144.403731 -72.606897) (xy 144.271194 -72.598882) (xy 144.139383 -72.582878)
			(xy 144.008779 -72.558945) (xy 143.879859 -72.52717) (xy 143.753092 -72.487669) (xy 143.628941 -72.440586)
			(xy 143.50786 -72.386093) (xy 143.39029 -72.324389) (xy 143.27666 -72.255699) (xy 143.167384 -72.180273)
			(xy 143.062862 -72.098386) (xy 142.963475 -72.010339) (xy 142.869586 -71.916451) (xy 142.781537 -71.817065)
			(xy 142.699649 -71.712545) (xy 142.624221 -71.603271) (xy 142.555529 -71.489642) (xy 142.493822 -71.372072)
			(xy 142.439327 -71.250992) (xy 142.392242 -71.126842) (xy 142.352739 -71.000076) (xy 142.320962 -70.871156)
			(xy 142.297027 -70.740552) (xy 142.281022 -70.608742) (xy 142.273004 -70.476205) (xy 142.272512 -70.409816)
			(xy 142.272989 -70.343594) (xy 142.280942 -70.211388) (xy 142.296845 -70.079902) (xy 142.320639 -69.949613)
			(xy 142.352238 -69.820993) (xy 142.391527 -69.694511) (xy 142.438365 -69.570624) (xy 142.492579 -69.449784)
			(xy 142.553975 -69.33243) (xy 142.587726 -69.275452) (xy 142.594076 -69.265038) (xy 142.595854 -69.241416)
			(xy 142.555722 -69.143372) (xy 142.537942 -69.127878) (xy 142.526004 -69.124576) (xy 142.477475 -69.111555)
			(xy 142.382423 -69.078958) (xy 142.29018 -69.039098) (xy 142.201302 -68.992213) (xy 142.116322 -68.938586)
			(xy 142.03575 -68.878538) (xy 141.960071 -68.81243) (xy 141.88974 -68.740659) (xy 141.825178 -68.663658)
			(xy 141.766774 -68.581887) (xy 141.714878 -68.495838) (xy 141.669802 -68.406029) (xy 141.631818 -68.312998)
			(xy 141.601152 -68.217305) (xy 141.57799 -68.119525) (xy 141.562471 -68.020244) (xy 141.554687 -67.920059)
			(xy 141.5542 -67.869816) (xy 104.146096 -67.869816) (xy 104.14544 -67.929021) (xy 104.134626 -68.046936)
			(xy 104.124506 -68.105274) (xy 104.12222 -68.117212) (xy 104.128824 -68.140072) (xy 104.20096 -68.217796)
			(xy 104.223058 -68.225924) (xy 104.23525 -68.224654) (xy 104.293747 -68.218802) (xy 104.411158 -68.212573)
			(xy 104.469946 -68.212208) (xy 104.537013 -68.212745) (xy 104.670898 -68.220917) (xy 104.804036 -68.237238)
			(xy 104.93593 -68.26165) (xy 105.06609 -68.29406) (xy 105.194031 -68.334348) (xy 105.319277 -68.382365)
			(xy 105.441361 -68.43793) (xy 105.559829 -68.500839) (xy 105.674239 -68.570855) (xy 105.784166 -68.647719)
			(xy 105.889201 -68.731144) (xy 105.988952 -68.82082) (xy 106.083048 -68.916412) (xy 106.171139 -69.017566)
			(xy 106.252896 -69.123904) (xy 106.290872 -69.179186) (xy 106.297984 -69.1896) (xy 106.320082 -69.201538)
			(xy 106.42981 -69.201538) (xy 106.451908 -69.1896) (xy 106.45902 -69.179186) (xy 106.496972 -69.123886)
			(xy 106.578722 -69.017537) (xy 106.666808 -68.916373) (xy 106.7609 -68.820772) (xy 106.86065 -68.731088)
			(xy 106.965684 -68.647656) (xy 107.075612 -68.570786) (xy 107.190025 -68.500765) (xy 107.308495 -68.437855)
			(xy 107.430583 -68.382288) (xy 107.555833 -68.334272) (xy 107.683779 -68.293986) (xy 107.813945 -68.26158)
			(xy 107.945844 -68.237175) (xy 108.078987 -68.220861) (xy 108.212877 -68.212699) (xy 108.279946 -68.212208)
			(xy 108.346561 -68.21269) (xy 108.479549 -68.220738) (xy 108.611805 -68.236826) (xy 108.742843 -68.260895)
			(xy 108.872183 -68.292856) (xy 108.99935 -68.332592) (xy 109.123877 -68.379958) (xy 109.245307 -68.434779)
			(xy 109.363193 -68.496853) (xy 109.420406 -68.530978) (xy 109.42955 -68.536566) (xy 109.450632 -68.53936)
			(xy 109.543088 -68.512436) (xy 109.559598 -68.49872) (xy 109.56417 -68.489068) (xy 109.58283 -68.45221)
			(xy 109.625989 -68.381762) (xy 109.675492 -68.315617) (xy 109.730913 -68.254346) (xy 109.791775 -68.198475)
			(xy 109.857554 -68.148486) (xy 109.927683 -68.10481) (xy 110.001559 -68.067822) (xy 110.078545 -68.037842)
			(xy 110.157978 -68.015126) (xy 110.239175 -67.999871) (xy 110.321437 -67.992208) (xy 110.362746 -67.991736)
			(xy 110.405055 -67.992204) (xy 110.489292 -68.000211) (xy 110.572388 -68.016178) (xy 110.653594 -68.039959)
			(xy 110.732177 -68.071342) (xy 110.807426 -68.110041) (xy 110.843314 -68.132452) (xy 110.851703 -68.137335)
			(xy 110.870746 -68.141006) (xy 110.889789 -68.137335) (xy 110.898178 -68.132452) (xy 110.934072 -68.110048)
			(xy 111.009313 -68.071332) (xy 111.087892 -68.039941) (xy 111.169099 -68.01616) (xy 111.252198 -68.000202)
			(xy 111.336437 -67.992213) (xy 111.378746 -67.991736) (xy 111.421055 -67.992204) (xy 111.505292 -68.000211)
			(xy 111.588388 -68.016178) (xy 111.669594 -68.039959) (xy 111.748177 -68.071342) (xy 111.823426 -68.110041)
			(xy 111.859314 -68.132452) (xy 111.867703 -68.137335) (xy 111.886746 -68.141006) (xy 111.905789 -68.137335)
			(xy 111.914178 -68.132452) (xy 111.950072 -68.110048) (xy 112.025313 -68.071332) (xy 112.103892 -68.039941)
			(xy 112.185099 -68.01616) (xy 112.268198 -68.000202) (xy 112.352437 -67.992213) (xy 112.394746 -67.991736)
			(xy 112.435853 -67.992169) (xy 112.517717 -67.999757) (xy 112.598532 -68.014865) (xy 112.677609 -68.037364)
			(xy 112.754273 -68.067061) (xy 112.827871 -68.103704) (xy 112.897774 -68.146979) (xy 112.963387 -68.196519)
			(xy 113.024151 -68.251901) (xy 113.079547 -68.312651) (xy 113.129102 -68.378253) (xy 113.172394 -68.448146)
			(xy 113.209054 -68.521735) (xy 113.23877 -68.598392) (xy 113.261287 -68.677463) (xy 113.276414 -68.758274)
			(xy 113.284022 -68.840137) (xy 113.284508 -68.881244) (xy 113.284026 -68.923559) (xy 113.275992 -69.007808)
			(xy 113.25999 -69.090912) (xy 113.236165 -69.17212) (xy 113.204733 -69.250697) (xy 113.165978 -69.325933)
			(xy 113.143538 -69.361812) (xy 113.138619 -69.370183) (xy 113.134959 -69.389237) (xy 113.138646 -69.408287)
			(xy 113.143538 -69.416676) (xy 113.166016 -69.452532) (xy 113.204764 -69.527773) (xy 113.236192 -69.606354)
			(xy 113.260013 -69.687564) (xy 113.276014 -69.770671) (xy 113.284049 -69.854921) (xy 113.284045 -69.939553)
			(xy 113.276003 -70.023803) (xy 113.259996 -70.106908) (xy 113.236167 -70.188116) (xy 113.204734 -70.266695)
			(xy 113.165979 -70.341932) (xy 113.143538 -70.377812) (xy 113.138619 -70.386183) (xy 113.134959 -70.405237)
			(xy 113.138646 -70.424287) (xy 113.143538 -70.432676) (xy 113.166016 -70.468532) (xy 113.204764 -70.543773)
			(xy 113.236192 -70.622354) (xy 113.260013 -70.703564) (xy 113.276014 -70.786671) (xy 113.284049 -70.870921)
			(xy 113.284045 -70.955553) (xy 113.276003 -71.039803) (xy 113.259996 -71.122908) (xy 113.236167 -71.204116)
			(xy 113.204734 -71.282695) (xy 113.165979 -71.357932) (xy 113.143538 -71.393812) (xy 113.138619 -71.402183)
			(xy 113.134959 -71.421237) (xy 113.138646 -71.440287) (xy 113.143538 -71.448676) (xy 113.165961 -71.484564)
			(xy 113.204707 -71.559802) (xy 113.236134 -71.638378) (xy 113.259957 -71.719584) (xy 113.275962 -71.802685)
			(xy 113.284004 -71.88693) (xy 113.284508 -71.929244) (xy 113.28409 -71.970355) (xy 113.276498 -72.052227)
			(xy 113.261383 -72.133048) (xy 113.238875 -72.21213) (xy 113.209164 -72.288798) (xy 113.172506 -72.362396)
			(xy 113.129212 -72.432297) (xy 113.079652 -72.497905) (xy 113.024249 -72.55866) (xy 112.963476 -72.614042)
			(xy 112.897851 -72.66358) (xy 112.827936 -72.706851) (xy 112.754325 -72.743485) (xy 112.677648 -72.773169)
			(xy 112.598558 -72.795651) (xy 112.517732 -72.810739) (xy 112.435857 -72.818303) (xy 112.394746 -72.818752)
			(xy 112.352437 -72.81829) (xy 112.2682 -72.810282) (xy 112.185103 -72.794314) (xy 112.103897 -72.770532)
			(xy 112.025315 -72.739148) (xy 111.950066 -72.700448) (xy 111.914178 -72.678036) (xy 111.905789 -72.673153)
			(xy 111.886746 -72.669482) (xy 111.867703 -72.673153) (xy 111.859314 -72.678036) (xy 111.823421 -72.700442)
			(xy 111.74818 -72.739158) (xy 111.669601 -72.770548) (xy 111.588394 -72.79433) (xy 111.505295 -72.810287)
			(xy 111.421055 -72.818276) (xy 111.378746 -72.818752) (xy 111.336437 -72.81829) (xy 111.2522 -72.810282)
			(xy 111.169103 -72.794314) (xy 111.087897 -72.770532) (xy 111.009315 -72.739148) (xy 110.934066 -72.700448)
			(xy 110.898178 -72.678036) (xy 110.889789 -72.673153) (xy 110.870746 -72.669482) (xy 110.851703 -72.673153)
			(xy 110.843314 -72.678036) (xy 110.807421 -72.700442) (xy 110.73218 -72.739158) (xy 110.653601 -72.770548)
			(xy 110.572394 -72.79433) (xy 110.489295 -72.810287) (xy 110.405055 -72.818276) (xy 110.362746 -72.818752)
			(xy 110.321736 -72.818307) (xy 110.240064 -72.81076) (xy 110.159434 -72.795726) (xy 110.08053 -72.773333)
			(xy 110.004023 -72.74377) (xy 109.930563 -72.70729) (xy 109.860773 -72.664201) (xy 109.795246 -72.614871)
			(xy 109.734539 -72.559717) (xy 109.679168 -72.499208) (xy 109.629603 -72.433859) (xy 109.586264 -72.364224)
			(xy 109.567472 -72.32777) (xy 109.562392 -72.318118) (xy 109.54639 -72.304656) (xy 109.45368 -72.277986)
			(xy 109.432852 -72.28078) (xy 109.423708 -72.286622) (xy 109.366375 -72.320967) (xy 109.24821 -72.383438)
			(xy 109.126467 -72.438611) (xy 109.001595 -72.486281) (xy 108.874056 -72.526273) (xy 108.744322 -72.558439)
			(xy 108.612872 -72.58266) (xy 108.480194 -72.598845) (xy 108.346777 -72.606936) (xy 108.279946 -72.607424)
			(xy 108.212878 -72.606923) (xy 108.078991 -72.598751) (xy 107.945853 -72.582428) (xy 107.813957 -72.558015)
			(xy 107.683796 -72.525603) (xy 107.555854 -72.485313) (xy 107.430608 -72.437295) (xy 107.308524 -72.381727)
			(xy 107.190056 -72.318816) (xy 107.075645 -72.248797) (xy 106.965718 -72.171931) (xy 106.860684 -72.088503)
			(xy 106.760934 -71.998824) (xy 106.666839 -71.903228) (xy 106.57875 -71.802071) (xy 106.496994 -71.69573)
			(xy 106.45902 -71.640446) (xy 106.451908 -71.630032) (xy 106.42981 -71.618094) (xy 106.320082 -71.618094)
			(xy 106.297984 -71.630032) (xy 106.290872 -71.640446) (xy 106.25287 -71.695711) (xy 106.171122 -71.802059)
			(xy 106.08304 -71.903222) (xy 105.98895 -71.998824) (xy 105.889205 -72.088508) (xy 105.784174 -72.171941)
			(xy 105.674249 -72.248812) (xy 105.55984 -72.318834) (xy 105.441373 -72.381747) (xy 105.319289 -72.437317)
			(xy 105.194042 -72.485335) (xy 105.0661 -72.525625) (xy 104.935938 -72.558035) (xy 104.804041 -72.582444)
			(xy 104.670901 -72.598763) (xy 104.537014 -72.60693) (xy 104.469946 -72.607424) (xy 104.403553 -72.606916)
			(xy 104.27101 -72.598902) (xy 104.139193 -72.5829) (xy 104.008582 -72.558969) (xy 103.879654 -72.527195)
			(xy 103.75288 -72.487696) (xy 103.628722 -72.440614) (xy 103.507633 -72.386123) (xy 103.390055 -72.32442)
			(xy 103.276417 -72.25573) (xy 103.167133 -72.180305) (xy 103.062602 -72.09842) (xy 102.963206 -72.010373)
			(xy 102.869307 -71.916485) (xy 102.781248 -71.817099) (xy 102.69935 -71.712578) (xy 102.623912 -71.603304)
			(xy 102.555209 -71.489673) (xy 102.493492 -71.372103) (xy 102.438986 -71.25102) (xy 102.39189 -71.126868)
			(xy 102.352375 -71.000098) (xy 102.320586 -70.871174) (xy 102.296639 -70.740566) (xy 102.280622 -70.608751)
			(xy 102.272592 -70.476209) (xy 102.272084 -70.409816) (xy 102.272569 -70.34359) (xy 102.280552 -70.211379)
			(xy 102.296484 -70.079888) (xy 102.320308 -69.949596) (xy 102.351937 -69.820976) (xy 102.391256 -69.694495)
			(xy 102.438121 -69.570611) (xy 102.492364 -69.449775) (xy 102.553787 -69.332426) (xy 102.587552 -69.275452)
			(xy 102.593902 -69.265038) (xy 102.59568 -69.241416) (xy 102.555548 -69.143372) (xy 102.537768 -69.127878)
			(xy 102.52583 -69.124576) (xy 102.477308 -69.111506) (xy 102.382235 -69.078934) (xy 102.289972 -69.039095)
			(xy 102.201072 -68.992228) (xy 102.116069 -68.938615) (xy 102.035476 -68.878579) (xy 101.959775 -68.81248)
			(xy 101.889422 -68.740715) (xy 101.82484 -68.663715) (xy 101.766417 -68.581944) (xy 101.714505 -68.495893)
			(xy 101.669414 -68.406079) (xy 101.631417 -68.313042) (xy 101.600741 -68.217341) (xy 101.577571 -68.119551)
			(xy 101.562046 -68.02026) (xy 101.554259 -67.920065) (xy 101.553772 -67.869816) (xy 64.146176 -67.869816)
			(xy 64.14552 -67.929021) (xy 64.134706 -68.046936) (xy 64.124586 -68.105274) (xy 64.1223 -68.117212)
			(xy 64.128904 -68.140072) (xy 64.20104 -68.217796) (xy 64.223138 -68.225924) (xy 64.23533 -68.224654)
			(xy 64.293827 -68.218795) (xy 64.411238 -68.212571) (xy 64.470026 -68.212208) (xy 64.537093 -68.212761)
			(xy 64.670978 -68.220931) (xy 64.804115 -68.237252) (xy 64.936009 -68.261662) (xy 65.066169 -68.294071)
			(xy 65.19411 -68.334358) (xy 65.319355 -68.382374) (xy 65.441439 -68.437938) (xy 65.559907 -68.500845)
			(xy 65.674318 -68.570861) (xy 65.784245 -68.647723) (xy 65.88928 -68.731148) (xy 65.989031 -68.820822)
			(xy 66.083128 -68.916414) (xy 66.171219 -69.017567) (xy 66.252976 -69.123904) (xy 66.290952 -69.179186)
			(xy 66.298064 -69.1896) (xy 66.320162 -69.201538) (xy 66.42989 -69.201538) (xy 66.451988 -69.1896)
			(xy 66.4591 -69.179186) (xy 66.497065 -69.123895) (xy 66.578815 -69.017546) (xy 66.666899 -68.916383)
			(xy 66.760991 -68.820781) (xy 66.860739 -68.731096) (xy 66.965772 -68.647664) (xy 67.0757 -68.570794)
			(xy 67.190111 -68.500773) (xy 67.308581 -68.437862) (xy 67.430668 -68.382294) (xy 67.555917 -68.334278)
			(xy 67.683863 -68.293991) (xy 67.814027 -68.261584) (xy 67.945926 -68.237178) (xy 68.079068 -68.220863)
			(xy 68.212957 -68.2127) (xy 68.280026 -68.212208) (xy 68.348503 -68.212702) (xy 68.485191 -68.22123)
			(xy 68.621084 -68.238252) (xy 68.755653 -68.263701) (xy 68.888376 -68.29748) (xy 69.018739 -68.339456)
			(xy 69.146235 -68.389467) (xy 69.270371 -68.447318) (xy 69.390664 -68.512787) (xy 69.448934 -68.548758)
			(xy 69.458332 -68.5546) (xy 69.480176 -68.557394) (xy 69.575426 -68.52793) (xy 69.591682 -68.512944)
			(xy 69.596254 -68.502784) (xy 69.613781 -68.463304) (xy 69.655415 -68.387612) (xy 69.704189 -68.316312)
			(xy 69.759644 -68.250076) (xy 69.821258 -68.189526) (xy 69.88845 -68.135232) (xy 69.960589 -68.087708)
			(xy 70.036994 -68.047398) (xy 70.116946 -68.014684) (xy 70.199693 -67.989873) (xy 70.284454 -67.9732)
			(xy 70.370433 -67.96482) (xy 70.413626 -67.964304) (xy 70.455934 -67.964787) (xy 70.540171 -67.972792)
			(xy 70.623267 -67.988756) (xy 70.704473 -68.012535) (xy 70.783056 -68.043914) (xy 70.858305 -68.08261)
			(xy 70.894194 -68.10502) (xy 70.902583 -68.109903) (xy 70.921626 -68.113574) (xy 70.940669 -68.109903)
			(xy 70.949058 -68.10502) (xy 70.984929 -68.082579) (xy 71.060175 -68.043869) (xy 71.13876 -68.012484)
			(xy 71.219971 -67.988709) (xy 71.303073 -67.972759) (xy 71.387316 -67.964777) (xy 71.429626 -67.964304)
			(xy 71.471934 -67.964787) (xy 71.556171 -67.972792) (xy 71.639267 -67.988756) (xy 71.720473 -68.012535)
			(xy 71.799056 -68.043914) (xy 71.874305 -68.08261) (xy 71.910194 -68.10502) (xy 71.918583 -68.109903)
			(xy 71.937626 -68.113574) (xy 71.956669 -68.109903) (xy 71.965058 -68.10502) (xy 72.000929 -68.082579)
			(xy 72.076175 -68.043869) (xy 72.15476 -68.012484) (xy 72.235971 -67.988709) (xy 72.319073 -67.972759)
			(xy 72.403316 -67.964777) (xy 72.445626 -67.964304) (xy 72.486732 -67.964788) (xy 72.568594 -67.972374)
			(xy 72.649407 -67.987479) (xy 72.728481 -68.009975) (xy 72.805144 -68.03967) (xy 72.87874 -68.076309)
			(xy 72.948642 -68.119582) (xy 73.014255 -68.169118) (xy 73.075018 -68.224496) (xy 73.130414 -68.285243)
			(xy 73.17997 -68.350841) (xy 73.223263 -68.420731) (xy 73.259924 -68.494317) (xy 73.289641 -68.57097)
			(xy 73.312161 -68.650038) (xy 73.32729 -68.730847) (xy 73.3349 -68.812706) (xy 73.335388 -68.853812)
			(xy 73.334894 -68.896127) (xy 73.326862 -68.980375) (xy 73.310862 -69.063479) (xy 73.28704 -69.144687)
			(xy 73.25561 -69.223265) (xy 73.216858 -69.298501) (xy 73.194418 -69.33438) (xy 73.189526 -69.342764)
			(xy 73.185859 -69.36181) (xy 73.189534 -69.380855) (xy 73.194418 -69.389244) (xy 73.216868 -69.425117)
			(xy 73.255619 -69.500355) (xy 73.287048 -69.578933) (xy 73.310873 -69.660142) (xy 73.326876 -69.743246)
			(xy 73.334913 -69.827495) (xy 73.334912 -69.912126) (xy 73.326873 -69.996374) (xy 73.310868 -70.079478)
			(xy 73.287042 -70.160686) (xy 73.25561 -70.239264) (xy 73.216857 -70.314501) (xy 73.194418 -70.35038)
			(xy 73.189526 -70.358764) (xy 73.185859 -70.37781) (xy 73.189534 -70.396855) (xy 73.194418 -70.405244)
			(xy 73.216868 -70.441117) (xy 73.255619 -70.516355) (xy 73.287048 -70.594933) (xy 73.310873 -70.676142)
			(xy 73.326876 -70.759246) (xy 73.334913 -70.843495) (xy 73.334912 -70.928126) (xy 73.326873 -71.012374)
			(xy 73.310868 -71.095478) (xy 73.287042 -71.176686) (xy 73.25561 -71.255264) (xy 73.216857 -71.330501)
			(xy 73.194418 -71.36638) (xy 73.189526 -71.374764) (xy 73.185859 -71.39381) (xy 73.189534 -71.412855)
			(xy 73.194418 -71.421244) (xy 73.216867 -71.457116) (xy 73.25561 -71.532357) (xy 73.287033 -71.610937)
			(xy 73.310852 -71.692146) (xy 73.326851 -71.77525) (xy 73.334887 -71.859497) (xy 73.335388 -71.901812)
			(xy 73.334959 -71.942923) (xy 73.32737 -72.024795) (xy 73.312258 -72.105617) (xy 73.289751 -72.1847)
			(xy 73.260042 -72.261368) (xy 73.223385 -72.334967) (xy 73.180092 -72.404869) (xy 73.130533 -72.470478)
			(xy 73.075131 -72.531233) (xy 73.014358 -72.586616) (xy 72.948733 -72.636154) (xy 72.878817 -72.679424)
			(xy 72.805206 -72.716058) (xy 72.728529 -72.745742) (xy 72.649439 -72.768223) (xy 72.568612 -72.783309)
			(xy 72.486738 -72.790872) (xy 72.445626 -72.79132) (xy 72.403319 -72.790808) (xy 72.319083 -72.782808)
			(xy 72.235987 -72.766849) (xy 72.154781 -72.743076) (xy 72.076198 -72.711702) (xy 72.000948 -72.673011)
			(xy 71.965058 -72.650604) (xy 71.956669 -72.645721) (xy 71.937626 -72.64205) (xy 71.918583 -72.645721)
			(xy 71.910194 -72.650604) (xy 71.874311 -72.673026) (xy 71.799067 -72.711738) (xy 71.720486 -72.743126)
			(xy 71.639277 -72.766904) (xy 71.556176 -72.782859) (xy 71.471936 -72.790845) (xy 71.429626 -72.79132)
			(xy 71.387319 -72.790808) (xy 71.303083 -72.782808) (xy 71.219987 -72.766849) (xy 71.138781 -72.743076)
			(xy 71.060198 -72.711702) (xy 70.984948 -72.673011) (xy 70.949058 -72.650604) (xy 70.940669 -72.645721)
			(xy 70.921626 -72.64205) (xy 70.902583 -72.645721) (xy 70.894194 -72.650604) (xy 70.858311 -72.673026)
			(xy 70.783067 -72.711738) (xy 70.704486 -72.743126) (xy 70.623277 -72.766904) (xy 70.540176 -72.782859)
			(xy 70.455936 -72.790845) (xy 70.413626 -72.79132) (xy 70.372474 -72.790836) (xy 70.290522 -72.783244)
			(xy 70.209621 -72.768112) (xy 70.130464 -72.745571) (xy 70.053729 -72.715814) (xy 69.980071 -72.679093)
			(xy 69.91012 -72.635725) (xy 69.844476 -72.58608) (xy 69.783699 -72.530582) (xy 69.728309 -72.469706)
			(xy 69.678781 -72.403973) (xy 69.635537 -72.333946) (xy 69.616828 -72.29729) (xy 69.611748 -72.287384)
			(xy 69.595492 -72.273922) (xy 69.501004 -72.24776) (xy 69.479922 -72.251062) (xy 69.470778 -72.257158)
			(xy 69.411715 -72.294571) (xy 69.2896 -72.362684) (xy 69.163401 -72.422894) (xy 69.033629 -72.474957)
			(xy 68.900809 -72.518663) (xy 68.765478 -72.553834) (xy 68.628185 -72.580329) (xy 68.489485 -72.59804)
			(xy 68.349939 -72.606894) (xy 68.280026 -72.607424) (xy 68.212958 -72.606939) (xy 68.079071 -72.598766)
			(xy 67.945932 -72.582442) (xy 67.814036 -72.558028) (xy 67.683875 -72.525615) (xy 67.555933 -72.485323)
			(xy 67.430686 -72.437304) (xy 67.308602 -72.381735) (xy 67.190134 -72.318823) (xy 67.075724 -72.248803)
			(xy 66.965797 -72.171935) (xy 66.860763 -72.088506) (xy 66.761013 -71.998827) (xy 66.666918 -71.90323)
			(xy 66.57883 -71.802072) (xy 66.497074 -71.69573) (xy 66.4591 -71.640446) (xy 66.451988 -71.630032)
			(xy 66.42989 -71.618094) (xy 66.320162 -71.618094) (xy 66.298064 -71.630032) (xy 66.290952 -71.640446)
			(xy 66.252963 -71.695721) (xy 66.171215 -71.802068) (xy 66.083131 -71.903231) (xy 65.989041 -71.998833)
			(xy 65.889294 -72.088517) (xy 65.784262 -72.17195) (xy 65.674337 -72.24882) (xy 65.559927 -72.318842)
			(xy 65.441459 -72.381754) (xy 65.319374 -72.437323) (xy 65.194126 -72.485341) (xy 65.066183 -72.525629)
			(xy 64.93602 -72.558038) (xy 64.804123 -72.582447) (xy 64.670982 -72.598765) (xy 64.537094 -72.60693)
			(xy 64.470026 -72.607424) (xy 64.403633 -72.606935) (xy 64.27109 -72.59892) (xy 64.139272 -72.582917)
			(xy 64.008661 -72.558985) (xy 63.879733 -72.52721) (xy 63.752959 -72.48771) (xy 63.628801 -72.440627)
			(xy 63.507712 -72.386135) (xy 63.390133 -72.32443) (xy 63.276495 -72.25574) (xy 63.167211 -72.180314)
			(xy 63.062681 -72.098428) (xy 62.963285 -72.01038) (xy 62.869386 -71.916492) (xy 62.781327 -71.817105)
			(xy 62.699429 -71.712584) (xy 62.623991 -71.603308) (xy 62.555288 -71.489678) (xy 62.493571 -71.372106)
			(xy 62.439065 -71.251023) (xy 62.391969 -71.12687) (xy 62.352455 -71.0001) (xy 62.320666 -70.871176)
			(xy 62.296719 -70.740567) (xy 62.280702 -70.608751) (xy 62.272672 -70.476209) (xy 62.272164 -70.409816)
			(xy 62.272637 -70.34359) (xy 62.280621 -70.211378) (xy 62.296554 -70.079887) (xy 62.320379 -69.949595)
			(xy 62.352008 -69.820975) (xy 62.391329 -69.694493) (xy 62.438196 -69.57061) (xy 62.492441 -69.449774)
			(xy 62.553866 -69.332426) (xy 62.587632 -69.275452) (xy 62.593982 -69.265038) (xy 62.59576 -69.241416)
			(xy 62.555628 -69.143372) (xy 62.537848 -69.127878) (xy 62.52591 -69.124576) (xy 62.477384 -69.111519)
			(xy 62.382312 -69.078946) (xy 62.290048 -69.039106) (xy 62.201148 -68.992238) (xy 62.116146 -68.938624)
			(xy 62.035553 -68.878586) (xy 61.959852 -68.812486) (xy 61.8895 -68.74072) (xy 61.824919 -68.66372)
			(xy 61.766496 -68.581948) (xy 61.714584 -68.495896) (xy 61.669493 -68.406082) (xy 61.631496 -68.313044)
			(xy 61.60082 -68.217342) (xy 61.577651 -68.119552) (xy 61.562126 -68.020261) (xy 61.554339 -67.920065)
			(xy 61.553852 -67.869816) (xy 12.462296 -67.869816) (xy 12.543801 -67.875925) (xy 12.6453 -67.891224)
			(xy 12.745372 -67.914066) (xy 12.843457 -67.944323) (xy 12.939007 -67.981824) (xy 13.031487 -68.026361)
			(xy 13.12038 -68.077685) (xy 13.205189 -68.135508) (xy 13.28544 -68.199507) (xy 13.360685 -68.269324)
			(xy 13.430501 -68.344569) (xy 13.494499 -68.42482) (xy 13.552321 -68.50963) (xy 13.603644 -68.598524)
			(xy 13.64818 -68.691004) (xy 13.685681 -68.786554) (xy 13.715937 -68.88464) (xy 13.738778 -68.984712)
			(xy 13.754077 -69.086211) (xy 13.761748 -69.188569) (xy 13.762228 -69.239892) (xy 13.761691 -69.294799)
			(xy 13.752937 -69.404262) (xy 13.73546 -69.512676) (xy 13.709373 -69.619345) (xy 13.674841 -69.723588)
			(xy 13.632088 -69.824737) (xy 13.581385 -69.922144) (xy 13.523057 -70.015186) (xy 13.490702 -70.05955)
			(xy 13.484624 -70.068604) (xy 13.480031 -70.089902) (xy 13.484626 -70.1112) (xy 13.490702 -70.120256)
			(xy 13.523049 -70.164626) (xy 13.581374 -70.257669) (xy 13.632076 -70.355076) (xy 13.67483 -70.456223)
			(xy 13.709363 -70.560465) (xy 13.735454 -70.667133) (xy 13.752935 -70.775545) (xy 13.761695 -70.885008)
			(xy 13.762228 -70.939914) (xy 13.761756 -70.99124) (xy 13.754085 -71.093606) (xy 13.738787 -71.195112)
			(xy 13.715947 -71.295192) (xy 13.685693 -71.393285) (xy 13.648194 -71.488843) (xy 13.603659 -71.581332)
			(xy 13.552338 -71.670235) (xy 13.494518 -71.755054) (xy 13.430521 -71.835316) (xy 13.360706 -71.910572)
			(xy 13.285463 -71.9804) (xy 13.205212 -72.044411) (xy 13.120403 -72.102247) (xy 13.031509 -72.153584)
			(xy 12.939028 -72.198135) (xy 12.843477 -72.235652) (xy 12.745389 -72.265924) (xy 12.645314 -72.288782)
			(xy 12.54381 -72.304098) (xy 12.441446 -72.311787) (xy 12.39012 -72.312276) (xy 12.339213 -72.311802)
			(xy 12.23768 -72.304233) (xy 12.136987 -72.28916) (xy 12.037688 -72.266667) (xy 11.940329 -72.236876)
			(xy 11.845446 -72.199952) (xy 11.75356 -72.156098) (xy 11.665176 -72.105555) (xy 11.580782 -72.048601)
			(xy 11.50084 -71.98555) (xy 11.42579 -71.916747) (xy 11.356046 -71.842572) (xy 11.291991 -71.763431)
			(xy 11.233977 -71.679762) (xy 11.20775 -71.636128) (xy 11.200892 -71.624444) (xy 11.177524 -71.611236)
			(xy 11.062716 -71.611236) (xy 11.039348 -71.624444) (xy 11.03249 -71.636128) (xy 11.006274 -71.679769)
			(xy 10.948263 -71.763443) (xy 10.88421 -71.842586) (xy 10.814467 -71.916765) (xy 10.739418 -71.98557)
			(xy 10.659476 -72.048624) (xy 10.57508 -72.105579) (xy 10.486695 -72.156122) (xy 10.394806 -72.199975)
			(xy 10.299921 -72.236897) (xy 10.202559 -72.266684) (xy 10.103258 -72.289173) (xy 10.002563 -72.304241)
			(xy 9.901028 -72.311804) (xy 9.85012 -72.312276) (xy 9.798791 -72.311809) (xy 9.696419 -72.304137)
			(xy 9.594908 -72.288835) (xy 9.494824 -72.265988) (xy 9.396727 -72.235726) (xy 9.301167 -72.198216)
			(xy 9.208677 -72.153669) (xy 9.119776 -72.102335) (xy 9.034959 -72.044499) (xy 8.954703 -71.980486)
			(xy 8.879455 -71.910654) (xy 8.809637 -71.835393) (xy 8.745639 -71.755125) (xy 8.687819 -71.670298)
			(xy 8.636501 -71.581386) (xy 8.591972 -71.488888) (xy 8.55448 -71.393321) (xy 8.524235 -71.295219)
			(xy 8.501408 -71.195131) (xy 8.486124 -71.093616) (xy 8.478471 -70.991243) (xy 8.478012 -70.939914)
			(xy 0.509016 -70.939914) (xy 0.509016 -76.019914) (xy 8.478012 -76.019914) (xy 8.478545 -75.965007)
			(xy 8.487299 -75.855543) (xy 8.504775 -75.747129) (xy 8.530863 -75.64046) (xy 8.565395 -75.536217)
			(xy 8.608149 -75.435068) (xy 8.658854 -75.337662) (xy 8.717182 -75.24462) (xy 8.749538 -75.200256)
			(xy 8.755682 -75.191222) (xy 8.760349 -75.169902) (xy 8.755684 -75.148582) (xy 8.749538 -75.13955)
			(xy 8.717186 -75.095184) (xy 8.65886 -75.002141) (xy 8.608158 -74.904733) (xy 8.565404 -74.803585)
			(xy 8.530872 -74.699343) (xy 8.504782 -74.592674) (xy 8.487302 -74.484262) (xy 8.478544 -74.374799)
			(xy 8.478012 -74.319892) (xy 8.478453 -74.268568) (xy 8.486124 -74.166208) (xy 8.501424 -74.064707)
			(xy 8.524266 -73.964633) (xy 8.554522 -73.866547) (xy 8.592024 -73.770995) (xy 8.636562 -73.678513)
			(xy 8.687887 -73.589618) (xy 8.745711 -73.504808) (xy 8.809711 -73.424555) (xy 8.87953 -73.34931)
			(xy 8.954776 -73.279493) (xy 9.03503 -73.215494) (xy 9.119842 -73.157672) (xy 9.208738 -73.106349)
			(xy 9.301221 -73.061813) (xy 9.396773 -73.024313) (xy 9.49486 -72.994058) (xy 9.594935 -72.971218)
			(xy 9.696436 -72.955921) (xy 9.798796 -72.948252) (xy 9.85012 -72.947784) (xy 9.901023 -72.948245)
			(xy 10.00255 -72.955789) (xy 10.103239 -72.970838) (xy 10.202535 -72.993308) (xy 10.299893 -73.023077)
			(xy 10.394776 -73.05998) (xy 10.486663 -73.103815) (xy 10.575047 -73.154339) (xy 10.659444 -73.211276)
			(xy 10.739389 -73.274313) (xy 10.814441 -73.343101) (xy 10.884187 -73.417263) (xy 10.948245 -73.496391)
			(xy 11.006262 -73.580049) (xy 11.03249 -73.623678) (xy 11.039348 -73.635362) (xy 11.062716 -73.64857)
			(xy 11.177524 -73.64857) (xy 11.200892 -73.635362) (xy 11.20775 -73.623678) (xy 11.233971 -73.580045)
			(xy 11.291989 -73.496388) (xy 11.356048 -73.417261) (xy 11.425796 -73.3431) (xy 11.500849 -73.274313)
			(xy 11.580794 -73.211277) (xy 11.665192 -73.154341) (xy 11.753577 -73.103817) (xy 11.845464 -73.059983)
			(xy 11.940347 -73.02308) (xy 12.037705 -72.993311) (xy 12.137001 -72.970841) (xy 12.23769 -72.955792)
			(xy 12.339217 -72.948247) (xy 12.39012 -72.947784) (xy 12.441443 -72.948253) (xy 12.543801 -72.955925)
			(xy 12.6453 -72.971224) (xy 12.745372 -72.994066) (xy 12.843457 -73.024323) (xy 12.939007 -73.061824)
			(xy 13.031487 -73.106361) (xy 13.12038 -73.157685) (xy 13.205189 -73.215508) (xy 13.28544 -73.279507)
			(xy 13.360685 -73.349324) (xy 13.430501 -73.424569) (xy 13.494499 -73.50482) (xy 13.552321 -73.58963)
			(xy 13.603644 -73.678524) (xy 13.64818 -73.771004) (xy 13.685681 -73.866554) (xy 13.715937 -73.96464)
			(xy 13.738778 -74.064712) (xy 13.754077 -74.166211) (xy 13.761748 -74.268569) (xy 13.762228 -74.319892)
			(xy 13.761691 -74.374799) (xy 13.752937 -74.484262) (xy 13.73546 -74.592676) (xy 13.709373 -74.699345)
			(xy 13.674841 -74.803588) (xy 13.632088 -74.904737) (xy 13.581385 -75.002144) (xy 13.523057 -75.095186)
			(xy 13.490702 -75.13955) (xy 13.484624 -75.148604) (xy 13.480031 -75.169902) (xy 13.484626 -75.1912)
			(xy 13.490702 -75.200256) (xy 13.523049 -75.244626) (xy 13.581374 -75.337669) (xy 13.632076 -75.435076)
			(xy 13.67483 -75.536223) (xy 13.709363 -75.640465) (xy 13.735454 -75.747133) (xy 13.752935 -75.855545)
			(xy 13.761695 -75.965008) (xy 13.762228 -76.019914) (xy 13.761756 -76.07124) (xy 13.754085 -76.173606)
			(xy 13.738787 -76.275112) (xy 13.715947 -76.375192) (xy 13.685693 -76.473285) (xy 13.648194 -76.568843)
			(xy 13.603659 -76.661332) (xy 13.552338 -76.750235) (xy 13.494518 -76.835054) (xy 13.430521 -76.915316)
			(xy 13.360706 -76.990572) (xy 13.285463 -77.0604) (xy 13.205212 -77.124411) (xy 13.120403 -77.182247)
			(xy 13.031509 -77.233584) (xy 12.939028 -77.278135) (xy 12.843477 -77.315652) (xy 12.745389 -77.345924)
			(xy 12.645314 -77.368782) (xy 12.54381 -77.384098) (xy 12.441446 -77.391787) (xy 12.39012 -77.392276)
			(xy 12.339213 -77.391802) (xy 12.23768 -77.384233) (xy 12.136987 -77.36916) (xy 12.037688 -77.346667)
			(xy 11.940329 -77.316876) (xy 11.845446 -77.279952) (xy 11.75356 -77.236098) (xy 11.665176 -77.185555)
			(xy 11.580782 -77.128601) (xy 11.50084 -77.06555) (xy 11.42579 -76.996747) (xy 11.356046 -76.922572)
			(xy 11.291991 -76.843431) (xy 11.233977 -76.759762) (xy 11.20775 -76.716128) (xy 11.200892 -76.704444)
			(xy 11.177524 -76.691236) (xy 11.062716 -76.691236) (xy 11.039348 -76.704444) (xy 11.03249 -76.716128)
			(xy 11.006274 -76.759769) (xy 10.948263 -76.843443) (xy 10.88421 -76.922586) (xy 10.814467 -76.996765)
			(xy 10.739418 -77.06557) (xy 10.659476 -77.128624) (xy 10.57508 -77.185579) (xy 10.486695 -77.236122)
			(xy 10.394806 -77.279975) (xy 10.299921 -77.316897) (xy 10.202559 -77.346684) (xy 10.103258 -77.369173)
			(xy 10.002563 -77.384241) (xy 9.901028 -77.391804) (xy 9.85012 -77.392276) (xy 9.798791 -77.391809)
			(xy 9.696419 -77.384137) (xy 9.594908 -77.368835) (xy 9.494824 -77.345988) (xy 9.396727 -77.315726)
			(xy 9.301167 -77.278216) (xy 9.208677 -77.233669) (xy 9.119776 -77.182335) (xy 9.034959 -77.124499)
			(xy 8.954703 -77.060486) (xy 8.879455 -76.990654) (xy 8.809637 -76.915393) (xy 8.745639 -76.835125)
			(xy 8.687819 -76.750298) (xy 8.636501 -76.661386) (xy 8.591972 -76.568888) (xy 8.55448 -76.473321)
			(xy 8.524235 -76.375219) (xy 8.501408 -76.275131) (xy 8.486124 -76.173616) (xy 8.478471 -76.071243)
			(xy 8.478012 -76.019914) (xy 0.509016 -76.019914) (xy 0.509016 -77.760011) (xy 61.960756 -77.760011)
			(xy 61.960756 -77.675289) (xy 61.968809 -77.590952) (xy 61.984843 -77.507762) (xy 62.008711 -77.426472)
			(xy 62.040199 -77.34782) (xy 62.079021 -77.272517) (xy 62.124824 -77.201245) (xy 62.177195 -77.134649)
			(xy 62.23566 -77.073334) (xy 62.299688 -77.017853) (xy 62.3687 -76.96871) (xy 62.44207 -76.92635)
			(xy 62.519135 -76.891155) (xy 62.599197 -76.863446) (xy 62.68153 -76.843472) (xy 62.765389 -76.831415)
			(xy 62.850014 -76.827384) (xy 62.934639 -76.831415) (xy 63.018498 -76.843472) (xy 63.100831 -76.863446)
			(xy 63.180893 -76.891155) (xy 63.257958 -76.92635) (xy 63.331328 -76.96871) (xy 63.40034 -77.017853)
			(xy 63.464368 -77.073334) (xy 63.522833 -77.134649) (xy 63.575204 -77.201245) (xy 63.621007 -77.272517)
			(xy 63.659829 -77.34782) (xy 63.691317 -77.426472) (xy 63.715185 -77.507762) (xy 63.731219 -77.590952)
			(xy 63.739272 -77.675289) (xy 63.739776 -77.71765) (xy 63.739272 -77.760011) (xy 101.960676 -77.760011)
			(xy 101.960676 -77.675289) (xy 101.968729 -77.590952) (xy 101.984763 -77.507762) (xy 102.008631 -77.426472)
			(xy 102.040119 -77.34782) (xy 102.078941 -77.272517) (xy 102.124744 -77.201245) (xy 102.177115 -77.134649)
			(xy 102.23558 -77.073334) (xy 102.299608 -77.017853) (xy 102.36862 -76.96871) (xy 102.44199 -76.92635)
			(xy 102.519055 -76.891155) (xy 102.599117 -76.863446) (xy 102.68145 -76.843472) (xy 102.765309 -76.831415)
			(xy 102.849934 -76.827384) (xy 102.934559 -76.831415) (xy 103.018418 -76.843472) (xy 103.100751 -76.863446)
			(xy 103.180813 -76.891155) (xy 103.257878 -76.92635) (xy 103.331248 -76.96871) (xy 103.40026 -77.017853)
			(xy 103.464288 -77.073334) (xy 103.522753 -77.134649) (xy 103.575124 -77.201245) (xy 103.620927 -77.272517)
			(xy 103.659749 -77.34782) (xy 103.691237 -77.426472) (xy 103.715105 -77.507762) (xy 103.731139 -77.590952)
			(xy 103.739192 -77.675289) (xy 103.739696 -77.71765) (xy 103.739192 -77.760011) (xy 141.96085 -77.760011)
			(xy 141.96085 -77.675289) (xy 141.968903 -77.590952) (xy 141.984937 -77.507762) (xy 142.008805 -77.426472)
			(xy 142.040293 -77.34782) (xy 142.079115 -77.272517) (xy 142.124918 -77.201245) (xy 142.177289 -77.134649)
			(xy 142.235754 -77.073334) (xy 142.299782 -77.017853) (xy 142.368794 -76.96871) (xy 142.442164 -76.92635)
			(xy 142.519229 -76.891155) (xy 142.599291 -76.863446) (xy 142.681624 -76.843472) (xy 142.765483 -76.831415)
			(xy 142.850108 -76.827384) (xy 142.934733 -76.831415) (xy 143.018592 -76.843472) (xy 143.100925 -76.863446)
			(xy 143.180987 -76.891155) (xy 143.258052 -76.92635) (xy 143.331422 -76.96871) (xy 143.400434 -77.017853)
			(xy 143.464462 -77.073334) (xy 143.522927 -77.134649) (xy 143.575298 -77.201245) (xy 143.621101 -77.272517)
			(xy 143.659923 -77.34782) (xy 143.691411 -77.426472) (xy 143.715279 -77.507762) (xy 143.731313 -77.590952)
			(xy 143.739366 -77.675289) (xy 143.73987 -77.71765) (xy 143.739366 -77.760011) (xy 181.961024 -77.760011)
			(xy 181.961024 -77.675289) (xy 181.969077 -77.590952) (xy 181.985111 -77.507762) (xy 182.008979 -77.426472)
			(xy 182.040467 -77.34782) (xy 182.079289 -77.272517) (xy 182.125092 -77.201245) (xy 182.177463 -77.134649)
			(xy 182.235928 -77.073334) (xy 182.299956 -77.017853) (xy 182.368968 -76.96871) (xy 182.442338 -76.92635)
			(xy 182.519403 -76.891155) (xy 182.599465 -76.863446) (xy 182.681798 -76.843472) (xy 182.765657 -76.831415)
			(xy 182.850282 -76.827384) (xy 182.934907 -76.831415) (xy 183.018766 -76.843472) (xy 183.101099 -76.863446)
			(xy 183.181161 -76.891155) (xy 183.258226 -76.92635) (xy 183.331596 -76.96871) (xy 183.400608 -77.017853)
			(xy 183.464636 -77.073334) (xy 183.523101 -77.134649) (xy 183.575472 -77.201245) (xy 183.621275 -77.272517)
			(xy 183.660097 -77.34782) (xy 183.691585 -77.426472) (xy 183.715453 -77.507762) (xy 183.731487 -77.590952)
			(xy 183.732064 -77.597) (xy 268.350492 -77.597) (xy 268.351075 -77.550604) (xy 268.36072 -77.458316)
			(xy 268.379916 -77.367532) (xy 268.408454 -77.279239) (xy 268.426692 -77.236574) (xy 268.430498 -77.226632)
			(xy 268.430498 -77.205368) (xy 268.426692 -77.195426) (xy 268.408447 -77.152764) (xy 268.379903 -77.064471)
			(xy 268.36071 -76.973686) (xy 268.351077 -76.881396) (xy 268.350492 -76.835) (xy 268.351075 -76.788604)
			(xy 268.36072 -76.696316) (xy 268.379916 -76.605532) (xy 268.408454 -76.517239) (xy 268.426692 -76.474574)
			(xy 268.430498 -76.464632) (xy 268.430498 -76.443368) (xy 268.426692 -76.433426) (xy 268.408447 -76.390764)
			(xy 268.379903 -76.302471) (xy 268.36071 -76.211686) (xy 268.351077 -76.119396) (xy 268.350492 -76.073)
			(xy 268.351075 -76.026604) (xy 268.36072 -75.934316) (xy 268.379916 -75.843532) (xy 268.408454 -75.755239)
			(xy 268.426692 -75.712574) (xy 268.430498 -75.702632) (xy 268.430498 -75.681368) (xy 268.426692 -75.671426)
			(xy 268.408447 -75.628764) (xy 268.379903 -75.540471) (xy 268.36071 -75.449686) (xy 268.351077 -75.357396)
			(xy 268.350492 -75.311) (xy 268.351075 -75.264604) (xy 268.36072 -75.172316) (xy 268.379916 -75.081532)
			(xy 268.408454 -74.993239) (xy 268.426692 -74.950574) (xy 268.430498 -74.940632) (xy 268.430498 -74.919368)
			(xy 268.426692 -74.909426) (xy 268.408447 -74.866764) (xy 268.379903 -74.778471) (xy 268.36071 -74.687686)
			(xy 268.351077 -74.595396) (xy 268.350492 -74.549) (xy 268.351075 -74.502604) (xy 268.36072 -74.410316)
			(xy 268.379916 -74.319532) (xy 268.408454 -74.231239) (xy 268.426692 -74.188574) (xy 268.430498 -74.178632)
			(xy 268.430498 -74.157368) (xy 268.426692 -74.147426) (xy 268.408447 -74.104764) (xy 268.379903 -74.016471)
			(xy 268.36071 -73.925686) (xy 268.351077 -73.833396) (xy 268.350492 -73.787) (xy 268.350967 -73.745898)
			(xy 268.358552 -73.664043) (xy 268.373657 -73.583238) (xy 268.396153 -73.504171) (xy 268.425849 -73.427517)
			(xy 268.462491 -73.35393) (xy 268.505766 -73.284038) (xy 268.555306 -73.218437) (xy 268.610687 -73.157687)
			(xy 268.671437 -73.102306) (xy 268.737038 -73.052766) (xy 268.80693 -73.009491) (xy 268.880517 -72.972849)
			(xy 268.957171 -72.943153) (xy 269.036238 -72.920657) (xy 269.117043 -72.905552) (xy 269.198898 -72.897967)
			(xy 269.24 -72.897492) (xy 269.286396 -72.898075) (xy 269.378684 -72.90772) (xy 269.469468 -72.926916)
			(xy 269.557761 -72.955454) (xy 269.600426 -72.973692) (xy 269.610368 -72.977498) (xy 269.631632 -72.977498)
			(xy 269.641574 -72.973692) (xy 269.684236 -72.955447) (xy 269.772529 -72.926903) (xy 269.863314 -72.90771)
			(xy 269.955604 -72.898077) (xy 270.002 -72.897492) (xy 270.048396 -72.898075) (xy 270.140684 -72.90772)
			(xy 270.231468 -72.926916) (xy 270.319761 -72.955454) (xy 270.362426 -72.973692) (xy 270.372368 -72.977498)
			(xy 270.393632 -72.977498) (xy 270.403574 -72.973692) (xy 270.446236 -72.955447) (xy 270.534529 -72.926903)
			(xy 270.625314 -72.90771) (xy 270.717604 -72.898077) (xy 270.764 -72.897492) (xy 270.810396 -72.898075)
			(xy 270.902684 -72.90772) (xy 270.993468 -72.926916) (xy 271.081761 -72.955454) (xy 271.124426 -72.973692)
			(xy 271.134368 -72.977498) (xy 271.155632 -72.977498) (xy 271.165574 -72.973692) (xy 271.208236 -72.955447)
			(xy 271.296529 -72.926903) (xy 271.387314 -72.90771) (xy 271.479604 -72.898077) (xy 271.526 -72.897492)
			(xy 271.572396 -72.898075) (xy 271.664684 -72.90772) (xy 271.755468 -72.926916) (xy 271.843761 -72.955454)
			(xy 271.886426 -72.973692) (xy 271.896368 -72.977498) (xy 271.917632 -72.977498) (xy 271.927574 -72.973692)
			(xy 271.970236 -72.955447) (xy 272.058529 -72.926903) (xy 272.149314 -72.90771) (xy 272.241604 -72.898077)
			(xy 272.288 -72.897492) (xy 272.329102 -72.897967) (xy 272.410957 -72.905552) (xy 272.491762 -72.920657)
			(xy 272.570829 -72.943153) (xy 272.647483 -72.972849) (xy 272.72107 -73.009491) (xy 272.790962 -73.052766)
			(xy 272.856563 -73.102306) (xy 272.917313 -73.157687) (xy 272.972694 -73.218437) (xy 273.022234 -73.284038)
			(xy 273.065509 -73.35393) (xy 273.102151 -73.427517) (xy 273.131847 -73.504171) (xy 273.154343 -73.583238)
			(xy 273.169448 -73.664043) (xy 273.177033 -73.745898) (xy 273.177508 -73.787) (xy 273.176925 -73.833396)
			(xy 273.16728 -73.925684) (xy 273.148084 -74.016468) (xy 273.119546 -74.104761) (xy 273.101308 -74.147426)
			(xy 273.097502 -74.157368) (xy 273.097502 -74.178632) (xy 273.101308 -74.188574) (xy 273.119553 -74.231236)
			(xy 273.148097 -74.319529) (xy 273.16729 -74.410314) (xy 273.176923 -74.502604) (xy 273.177508 -74.549)
			(xy 273.177033 -74.590102) (xy 273.169448 -74.671957) (xy 273.154343 -74.752762) (xy 273.131847 -74.831829)
			(xy 273.102151 -74.908483) (xy 273.065509 -74.98207) (xy 273.022234 -75.051962) (xy 272.972694 -75.117563)
			(xy 272.917313 -75.178313) (xy 272.856563 -75.233694) (xy 272.790962 -75.283234) (xy 272.72107 -75.326509)
			(xy 272.647483 -75.363151) (xy 272.570829 -75.392847) (xy 272.491762 -75.415343) (xy 272.410957 -75.430448)
			(xy 272.329102 -75.438033) (xy 272.288 -75.438508) (xy 272.241604 -75.437925) (xy 272.149316 -75.42828)
			(xy 272.058532 -75.409084) (xy 271.970239 -75.380546) (xy 271.927574 -75.362308) (xy 271.917632 -75.358502)
			(xy 271.896368 -75.358502) (xy 271.886426 -75.362308) (xy 271.853507 -75.376537) (xy 271.785822 -75.400257)
			(xy 271.716442 -75.418437) (xy 271.681194 -75.425046) (xy 271.67107 -75.427344) (xy 271.653749 -75.438749)
			(xy 271.642344 -75.45607) (xy 271.640046 -75.466194) (xy 271.633416 -75.501437) (xy 271.61522 -75.57081)
			(xy 271.591513 -75.638498) (xy 271.577308 -75.671426) (xy 271.573502 -75.681368) (xy 271.573502 -75.702632)
			(xy 271.577308 -75.712574) (xy 271.591537 -75.745493) (xy 271.615257 -75.813178) (xy 271.633437 -75.882558)
			(xy 271.640046 -75.917806) (xy 271.642344 -75.92793) (xy 271.653749 -75.945251) (xy 271.67107 -75.956656)
			(xy 271.681194 -75.958954) (xy 271.716437 -75.965584) (xy 271.78581 -75.98378) (xy 271.853498 -76.007487)
			(xy 271.886426 -76.021692) (xy 271.896368 -76.025498) (xy 271.917632 -76.025498) (xy 271.927574 -76.021692)
			(xy 271.970236 -76.003447) (xy 272.058529 -75.974903) (xy 272.149314 -75.95571) (xy 272.241604 -75.946077)
			(xy 272.288 -75.945492) (xy 272.329102 -75.945967) (xy 272.410957 -75.953552) (xy 272.491762 -75.968657)
			(xy 272.570829 -75.991153) (xy 272.647483 -76.020849) (xy 272.72107 -76.057491) (xy 272.790962 -76.100766)
			(xy 272.856563 -76.150306) (xy 272.917313 -76.205687) (xy 272.972694 -76.266437) (xy 273.022234 -76.332038)
			(xy 273.065509 -76.40193) (xy 273.102151 -76.475517) (xy 273.131847 -76.552171) (xy 273.154343 -76.631238)
			(xy 273.169448 -76.712043) (xy 273.177033 -76.793898) (xy 273.177508 -76.835) (xy 273.176925 -76.881396)
			(xy 273.16728 -76.973684) (xy 273.148084 -77.064468) (xy 273.119546 -77.152761) (xy 273.101308 -77.195426)
			(xy 273.097502 -77.205368) (xy 273.097502 -77.226632) (xy 273.101308 -77.236574) (xy 273.119553 -77.279236)
			(xy 273.148097 -77.367529) (xy 273.16729 -77.458314) (xy 273.176923 -77.550604) (xy 273.177508 -77.597)
			(xy 273.177033 -77.638102) (xy 273.169448 -77.719957) (xy 273.154343 -77.800762) (xy 273.131847 -77.879829)
			(xy 273.102151 -77.956483) (xy 273.065509 -78.03007) (xy 273.022234 -78.099962) (xy 272.972694 -78.165563)
			(xy 272.917313 -78.226313) (xy 272.856563 -78.281694) (xy 272.790962 -78.331234) (xy 272.72107 -78.374509)
			(xy 272.647483 -78.411151) (xy 272.570829 -78.440847) (xy 272.491762 -78.463343) (xy 272.410957 -78.478448)
			(xy 272.329102 -78.486033) (xy 272.288 -78.486508) (xy 272.241604 -78.485925) (xy 272.149316 -78.47628)
			(xy 272.058532 -78.457084) (xy 271.970239 -78.428546) (xy 271.927574 -78.410308) (xy 271.917632 -78.406502)
			(xy 271.896368 -78.406502) (xy 271.886426 -78.410308) (xy 271.843764 -78.428553) (xy 271.755471 -78.457097)
			(xy 271.664686 -78.47629) (xy 271.572396 -78.485923) (xy 271.526 -78.486508) (xy 271.479604 -78.485925)
			(xy 271.387316 -78.47628) (xy 271.296532 -78.457084) (xy 271.208239 -78.428546) (xy 271.165574 -78.410308)
			(xy 271.155632 -78.406502) (xy 271.134368 -78.406502) (xy 271.124426 -78.410308) (xy 271.081764 -78.428553)
			(xy 270.993471 -78.457097) (xy 270.902686 -78.47629) (xy 270.810396 -78.485923) (xy 270.764 -78.486508)
			(xy 270.717604 -78.485925) (xy 270.625316 -78.47628) (xy 270.534532 -78.457084) (xy 270.446239 -78.428546)
			(xy 270.403574 -78.410308) (xy 270.393632 -78.406502) (xy 270.372368 -78.406502) (xy 270.362426 -78.410308)
			(xy 270.319764 -78.428553) (xy 270.231471 -78.457097) (xy 270.140686 -78.47629) (xy 270.048396 -78.485923)
			(xy 270.002 -78.486508) (xy 269.955604 -78.485925) (xy 269.863316 -78.47628) (xy 269.772532 -78.457084)
			(xy 269.684239 -78.428546) (xy 269.641574 -78.410308) (xy 269.631632 -78.406502) (xy 269.610368 -78.406502)
			(xy 269.600426 -78.410308) (xy 269.557764 -78.428553) (xy 269.469471 -78.457097) (xy 269.378686 -78.47629)
			(xy 269.286396 -78.485923) (xy 269.24 -78.486508) (xy 269.198898 -78.486033) (xy 269.117043 -78.478448)
			(xy 269.036238 -78.463343) (xy 268.957171 -78.440847) (xy 268.880517 -78.411151) (xy 268.80693 -78.374509)
			(xy 268.737038 -78.331234) (xy 268.671437 -78.281694) (xy 268.610687 -78.226313) (xy 268.555306 -78.165563)
			(xy 268.505766 -78.099962) (xy 268.462491 -78.03007) (xy 268.425849 -77.956483) (xy 268.396153 -77.879829)
			(xy 268.373657 -77.800762) (xy 268.358552 -77.719957) (xy 268.350967 -77.638102) (xy 268.350492 -77.597)
			(xy 183.732064 -77.597) (xy 183.73954 -77.675289) (xy 183.740044 -77.71765) (xy 183.73954 -77.760011)
			(xy 183.731487 -77.844348) (xy 183.715453 -77.927538) (xy 183.691585 -78.008828) (xy 183.660097 -78.08748)
			(xy 183.621275 -78.162783) (xy 183.575472 -78.234055) (xy 183.523101 -78.300651) (xy 183.464636 -78.361966)
			(xy 183.400608 -78.417447) (xy 183.331596 -78.46659) (xy 183.258226 -78.50895) (xy 183.181161 -78.544145)
			(xy 183.101099 -78.571854) (xy 183.018766 -78.591828) (xy 182.934907 -78.603885) (xy 182.850282 -78.607917)
			(xy 182.765657 -78.603885) (xy 182.681798 -78.591828) (xy 182.599465 -78.571854) (xy 182.519403 -78.544145)
			(xy 182.442338 -78.50895) (xy 182.368968 -78.46659) (xy 182.299956 -78.417447) (xy 182.235928 -78.361966)
			(xy 182.177463 -78.300651) (xy 182.125092 -78.234055) (xy 182.079289 -78.162783) (xy 182.040467 -78.08748)
			(xy 182.008979 -78.008828) (xy 181.985111 -77.927538) (xy 181.969077 -77.844348) (xy 181.961024 -77.760011)
			(xy 143.739366 -77.760011) (xy 143.731313 -77.844348) (xy 143.715279 -77.927538) (xy 143.691411 -78.008828)
			(xy 143.659923 -78.08748) (xy 143.621101 -78.162783) (xy 143.575298 -78.234055) (xy 143.522927 -78.300651)
			(xy 143.464462 -78.361966) (xy 143.400434 -78.417447) (xy 143.331422 -78.46659) (xy 143.258052 -78.50895)
			(xy 143.180987 -78.544145) (xy 143.100925 -78.571854) (xy 143.018592 -78.591828) (xy 142.934733 -78.603885)
			(xy 142.850108 -78.607917) (xy 142.765483 -78.603885) (xy 142.681624 -78.591828) (xy 142.599291 -78.571854)
			(xy 142.519229 -78.544145) (xy 142.442164 -78.50895) (xy 142.368794 -78.46659) (xy 142.299782 -78.417447)
			(xy 142.235754 -78.361966) (xy 142.177289 -78.300651) (xy 142.124918 -78.234055) (xy 142.079115 -78.162783)
			(xy 142.040293 -78.08748) (xy 142.008805 -78.008828) (xy 141.984937 -77.927538) (xy 141.968903 -77.844348)
			(xy 141.96085 -77.760011) (xy 103.739192 -77.760011) (xy 103.731139 -77.844348) (xy 103.715105 -77.927538)
			(xy 103.691237 -78.008828) (xy 103.659749 -78.08748) (xy 103.620927 -78.162783) (xy 103.575124 -78.234055)
			(xy 103.522753 -78.300651) (xy 103.464288 -78.361966) (xy 103.40026 -78.417447) (xy 103.331248 -78.46659)
			(xy 103.257878 -78.50895) (xy 103.180813 -78.544145) (xy 103.100751 -78.571854) (xy 103.018418 -78.591828)
			(xy 102.934559 -78.603885) (xy 102.849934 -78.607917) (xy 102.765309 -78.603885) (xy 102.68145 -78.591828)
			(xy 102.599117 -78.571854) (xy 102.519055 -78.544145) (xy 102.44199 -78.50895) (xy 102.36862 -78.46659)
			(xy 102.299608 -78.417447) (xy 102.23558 -78.361966) (xy 102.177115 -78.300651) (xy 102.124744 -78.234055)
			(xy 102.078941 -78.162783) (xy 102.040119 -78.08748) (xy 102.008631 -78.008828) (xy 101.984763 -77.927538)
			(xy 101.968729 -77.844348) (xy 101.960676 -77.760011) (xy 63.739272 -77.760011) (xy 63.731219 -77.844348)
			(xy 63.715185 -77.927538) (xy 63.691317 -78.008828) (xy 63.659829 -78.08748) (xy 63.621007 -78.162783)
			(xy 63.575204 -78.234055) (xy 63.522833 -78.300651) (xy 63.464368 -78.361966) (xy 63.40034 -78.417447)
			(xy 63.331328 -78.46659) (xy 63.257958 -78.50895) (xy 63.180893 -78.544145) (xy 63.100831 -78.571854)
			(xy 63.018498 -78.591828) (xy 62.934639 -78.603885) (xy 62.850014 -78.607917) (xy 62.765389 -78.603885)
			(xy 62.68153 -78.591828) (xy 62.599197 -78.571854) (xy 62.519135 -78.544145) (xy 62.44207 -78.50895)
			(xy 62.3687 -78.46659) (xy 62.299688 -78.417447) (xy 62.23566 -78.361966) (xy 62.177195 -78.300651)
			(xy 62.124824 -78.234055) (xy 62.079021 -78.162783) (xy 62.040199 -78.08748) (xy 62.008711 -78.008828)
			(xy 61.984843 -77.927538) (xy 61.968809 -77.844348) (xy 61.960756 -77.760011) (xy 0.509016 -77.760011)
			(xy 0.509016 -80.799629) (xy 270.301208 -80.799629) (xy 270.301208 -80.714907) (xy 270.309261 -80.63057)
			(xy 270.325295 -80.54738) (xy 270.349163 -80.46609) (xy 270.380651 -80.387438) (xy 270.419473 -80.312135)
			(xy 270.465276 -80.240863) (xy 270.517647 -80.174267) (xy 270.576112 -80.112952) (xy 270.64014 -80.057471)
			(xy 270.709152 -80.008328) (xy 270.782522 -79.965968) (xy 270.859587 -79.930773) (xy 270.939649 -79.903064)
			(xy 271.021982 -79.88309) (xy 271.105841 -79.871033) (xy 271.190466 -79.867002) (xy 271.275091 -79.871033)
			(xy 271.35895 -79.88309) (xy 271.441283 -79.903064) (xy 271.521345 -79.930773) (xy 271.59841 -79.965968)
			(xy 271.67178 -80.008328) (xy 271.740792 -80.057471) (xy 271.80482 -80.112952) (xy 271.863285 -80.174267)
			(xy 271.915656 -80.240863) (xy 271.961459 -80.312135) (xy 272.000281 -80.387438) (xy 272.031769 -80.46609)
			(xy 272.055637 -80.54738) (xy 272.071671 -80.63057) (xy 272.079724 -80.714907) (xy 272.080228 -80.757268)
			(xy 272.079724 -80.799629) (xy 272.071671 -80.883966) (xy 272.055637 -80.967156) (xy 272.031769 -81.048446)
			(xy 272.000281 -81.127098) (xy 271.961459 -81.202401) (xy 271.915656 -81.273673) (xy 271.863285 -81.340269)
			(xy 271.80482 -81.401584) (xy 271.740792 -81.457065) (xy 271.67178 -81.506208) (xy 271.59841 -81.548568)
			(xy 271.521345 -81.583763) (xy 271.441283 -81.611472) (xy 271.35895 -81.631446) (xy 271.275091 -81.643503)
			(xy 271.190466 -81.647535) (xy 271.105841 -81.643503) (xy 271.021982 -81.631446) (xy 270.939649 -81.611472)
			(xy 270.859587 -81.583763) (xy 270.782522 -81.548568) (xy 270.709152 -81.506208) (xy 270.64014 -81.457065)
			(xy 270.576112 -81.401584) (xy 270.517647 -81.340269) (xy 270.465276 -81.273673) (xy 270.419473 -81.202401)
			(xy 270.380651 -81.127098) (xy 270.349163 -81.048446) (xy 270.325295 -80.967156) (xy 270.309261 -80.883966)
			(xy 270.301208 -80.799629) (xy 0.509016 -80.799629) (xy 0.509016 -82.272829) (xy 268.757142 -82.272829)
			(xy 268.757142 -82.188107) (xy 268.765195 -82.10377) (xy 268.781229 -82.02058) (xy 268.805097 -81.93929)
			(xy 268.836585 -81.860638) (xy 268.875407 -81.785335) (xy 268.92121 -81.714063) (xy 268.973581 -81.647467)
			(xy 269.032046 -81.586152) (xy 269.096074 -81.530671) (xy 269.165086 -81.481528) (xy 269.238456 -81.439168)
			(xy 269.315521 -81.403973) (xy 269.395583 -81.376264) (xy 269.477916 -81.35629) (xy 269.561775 -81.344233)
			(xy 269.6464 -81.340202) (xy 269.731025 -81.344233) (xy 269.814884 -81.35629) (xy 269.897217 -81.376264)
			(xy 269.977279 -81.403973) (xy 270.054344 -81.439168) (xy 270.127714 -81.481528) (xy 270.196726 -81.530671)
			(xy 270.260754 -81.586152) (xy 270.319219 -81.647467) (xy 270.37159 -81.714063) (xy 270.417393 -81.785335)
			(xy 270.456215 -81.860638) (xy 270.487703 -81.93929) (xy 270.511571 -82.02058) (xy 270.527605 -82.10377)
			(xy 270.535658 -82.188107) (xy 270.536162 -82.230468) (xy 270.535658 -82.272829) (xy 270.527605 -82.357166)
			(xy 270.511571 -82.440356) (xy 270.487703 -82.521646) (xy 270.456215 -82.600298) (xy 270.417393 -82.675601)
			(xy 270.37159 -82.746873) (xy 270.319219 -82.813469) (xy 270.260754 -82.874784) (xy 270.196726 -82.930265)
			(xy 270.127714 -82.979408) (xy 270.054344 -83.021768) (xy 269.977279 -83.056963) (xy 269.897217 -83.084672)
			(xy 269.814884 -83.104646) (xy 269.731025 -83.116703) (xy 269.6464 -83.120735) (xy 269.561775 -83.116703)
			(xy 269.477916 -83.104646) (xy 269.395583 -83.084672) (xy 269.315521 -83.056963) (xy 269.238456 -83.021768)
			(xy 269.165086 -82.979408) (xy 269.096074 -82.930265) (xy 269.032046 -82.874784) (xy 268.973581 -82.813469)
			(xy 268.92121 -82.746873) (xy 268.875407 -82.675601) (xy 268.836585 -82.600298) (xy 268.805097 -82.521646)
			(xy 268.781229 -82.440356) (xy 268.765195 -82.357166) (xy 268.757142 -82.272829) (xy 0.509016 -82.272829)
			(xy 0.509016 -83.749896) (xy 11.118856 -83.749896) (xy 11.122874 -83.648894) (xy 11.134905 -83.54853)
			(xy 11.154871 -83.44944) (xy 11.182647 -83.352249) (xy 11.218058 -83.257572) (xy 11.260878 -83.166008)
			(xy 11.310838 -83.078135) (xy 11.367621 -82.994509) (xy 11.430869 -82.91566) (xy 11.500181 -82.842084)
			(xy 11.57512 -82.774248) (xy 11.655212 -82.71258) (xy 11.73995 -82.657471) (xy 11.828799 -82.609268)
			(xy 11.921196 -82.568277) (xy 12.016559 -82.534756) (xy 12.114283 -82.508918) (xy 12.21375 -82.490925)
			(xy 12.314333 -82.480893) (xy 12.415396 -82.478883) (xy 12.516298 -82.484909) (xy 12.616402 -82.498932)
			(xy 12.715076 -82.520865) (xy 12.811696 -82.550568) (xy 12.90565 -82.587854) (xy 12.996345 -82.632486)
			(xy 13.083207 -82.684183) (xy 13.165687 -82.742618) (xy 13.243264 -82.807421) (xy 13.315446 -82.878183)
			(xy 13.381779 -82.954456) (xy 13.441842 -83.035758) (xy 13.495256 -83.121575) (xy 13.541683 -83.211364)
			(xy 13.580829 -83.304558) (xy 13.612447 -83.400568) (xy 13.636337 -83.498786) (xy 13.652348 -83.598592)
			(xy 13.660379 -83.699355) (xy 13.660882 -83.749896) (xy 13.660379 -83.800437) (xy 13.652348 -83.9012)
			(xy 13.636337 -84.001006) (xy 13.612447 -84.099224) (xy 13.580829 -84.195234) (xy 13.541683 -84.288428)
			(xy 13.495256 -84.378217) (xy 13.441842 -84.464034) (xy 13.381779 -84.545336) (xy 13.315446 -84.621609)
			(xy 13.243264 -84.692371) (xy 13.165687 -84.757174) (xy 13.083207 -84.815609) (xy 12.996345 -84.867306)
			(xy 12.90565 -84.911938) (xy 12.811696 -84.949224) (xy 12.715076 -84.978927) (xy 12.616402 -85.00086)
			(xy 12.516298 -85.014883) (xy 12.415396 -85.020909) (xy 12.314333 -85.018899) (xy 12.21375 -85.008867)
			(xy 12.114283 -84.990874) (xy 12.016559 -84.965036) (xy 11.921196 -84.931515) (xy 11.828799 -84.890524)
			(xy 11.73995 -84.842321) (xy 11.655212 -84.787212) (xy 11.57512 -84.725544) (xy 11.500181 -84.657708)
			(xy 11.430869 -84.584132) (xy 11.367621 -84.505283) (xy 11.310838 -84.421657) (xy 11.260878 -84.333784)
			(xy 11.218058 -84.24222) (xy 11.182647 -84.147543) (xy 11.154871 -84.050352) (xy 11.134905 -83.951262)
			(xy 11.122874 -83.850898) (xy 11.118856 -83.749896) (xy 0.509016 -83.749896) (xy 0.509016 -87.559896)
			(xy 9.849612 -87.559896) (xy 9.850066 -87.509996) (xy 9.857896 -87.410503) (xy 9.873509 -87.311931)
			(xy 9.896807 -87.214889) (xy 9.927648 -87.119973) (xy 9.96584 -87.02777) (xy 10.011149 -86.938847)
			(xy 10.063296 -86.853754) (xy 10.121957 -86.773014) (xy 10.186773 -86.697126) (xy 10.257344 -86.626557)
			(xy 10.333233 -86.561743) (xy 10.413974 -86.503082) (xy 10.499068 -86.450938) (xy 10.587992 -86.40563)
			(xy 10.680196 -86.36744) (xy 10.775112 -86.336601) (xy 10.872155 -86.313304) (xy 10.970727 -86.297693)
			(xy 11.07022 -86.289865) (xy 11.12012 -86.289388) (xy 11.17137 -86.289896) (xy 11.273537 -86.298164)
			(xy 11.374705 -86.314636) (xy 11.474217 -86.339204) (xy 11.571427 -86.371709) (xy 11.665703 -86.411939)
			(xy 11.756431 -86.459633) (xy 11.843023 -86.514481) (xy 11.924914 -86.576126) (xy 12.001573 -86.644168)
			(xy 12.072502 -86.718164) (xy 12.13724 -86.797634) (xy 12.195365 -86.88206) (xy 12.2465 -86.970895)
			(xy 12.290312 -87.06356) (xy 12.326518 -87.159453) (xy 12.35488 -87.257951) (xy 12.375216 -87.358414)
			(xy 12.387393 -87.460189) (xy 12.389866 -87.511382) (xy 12.390707 -87.520861) (xy 12.398315 -87.538282)
			(xy 12.411745 -87.551735) (xy 12.429153 -87.559373) (xy 12.438634 -87.56015) (xy 12.489829 -87.562618)
			(xy 12.59161 -87.574781) (xy 12.692079 -87.595106) (xy 12.790584 -87.623459) (xy 12.886484 -87.659657)
			(xy 12.979156 -87.703465) (xy 13.067997 -87.754597) (xy 13.152429 -87.812721) (xy 13.231903 -87.877459)
			(xy 13.305903 -87.94839) (xy 13.373947 -88.025052) (xy 13.435592 -88.106949) (xy 13.490439 -88.193546)
			(xy 13.53813 -88.28428) (xy 13.578355 -88.378562) (xy 13.610852 -88.475779) (xy 13.635411 -88.575298)
			(xy 13.651871 -88.676472) (xy 13.660126 -88.778644) (xy 13.660628 -88.829896) (xy 13.660114 -88.879795)
			(xy 13.652285 -88.979284) (xy 13.636673 -89.077853) (xy 13.613377 -89.174893) (xy 13.582538 -89.269806)
			(xy 13.544348 -89.362006) (xy 13.499042 -89.450927) (xy 13.446898 -89.536018) (xy 13.38824 -89.616756)
			(xy 13.349598 -89.662) (xy 268.350492 -89.662) (xy 268.351075 -89.615604) (xy 268.36072 -89.523316)
			(xy 268.379916 -89.432532) (xy 268.408454 -89.344239) (xy 268.426692 -89.301574) (xy 268.430498 -89.291632)
			(xy 268.430498 -89.270368) (xy 268.426692 -89.260426) (xy 268.408447 -89.217764) (xy 268.379903 -89.129471)
			(xy 268.36071 -89.038686) (xy 268.351077 -88.946396) (xy 268.350492 -88.9) (xy 268.351075 -88.853604)
			(xy 268.36072 -88.761316) (xy 268.379916 -88.670532) (xy 268.408454 -88.582239) (xy 268.426692 -88.539574)
			(xy 268.430498 -88.529632) (xy 268.430498 -88.508368) (xy 268.426692 -88.498426) (xy 268.408447 -88.455764)
			(xy 268.379903 -88.367471) (xy 268.36071 -88.276686) (xy 268.351077 -88.184396) (xy 268.350492 -88.138)
			(xy 268.351075 -88.091604) (xy 268.36072 -87.999316) (xy 268.379916 -87.908532) (xy 268.408454 -87.820239)
			(xy 268.426692 -87.777574) (xy 268.430498 -87.767632) (xy 268.430498 -87.746368) (xy 268.426692 -87.736426)
			(xy 268.408447 -87.693764) (xy 268.379903 -87.605471) (xy 268.36071 -87.514686) (xy 268.351077 -87.422396)
			(xy 268.350492 -87.376) (xy 268.351075 -87.329604) (xy 268.36072 -87.237316) (xy 268.379916 -87.146532)
			(xy 268.408454 -87.058239) (xy 268.426692 -87.015574) (xy 268.430498 -87.005632) (xy 268.430498 -86.984368)
			(xy 268.426692 -86.974426) (xy 268.408447 -86.931764) (xy 268.379903 -86.843471) (xy 268.36071 -86.752686)
			(xy 268.351077 -86.660396) (xy 268.350492 -86.614) (xy 268.351075 -86.567604) (xy 268.36072 -86.475316)
			(xy 268.379916 -86.384532) (xy 268.408454 -86.296239) (xy 268.426692 -86.253574) (xy 268.430498 -86.243632)
			(xy 268.430498 -86.222368) (xy 268.426692 -86.212426) (xy 268.408447 -86.169764) (xy 268.379903 -86.081471)
			(xy 268.36071 -85.990686) (xy 268.351077 -85.898396) (xy 268.350492 -85.852) (xy 268.350967 -85.810898)
			(xy 268.358552 -85.729043) (xy 268.373657 -85.648238) (xy 268.396153 -85.569171) (xy 268.425849 -85.492517)
			(xy 268.462491 -85.41893) (xy 268.505766 -85.349038) (xy 268.555306 -85.283437) (xy 268.610687 -85.222687)
			(xy 268.671437 -85.167306) (xy 268.737038 -85.117766) (xy 268.80693 -85.074491) (xy 268.880517 -85.037849)
			(xy 268.957171 -85.008153) (xy 269.036238 -84.985657) (xy 269.117043 -84.970552) (xy 269.198898 -84.962967)
			(xy 269.24 -84.962492) (xy 269.286396 -84.963075) (xy 269.378684 -84.97272) (xy 269.469468 -84.991916)
			(xy 269.557761 -85.020454) (xy 269.600426 -85.038692) (xy 269.610368 -85.042498) (xy 269.631632 -85.042498)
			(xy 269.641574 -85.038692) (xy 269.684236 -85.020447) (xy 269.772529 -84.991903) (xy 269.863314 -84.97271)
			(xy 269.955604 -84.963077) (xy 270.002 -84.962492) (xy 270.048396 -84.963075) (xy 270.140684 -84.97272)
			(xy 270.231468 -84.991916) (xy 270.319761 -85.020454) (xy 270.362426 -85.038692) (xy 270.372368 -85.042498)
			(xy 270.393632 -85.042498) (xy 270.403574 -85.038692) (xy 270.446236 -85.020447) (xy 270.534529 -84.991903)
			(xy 270.625314 -84.97271) (xy 270.717604 -84.963077) (xy 270.764 -84.962492) (xy 270.810396 -84.963075)
			(xy 270.902684 -84.97272) (xy 270.993468 -84.991916) (xy 271.081761 -85.020454) (xy 271.124426 -85.038692)
			(xy 271.134368 -85.042498) (xy 271.155632 -85.042498) (xy 271.165574 -85.038692) (xy 271.208236 -85.020447)
			(xy 271.296529 -84.991903) (xy 271.387314 -84.97271) (xy 271.479604 -84.963077) (xy 271.526 -84.962492)
			(xy 271.572396 -84.963075) (xy 271.664684 -84.97272) (xy 271.755468 -84.991916) (xy 271.843761 -85.020454)
			(xy 271.886426 -85.038692) (xy 271.896368 -85.042498) (xy 271.917632 -85.042498) (xy 271.927574 -85.038692)
			(xy 271.970236 -85.020447) (xy 272.058529 -84.991903) (xy 272.149314 -84.97271) (xy 272.241604 -84.963077)
			(xy 272.288 -84.962492) (xy 272.329102 -84.962967) (xy 272.410957 -84.970552) (xy 272.491762 -84.985657)
			(xy 272.570829 -85.008153) (xy 272.647483 -85.037849) (xy 272.72107 -85.074491) (xy 272.790962 -85.117766)
			(xy 272.856563 -85.167306) (xy 272.917313 -85.222687) (xy 272.972694 -85.283437) (xy 273.022234 -85.349038)
			(xy 273.065509 -85.41893) (xy 273.102151 -85.492517) (xy 273.131847 -85.569171) (xy 273.154343 -85.648238)
			(xy 273.169448 -85.729043) (xy 273.177033 -85.810898) (xy 273.177508 -85.852) (xy 273.176925 -85.898396)
			(xy 273.16728 -85.990684) (xy 273.148084 -86.081468) (xy 273.119546 -86.169761) (xy 273.101308 -86.212426)
			(xy 273.097502 -86.222368) (xy 273.097502 -86.243632) (xy 273.101308 -86.253574) (xy 273.119553 -86.296236)
			(xy 273.148097 -86.384529) (xy 273.16729 -86.475314) (xy 273.176923 -86.567604) (xy 273.177508 -86.614)
			(xy 273.177033 -86.655102) (xy 273.169448 -86.736957) (xy 273.154343 -86.817762) (xy 273.131847 -86.896829)
			(xy 273.102151 -86.973483) (xy 273.065509 -87.04707) (xy 273.022234 -87.116962) (xy 272.972694 -87.182563)
			(xy 272.917313 -87.243313) (xy 272.856563 -87.298694) (xy 272.790962 -87.348234) (xy 272.72107 -87.391509)
			(xy 272.647483 -87.428151) (xy 272.570829 -87.457847) (xy 272.491762 -87.480343) (xy 272.410957 -87.495448)
			(xy 272.329102 -87.503033) (xy 272.288 -87.503508) (xy 272.241604 -87.502925) (xy 272.149316 -87.49328)
			(xy 272.058532 -87.474084) (xy 271.970239 -87.445546) (xy 271.927574 -87.427308) (xy 271.917632 -87.423502)
			(xy 271.896368 -87.423502) (xy 271.886426 -87.427308) (xy 271.853507 -87.441537) (xy 271.785822 -87.465257)
			(xy 271.716442 -87.483437) (xy 271.681194 -87.490046) (xy 271.67107 -87.492344) (xy 271.653749 -87.503749)
			(xy 271.642344 -87.52107) (xy 271.640046 -87.531194) (xy 271.633416 -87.566437) (xy 271.61522 -87.63581)
			(xy 271.591513 -87.703498) (xy 271.577308 -87.736426) (xy 271.573502 -87.746368) (xy 271.573502 -87.767632)
			(xy 271.577308 -87.777574) (xy 271.591537 -87.810493) (xy 271.615257 -87.878178) (xy 271.633437 -87.947558)
			(xy 271.640046 -87.982806) (xy 271.642344 -87.99293) (xy 271.653749 -88.010251) (xy 271.67107 -88.021656)
			(xy 271.681194 -88.023954) (xy 271.716437 -88.030584) (xy 271.78581 -88.04878) (xy 271.853498 -88.072487)
			(xy 271.886426 -88.086692) (xy 271.896368 -88.090498) (xy 271.917632 -88.090498) (xy 271.927574 -88.086692)
			(xy 271.970236 -88.068447) (xy 272.058529 -88.039903) (xy 272.149314 -88.02071) (xy 272.241604 -88.011077)
			(xy 272.288 -88.010492) (xy 272.329102 -88.010967) (xy 272.410957 -88.018552) (xy 272.491762 -88.033657)
			(xy 272.570829 -88.056153) (xy 272.647483 -88.085849) (xy 272.72107 -88.122491) (xy 272.790962 -88.165766)
			(xy 272.856563 -88.215306) (xy 272.917313 -88.270687) (xy 272.972694 -88.331437) (xy 273.022234 -88.397038)
			(xy 273.065509 -88.46693) (xy 273.102151 -88.540517) (xy 273.131847 -88.617171) (xy 273.154343 -88.696238)
			(xy 273.169448 -88.777043) (xy 273.177033 -88.858898) (xy 273.177508 -88.9) (xy 273.176925 -88.946396)
			(xy 273.16728 -89.038684) (xy 273.148084 -89.129468) (xy 273.119546 -89.217761) (xy 273.101308 -89.260426)
			(xy 273.097502 -89.270368) (xy 273.097502 -89.291632) (xy 273.101308 -89.301574) (xy 273.119553 -89.344236)
			(xy 273.148097 -89.432529) (xy 273.16729 -89.523314) (xy 273.176923 -89.615604) (xy 273.177508 -89.662)
			(xy 273.177033 -89.703102) (xy 273.169448 -89.784957) (xy 273.154343 -89.865762) (xy 273.131847 -89.944829)
			(xy 273.102151 -90.021483) (xy 273.065509 -90.09507) (xy 273.022234 -90.164962) (xy 272.972694 -90.230563)
			(xy 272.917313 -90.291313) (xy 272.856563 -90.346694) (xy 272.790962 -90.396234) (xy 272.72107 -90.439509)
			(xy 272.667144 -90.466361) (xy 275.081742 -90.466361) (xy 275.081742 -90.381639) (xy 275.089795 -90.297302)
			(xy 275.105829 -90.214112) (xy 275.129697 -90.132822) (xy 275.161185 -90.05417) (xy 275.200007 -89.978867)
			(xy 275.24581 -89.907595) (xy 275.298181 -89.840999) (xy 275.356646 -89.779684) (xy 275.420674 -89.724203)
			(xy 275.489686 -89.67506) (xy 275.563056 -89.6327) (xy 275.640121 -89.597505) (xy 275.720183 -89.569796)
			(xy 275.802516 -89.549822) (xy 275.886375 -89.537765) (xy 275.971 -89.533734) (xy 276.055625 -89.537765)
			(xy 276.139484 -89.549822) (xy 276.221817 -89.569796) (xy 276.301879 -89.597505) (xy 276.378944 -89.6327)
			(xy 276.452314 -89.67506) (xy 276.521326 -89.724203) (xy 276.585354 -89.779684) (xy 276.643819 -89.840999)
			(xy 276.69619 -89.907595) (xy 276.741993 -89.978867) (xy 276.780815 -90.05417) (xy 276.812303 -90.132822)
			(xy 276.836171 -90.214112) (xy 276.852205 -90.297302) (xy 276.860258 -90.381639) (xy 276.860762 -90.424)
			(xy 276.860258 -90.466361) (xy 276.852205 -90.550698) (xy 276.836171 -90.633888) (xy 276.812303 -90.715178)
			(xy 276.780815 -90.79383) (xy 276.741993 -90.869133) (xy 276.69619 -90.940405) (xy 276.643819 -91.007001)
			(xy 276.585354 -91.068316) (xy 276.521326 -91.123797) (xy 276.452314 -91.17294) (xy 276.378944 -91.2153)
			(xy 276.301879 -91.250495) (xy 276.221817 -91.278204) (xy 276.139484 -91.298178) (xy 276.055625 -91.310235)
			(xy 275.971 -91.314267) (xy 275.886375 -91.310235) (xy 275.802516 -91.298178) (xy 275.720183 -91.278204)
			(xy 275.640121 -91.250495) (xy 275.563056 -91.2153) (xy 275.489686 -91.17294) (xy 275.420674 -91.123797)
			(xy 275.356646 -91.068316) (xy 275.298181 -91.007001) (xy 275.24581 -90.940405) (xy 275.200007 -90.869133)
			(xy 275.161185 -90.79383) (xy 275.129697 -90.715178) (xy 275.105829 -90.633888) (xy 275.089795 -90.550698)
			(xy 275.081742 -90.466361) (xy 272.667144 -90.466361) (xy 272.647483 -90.476151) (xy 272.570829 -90.505847)
			(xy 272.491762 -90.528343) (xy 272.410957 -90.543448) (xy 272.329102 -90.551033) (xy 272.288 -90.551508)
			(xy 272.241604 -90.550925) (xy 272.149316 -90.54128) (xy 272.058532 -90.522084) (xy 271.970239 -90.493546)
			(xy 271.927574 -90.475308) (xy 271.917632 -90.471502) (xy 271.896368 -90.471502) (xy 271.886426 -90.475308)
			(xy 271.843764 -90.493553) (xy 271.755471 -90.522097) (xy 271.664686 -90.54129) (xy 271.572396 -90.550923)
			(xy 271.526 -90.551508) (xy 271.479604 -90.550925) (xy 271.387316 -90.54128) (xy 271.296532 -90.522084)
			(xy 271.208239 -90.493546) (xy 271.165574 -90.475308) (xy 271.155632 -90.471502) (xy 271.134368 -90.471502)
			(xy 271.124426 -90.475308) (xy 271.081764 -90.493553) (xy 270.993471 -90.522097) (xy 270.902686 -90.54129)
			(xy 270.810396 -90.550923) (xy 270.764 -90.551508) (xy 270.717604 -90.550925) (xy 270.625316 -90.54128)
			(xy 270.534532 -90.522084) (xy 270.446239 -90.493546) (xy 270.403574 -90.475308) (xy 270.393632 -90.471502)
			(xy 270.372368 -90.471502) (xy 270.362426 -90.475308) (xy 270.340242 -90.484956) (xy 270.295004 -90.502108)
			(xy 270.272002 -90.509598) (xy 270.258794 -90.513916) (xy 270.24076 -90.533982) (xy 270.21663 -90.64752)
			(xy 270.225266 -90.673428) (xy 270.23568 -90.682572) (xy 270.266746 -90.710632) (xy 270.323976 -90.771738)
			(xy 270.375209 -90.837953) (xy 270.419991 -90.90869) (xy 270.457926 -90.983323) (xy 270.488678 -91.061192)
			(xy 270.511974 -91.141606) (xy 270.527609 -91.223854) (xy 270.535444 -91.307207) (xy 270.535908 -91.349068)
			(xy 270.535404 -91.391416) (xy 270.527353 -91.47573) (xy 270.511324 -91.558896) (xy 270.487463 -91.640163)
			(xy 270.455984 -91.718793) (xy 270.417173 -91.794074) (xy 270.371383 -91.865326) (xy 270.319027 -91.931902)
			(xy 270.260579 -91.9932) (xy 270.196569 -92.048665) (xy 270.127577 -92.097794) (xy 270.054227 -92.140143)
			(xy 269.977184 -92.175327) (xy 269.897145 -92.203029) (xy 269.814836 -92.222997) (xy 269.731001 -92.23505)
			(xy 269.6464 -92.239081) (xy 269.561799 -92.23505) (xy 269.477964 -92.222997) (xy 269.395655 -92.203029)
			(xy 269.315616 -92.175327) (xy 269.238573 -92.140143) (xy 269.165223 -92.097794) (xy 269.096231 -92.048665)
			(xy 269.032221 -91.9932) (xy 268.973773 -91.931902) (xy 268.921417 -91.865326) (xy 268.875627 -91.794074)
			(xy 268.836816 -91.718793) (xy 268.805337 -91.640163) (xy 268.781476 -91.558896) (xy 268.765447 -91.47573)
			(xy 268.757396 -91.391416) (xy 268.756892 -91.349068) (xy 268.757344 -91.308052) (xy 268.764906 -91.226369)
			(xy 268.779953 -91.145729) (xy 268.802357 -91.066816) (xy 268.831929 -90.990299) (xy 268.868417 -90.916829)
			(xy 268.911512 -90.847029) (xy 268.960847 -90.781491) (xy 269.016005 -90.720771) (xy 269.045944 -90.692732)
			(xy 269.056104 -90.683334) (xy 269.064232 -90.656918) (xy 269.0368 -90.54338) (xy 269.01775 -90.523568)
			(xy 269.004288 -90.519758) (xy 268.964497 -90.508355) (xy 268.88706 -90.47909) (xy 268.812678 -90.442758)
			(xy 268.741992 -90.399673) (xy 268.675615 -90.350208) (xy 268.61412 -90.29479) (xy 268.55804 -90.233898)
			(xy 268.507859 -90.16806) (xy 268.464012 -90.097845) (xy 268.426877 -90.02386) (xy 268.396777 -89.946745)
			(xy 268.373971 -89.867167) (xy 268.358656 -89.785814) (xy 268.350965 -89.703391) (xy 268.350492 -89.662)
			(xy 13.349598 -89.662) (xy 13.323427 -89.692643) (xy 13.252861 -89.763211) (xy 13.176975 -89.828025)
			(xy 13.096238 -89.886685) (xy 13.011148 -89.93883) (xy 12.922228 -89.984138) (xy 12.830028 -90.02233)
			(xy 12.735116 -90.05317) (xy 12.638076 -90.076469) (xy 12.539508 -90.092082) (xy 12.440019 -90.099913)
			(xy 12.39012 -90.100404) (xy 12.33887 -90.099894) (xy 12.236704 -90.091626) (xy 12.135535 -90.075154)
			(xy 12.036023 -90.050586) (xy 11.938813 -90.018081) (xy 11.844537 -89.977851) (xy 11.753809 -89.930157)
			(xy 11.667218 -89.875309) (xy 11.585327 -89.813664) (xy 11.508667 -89.745623) (xy 11.437738 -89.671626)
			(xy 11.373001 -89.592157) (xy 11.314876 -89.507731) (xy 11.263741 -89.418896) (xy 11.219928 -89.326232)
			(xy 11.183723 -89.230338) (xy 11.15536 -89.13184) (xy 11.135024 -89.031377) (xy 11.122847 -88.929603)
			(xy 11.120374 -88.87841) (xy 11.119594 -88.868921) (xy 11.111973 -88.851491) (xy 11.098523 -88.838037)
			(xy 11.081095 -88.830409) (xy 11.071606 -88.829642) (xy 11.020411 -88.827172) (xy 10.918631 -88.815009)
			(xy 10.818161 -88.794684) (xy 10.719656 -88.766331) (xy 10.623756 -88.730133) (xy 10.531084 -88.686326)
			(xy 10.442244 -88.635194) (xy 10.357812 -88.57707) (xy 10.278337 -88.512332) (xy 10.204338 -88.441401)
			(xy 10.136294 -88.364738) (xy 10.074648 -88.282842) (xy 10.019802 -88.196246) (xy 9.972111 -88.105511)
			(xy 9.931886 -88.011229) (xy 9.899388 -87.914013) (xy 9.87483 -87.814494) (xy 9.858369 -87.71332)
			(xy 9.850114 -87.611148) (xy 9.849612 -87.559896) (xy 0.509016 -87.559896) (xy 0.509016 -93.399864)
			(xy 3.446023 -93.399864) (xy 3.450044 -93.286002) (xy 3.462086 -93.172708) (xy 3.482091 -93.060546)
			(xy 3.509957 -92.950074) (xy 3.545546 -92.841842) (xy 3.588681 -92.736391) (xy 3.639147 -92.634245)
			(xy 3.696693 -92.535914) (xy 3.761032 -92.441886) (xy 3.831843 -92.352631) (xy 3.908773 -92.268594)
			(xy 3.99144 -92.190192) (xy 4.079431 -92.117817) (xy 4.172308 -92.051829) (xy 4.269609 -91.992557)
			(xy 4.370848 -91.940296) (xy 4.475522 -91.895306) (xy 4.583108 -91.857812) (xy 4.693071 -91.828001)
			(xy 4.804864 -91.80602) (xy 4.917928 -91.79198) (xy 5.0317 -91.78595) (xy 5.145615 -91.787961) (xy 5.259104 -91.798002)
			(xy 5.371603 -91.816024) (xy 5.482549 -91.841936) (xy 5.591392 -91.87561) (xy 5.697588 -91.916877)
			(xy 5.800608 -91.965533) (xy 5.89994 -92.021334) (xy 5.995089 -92.084003) (xy 6.085579 -92.153228)
			(xy 6.170961 -92.228663) (xy 6.25081 -92.309934) (xy 6.324727 -92.396634) (xy 6.392343 -92.488332)
			(xy 6.453324 -92.584571) (xy 6.507363 -92.684873) (xy 6.554193 -92.788736) (xy 6.582153 -92.864629)
			(xy 270.30832 -92.864629) (xy 270.30832 -92.779907) (xy 270.316373 -92.69557) (xy 270.332407 -92.61238)
			(xy 270.356275 -92.53109) (xy 270.387763 -92.452438) (xy 270.426585 -92.377135) (xy 270.472388 -92.305863)
			(xy 270.524759 -92.239267) (xy 270.583224 -92.177952) (xy 270.647252 -92.122471) (xy 270.716264 -92.073328)
			(xy 270.789634 -92.030968) (xy 270.866699 -91.995773) (xy 270.946761 -91.968064) (xy 271.029094 -91.94809)
			(xy 271.112953 -91.936033) (xy 271.197578 -91.932002) (xy 271.282203 -91.936033) (xy 271.366062 -91.94809)
			(xy 271.448395 -91.968064) (xy 271.528457 -91.995773) (xy 271.605522 -92.030968) (xy 271.678892 -92.073328)
			(xy 271.747904 -92.122471) (xy 271.811932 -92.177952) (xy 271.870397 -92.239267) (xy 271.922768 -92.305863)
			(xy 271.968571 -92.377135) (xy 272.007393 -92.452438) (xy 272.038881 -92.53109) (xy 272.062749 -92.61238)
			(xy 272.078783 -92.69557) (xy 272.086836 -92.779907) (xy 272.08734 -92.822268) (xy 272.086836 -92.864629)
			(xy 272.078783 -92.948966) (xy 272.062749 -93.032156) (xy 272.038881 -93.113446) (xy 272.007393 -93.192098)
			(xy 271.968571 -93.267401) (xy 271.922768 -93.338673) (xy 271.870397 -93.405269) (xy 271.811932 -93.466584)
			(xy 271.747904 -93.522065) (xy 271.678892 -93.571208) (xy 271.605522 -93.613568) (xy 271.528457 -93.648763)
			(xy 271.448395 -93.676472) (xy 271.366062 -93.696446) (xy 271.282203 -93.708503) (xy 271.197578 -93.712535)
			(xy 271.112953 -93.708503) (xy 271.029094 -93.696446) (xy 270.946761 -93.676472) (xy 270.866699 -93.648763)
			(xy 270.789634 -93.613568) (xy 270.716264 -93.571208) (xy 270.647252 -93.522065) (xy 270.583224 -93.466584)
			(xy 270.524759 -93.405269) (xy 270.472388 -93.338673) (xy 270.426585 -93.267401) (xy 270.387763 -93.192098)
			(xy 270.356275 -93.113446) (xy 270.332407 -93.032156) (xy 270.316373 -92.948966) (xy 270.30832 -92.864629)
			(xy 6.582153 -92.864629) (xy 6.59358 -92.895644) (xy 6.625327 -93.005064) (xy 6.649277 -93.11645)
			(xy 6.665311 -93.229249) (xy 6.673347 -93.342898) (xy 6.67385 -93.399864) (xy 6.673347 -93.45683)
			(xy 6.665311 -93.570479) (xy 6.649277 -93.683278) (xy 6.625327 -93.794664) (xy 6.59358 -93.904084)
			(xy 6.554193 -94.010992) (xy 6.507363 -94.114855) (xy 6.453324 -94.215157) (xy 6.392343 -94.311396)
			(xy 6.324727 -94.403094) (xy 6.25081 -94.489794) (xy 6.170961 -94.571065) (xy 6.085579 -94.6465)
			(xy 5.995089 -94.715725) (xy 5.89994 -94.778394) (xy 5.800608 -94.834195) (xy 5.697588 -94.882851)
			(xy 5.591392 -94.924118) (xy 5.550527 -94.936761) (xy 273.536914 -94.936761) (xy 273.536914 -94.852039)
			(xy 273.544967 -94.767702) (xy 273.561001 -94.684512) (xy 273.584869 -94.603222) (xy 273.616357 -94.52457)
			(xy 273.655179 -94.449267) (xy 273.700982 -94.377995) (xy 273.753353 -94.311399) (xy 273.811818 -94.250084)
			(xy 273.875846 -94.194603) (xy 273.944858 -94.14546) (xy 274.018228 -94.1031) (xy 274.095293 -94.067905)
			(xy 274.175355 -94.040196) (xy 274.257688 -94.020222) (xy 274.341547 -94.008165) (xy 274.426172 -94.004134)
			(xy 274.510797 -94.008165) (xy 274.594656 -94.020222) (xy 274.676989 -94.040196) (xy 274.757051 -94.067905)
			(xy 274.834116 -94.1031) (xy 274.907486 -94.14546) (xy 274.976498 -94.194603) (xy 275.040526 -94.250084)
			(xy 275.098991 -94.311399) (xy 275.151362 -94.377995) (xy 275.197165 -94.449267) (xy 275.235987 -94.52457)
			(xy 275.267475 -94.603222) (xy 275.291343 -94.684512) (xy 275.307377 -94.767702) (xy 275.31543 -94.852039)
			(xy 275.315934 -94.8944) (xy 275.31543 -94.936761) (xy 275.307377 -95.021098) (xy 275.291343 -95.104288)
			(xy 275.267475 -95.185578) (xy 275.235987 -95.26423) (xy 275.197165 -95.339533) (xy 275.151362 -95.410805)
			(xy 275.098991 -95.477401) (xy 275.040526 -95.538716) (xy 274.976498 -95.594197) (xy 274.907486 -95.64334)
			(xy 274.834116 -95.6857) (xy 274.757051 -95.720895) (xy 274.676989 -95.748604) (xy 274.594656 -95.768578)
			(xy 274.510797 -95.780635) (xy 274.426172 -95.784667) (xy 274.341547 -95.780635) (xy 274.257688 -95.768578)
			(xy 274.175355 -95.748604) (xy 274.095293 -95.720895) (xy 274.018228 -95.6857) (xy 273.944858 -95.64334)
			(xy 273.875846 -95.594197) (xy 273.811818 -95.538716) (xy 273.753353 -95.477401) (xy 273.700982 -95.410805)
			(xy 273.655179 -95.339533) (xy 273.616357 -95.26423) (xy 273.584869 -95.185578) (xy 273.561001 -95.104288)
			(xy 273.544967 -95.021098) (xy 273.536914 -94.936761) (xy 5.550527 -94.936761) (xy 5.482549 -94.957792)
			(xy 5.371603 -94.983704) (xy 5.259104 -95.001726) (xy 5.145615 -95.011767) (xy 5.0317 -95.013778)
			(xy 4.917928 -95.007748) (xy 4.804864 -94.993708) (xy 4.693071 -94.971727) (xy 4.583108 -94.941916)
			(xy 4.475522 -94.904422) (xy 4.370848 -94.859432) (xy 4.269609 -94.807171) (xy 4.172308 -94.747899)
			(xy 4.079431 -94.681911) (xy 3.99144 -94.609536) (xy 3.908773 -94.531134) (xy 3.831843 -94.447097)
			(xy 3.761032 -94.357842) (xy 3.696693 -94.263814) (xy 3.639147 -94.165483) (xy 3.588681 -94.063337)
			(xy 3.545546 -93.957886) (xy 3.509957 -93.849654) (xy 3.482091 -93.739182) (xy 3.462086 -93.62702)
			(xy 3.450044 -93.513726) (xy 3.446023 -93.399864) (xy 0.509016 -93.399864) (xy 0.509016 -98.013)
			(xy 214.347099 -98.013) (xy 214.351129 -97.928402) (xy 214.363182 -97.844571) (xy 214.383149 -97.762265)
			(xy 214.410848 -97.682229) (xy 214.44603 -97.605189) (xy 214.488376 -97.531842) (xy 214.537502 -97.462852)
			(xy 214.592963 -97.398843) (xy 214.654257 -97.340397) (xy 214.720829 -97.288041) (xy 214.792077 -97.24225)
			(xy 214.867354 -97.203439) (xy 214.94598 -97.171959) (xy 215.027241 -97.148095) (xy 215.110404 -97.132064)
			(xy 215.194713 -97.124009) (xy 215.23706 -97.123504) (xy 215.283455 -97.1241) (xy 215.375743 -97.133741)
			(xy 215.466527 -97.152933) (xy 215.554821 -97.181468) (xy 215.597486 -97.199704) (xy 215.607428 -97.20351)
			(xy 215.628692 -97.20351) (xy 215.638634 -97.199704) (xy 215.681302 -97.181473) (xy 215.769592 -97.152925)
			(xy 215.860375 -97.133728) (xy 215.952664 -97.124091) (xy 215.99906 -97.123504) (xy 216.041067 -97.12399)
			(xy 216.124708 -97.131906) (xy 216.207231 -97.14767) (xy 216.2879 -97.171143) (xy 216.365997 -97.202116)
			(xy 216.440827 -97.240312) (xy 216.511723 -97.285392) (xy 216.578055 -97.336953) (xy 216.639231 -97.394538)
			(xy 216.667334 -97.425764) (xy 216.6747 -97.434146) (xy 216.694512 -97.443036) (xy 216.79281 -97.443036)
			(xy 216.812622 -97.434146) (xy 216.819988 -97.425764) (xy 216.848079 -97.394524) (xy 216.909243 -97.33692)
			(xy 216.975568 -97.285342) (xy 217.046463 -97.240252) (xy 217.121295 -97.202051) (xy 217.199398 -97.171081)
			(xy 217.280074 -97.147616) (xy 217.362604 -97.131868) (xy 217.446252 -97.123975) (xy 217.488262 -97.123504)
			(xy 217.534657 -97.124099) (xy 217.626945 -97.133741) (xy 217.717729 -97.152933) (xy 217.806023 -97.181468)
			(xy 217.848688 -97.199704) (xy 217.85863 -97.20351) (xy 217.879894 -97.20351) (xy 217.889836 -97.199704)
			(xy 217.932504 -97.181473) (xy 218.020794 -97.152925) (xy 218.111577 -97.133728) (xy 218.203866 -97.124091)
			(xy 218.250262 -97.123504) (xy 218.291199 -97.124004) (xy 218.372725 -97.13153) (xy 218.453216 -97.146514)
			(xy 218.531989 -97.168828) (xy 218.60838 -97.198285) (xy 218.681742 -97.234633) (xy 218.751455 -97.277567)
			(xy 218.81693 -97.326724) (xy 218.877611 -97.381687) (xy 218.932988 -97.441992) (xy 218.95816 -97.474278)
			(xy 218.965526 -97.48393) (xy 218.987116 -97.494344) (xy 219.093542 -97.492566) (xy 219.114878 -97.48139)
			(xy 219.12199 -97.471484) (xy 219.146898 -97.437102) (xy 219.202355 -97.372809) (xy 219.263686 -97.314092)
			(xy 219.330332 -97.261485) (xy 219.401687 -97.215468) (xy 219.477102 -97.176458) (xy 219.55589 -97.144811)
			(xy 219.637335 -97.120815) (xy 219.720696 -97.104688) (xy 219.805215 -97.096576) (xy 219.847668 -97.096072)
			(xy 219.894071 -97.096675) (xy 219.986369 -97.106372) (xy 220.077154 -97.125633) (xy 220.165439 -97.154247)
			(xy 220.208094 -97.172526) (xy 220.218036 -97.176332) (xy 220.2393 -97.176332) (xy 220.249242 -97.172526)
			(xy 220.291907 -97.154274) (xy 220.380194 -97.125678) (xy 220.470975 -97.106418) (xy 220.563267 -97.096703)
			(xy 220.609668 -97.096072) (xy 220.651684 -97.096525) (xy 220.73534 -97.104457) (xy 220.817875 -97.120244)
			(xy 220.898554 -97.143744) (xy 220.976656 -97.174749) (xy 221.051486 -97.212982) (xy 221.122376 -97.258102)
			(xy 221.188695 -97.309707) (xy 221.249851 -97.367337) (xy 221.277942 -97.398586) (xy 221.285308 -97.406968)
			(xy 221.30512 -97.415858) (xy 221.403418 -97.415858) (xy 221.42323 -97.406968) (xy 221.430596 -97.398586)
			(xy 221.458694 -97.367348) (xy 221.519864 -97.309741) (xy 221.586191 -97.258156) (xy 221.657084 -97.213051)
			(xy 221.731912 -97.174827) (xy 221.81001 -97.143825) (xy 221.890681 -97.120321) (xy 221.973209 -97.104524)
			(xy 222.056857 -97.096575) (xy 222.09887 -97.096072) (xy 222.145273 -97.096675) (xy 222.237571 -97.106372)
			(xy 222.328356 -97.125632) (xy 222.416641 -97.154247) (xy 222.459296 -97.172526) (xy 222.469238 -97.176332)
			(xy 222.490502 -97.176332) (xy 222.500444 -97.172526) (xy 222.543109 -97.154273) (xy 222.631395 -97.125678)
			(xy 222.722177 -97.106418) (xy 222.814469 -97.096703) (xy 222.86087 -97.096072) (xy 222.903898 -97.096585)
			(xy 222.989549 -97.104908) (xy 223.073998 -97.12146) (xy 223.156454 -97.146086) (xy 223.236148 -97.178557)
			(xy 223.312336 -97.218569) (xy 223.384305 -97.265748) (xy 223.451385 -97.319654) (xy 223.512948 -97.379783)
			(xy 223.568419 -97.445574) (xy 223.61728 -97.516413) (xy 223.638618 -97.55378) (xy 223.643347 -97.561498)
			(xy 223.657067 -97.573284) (xy 223.674025 -97.579573) (xy 223.683068 -97.579942) (xy 223.771714 -97.579942)
			(xy 223.78076 -97.579567) (xy 223.797731 -97.573298) (xy 223.811459 -97.561515) (xy 223.816164 -97.55378)
			(xy 223.837459 -97.516385) (xy 223.88631 -97.445532) (xy 223.941777 -97.379729) (xy 224.003339 -97.319589)
			(xy 224.070421 -97.265677) (xy 224.142397 -97.218495) (xy 224.218592 -97.178485) (xy 224.298296 -97.146021)
			(xy 224.380763 -97.121407) (xy 224.465221 -97.104872) (xy 224.550881 -97.096571) (xy 224.593912 -97.096072)
			(xy 224.640314 -97.096695) (xy 224.732612 -97.106386) (xy 224.823397 -97.125641) (xy 224.911682 -97.15425)
			(xy 224.954338 -97.172526) (xy 224.96428 -97.176332) (xy 224.985544 -97.176332) (xy 224.995486 -97.172526)
			(xy 225.038145 -97.154259) (xy 225.126434 -97.125668) (xy 225.217217 -97.106412) (xy 225.309511 -97.0967)
			(xy 225.355912 -97.096072) (xy 225.397927 -97.096565) (xy 225.481582 -97.104491) (xy 225.564116 -97.120273)
			(xy 225.644794 -97.143768) (xy 225.722896 -97.174768) (xy 225.797726 -97.212997) (xy 225.868618 -97.258112)
			(xy 225.934937 -97.309713) (xy 225.996095 -97.367339) (xy 226.024186 -97.398586) (xy 226.031552 -97.406968)
			(xy 226.051364 -97.415858) (xy 226.149662 -97.415858) (xy 226.169474 -97.406968) (xy 226.17684 -97.398586)
			(xy 226.204915 -97.367326) (xy 226.266088 -97.309721) (xy 226.332418 -97.258137) (xy 226.403314 -97.213033)
			(xy 226.478146 -97.174812) (xy 226.556246 -97.143813) (xy 226.63692 -97.120312) (xy 226.71945 -97.104518)
			(xy 226.8031 -97.096573) (xy 226.845114 -97.096072) (xy 226.891516 -97.096694) (xy 226.983814 -97.106386)
			(xy 227.074599 -97.125641) (xy 227.162884 -97.15425) (xy 227.20554 -97.172526) (xy 227.215482 -97.176332)
			(xy 227.236746 -97.176332) (xy 227.246688 -97.172526) (xy 227.289347 -97.154259) (xy 227.377636 -97.125667)
			(xy 227.468419 -97.106411) (xy 227.560713 -97.0967) (xy 227.607114 -97.096072) (xy 227.649476 -97.096509)
			(xy 227.733816 -97.104563) (xy 227.817008 -97.120598) (xy 227.898299 -97.144469) (xy 227.976953 -97.175958)
			(xy 228.052258 -97.214782) (xy 228.123532 -97.260588) (xy 228.190129 -97.312961) (xy 228.251445 -97.371427)
			(xy 228.306927 -97.435457) (xy 228.356071 -97.504471) (xy 228.398433 -97.577844) (xy 228.433628 -97.654912)
			(xy 228.461338 -97.734976) (xy 228.481312 -97.817311) (xy 228.493369 -97.901172) (xy 228.497401 -97.9858)
			(xy 228.496115 -98.0128) (xy 228.639776 -98.0128) (xy 228.643808 -97.928166) (xy 228.655866 -97.844299)
			(xy 228.675843 -97.761958) (xy 228.703556 -97.681889) (xy 228.738755 -97.604817) (xy 228.781121 -97.53144)
			(xy 228.830271 -97.462422) (xy 228.885758 -97.398389) (xy 228.947082 -97.339921) (xy 229.013685 -97.287547)
			(xy 229.084966 -97.241741) (xy 229.160278 -97.202918) (xy 229.238939 -97.171431) (xy 229.320238 -97.147563)
			(xy 229.403437 -97.131532) (xy 229.487783 -97.123482) (xy 229.530148 -97.122996) (xy 229.576551 -97.123604)
			(xy 229.668849 -97.133299) (xy 229.759634 -97.152558) (xy 229.847919 -97.181172) (xy 229.890574 -97.19945)
			(xy 229.900516 -97.203256) (xy 229.92178 -97.203256) (xy 229.931722 -97.19945) (xy 229.974377 -97.181173)
			(xy 230.062667 -97.152584) (xy 230.153452 -97.13333) (xy 230.245746 -97.123623) (xy 230.292148 -97.122996)
			(xy 230.334163 -97.123489) (xy 230.417817 -97.131418) (xy 230.50035 -97.147202) (xy 230.581028 -97.170698)
			(xy 230.659129 -97.201699) (xy 230.733959 -97.239927) (xy 230.80485 -97.285041) (xy 230.871171 -97.336641)
			(xy 230.93233 -97.394264) (xy 230.960422 -97.42551) (xy 230.967788 -97.433892) (xy 230.9876 -97.442782)
			(xy 231.085898 -97.442782) (xy 231.10571 -97.433892) (xy 231.113076 -97.42551) (xy 231.14119 -97.394286)
			(xy 231.202357 -97.336679) (xy 231.268682 -97.285092) (xy 231.339573 -97.239985) (xy 231.414399 -97.201759)
			(xy 231.492495 -97.170756) (xy 231.573164 -97.14725) (xy 231.65569 -97.131451) (xy 231.739338 -97.123499)
			(xy 231.78135 -97.122996) (xy 231.827753 -97.123604) (xy 231.920051 -97.133299) (xy 232.010836 -97.152558)
			(xy 232.099121 -97.181171) (xy 232.141776 -97.19945) (xy 232.151718 -97.203256) (xy 232.172982 -97.203256)
			(xy 232.182924 -97.19945) (xy 232.225592 -97.181205) (xy 232.313877 -97.152607) (xy 232.404658 -97.133345)
			(xy 232.49695 -97.123628) (xy 232.54335 -97.122996) (xy 232.586931 -97.123531) (xy 232.673673 -97.132067)
			(xy 232.759165 -97.149043) (xy 232.842588 -97.174296) (xy 232.923142 -97.207584) (xy 233.000056 -97.248588)
			(xy 233.072592 -97.296916) (xy 233.140056 -97.352103) (xy 233.201801 -97.413622) (xy 233.257236 -97.480883)
			(xy 233.30583 -97.553242) (xy 233.32694 -97.591372) (xy 233.333798 -97.604072) (xy 233.357928 -97.618296)
			(xy 233.477054 -97.616518) (xy 233.50093 -97.601532) (xy 233.50728 -97.588578) (xy 233.526 -97.552008)
			(xy 233.569301 -97.482183) (xy 233.618856 -97.416648) (xy 233.674243 -97.355962) (xy 233.734989 -97.300641)
			(xy 233.800577 -97.251157) (xy 233.870449 -97.207932) (xy 233.944009 -97.171333) (xy 234.02063 -97.141673)
			(xy 234.099659 -97.119205) (xy 234.180424 -97.104119) (xy 234.262235 -97.096545) (xy 234.303316 -97.096072)
			(xy 234.349718 -97.096694) (xy 234.442016 -97.106385) (xy 234.532801 -97.12564) (xy 234.621086 -97.15425)
			(xy 234.663742 -97.172526) (xy 234.673684 -97.176332) (xy 234.694948 -97.176332) (xy 234.70489 -97.172526)
			(xy 234.747548 -97.154258) (xy 234.835837 -97.125667) (xy 234.926621 -97.106411) (xy 235.018915 -97.0967)
			(xy 235.065316 -97.096072) (xy 235.107331 -97.096562) (xy 235.190986 -97.104489) (xy 235.27352 -97.120271)
			(xy 235.354198 -97.143767) (xy 235.4323 -97.174767) (xy 235.507131 -97.212996) (xy 235.578022 -97.258112)
			(xy 235.644341 -97.309713) (xy 235.705499 -97.367339) (xy 235.73359 -97.398586) (xy 235.740956 -97.406968)
			(xy 235.760768 -97.415858) (xy 235.859066 -97.415858) (xy 235.878878 -97.406968) (xy 235.886244 -97.398586)
			(xy 235.914369 -97.367373) (xy 235.975536 -97.309766) (xy 236.041859 -97.258179) (xy 236.112748 -97.213071)
			(xy 236.187573 -97.174845) (xy 236.265667 -97.14384) (xy 236.346335 -97.120332) (xy 236.42886 -97.104531)
			(xy 236.512506 -97.096577) (xy 236.554518 -97.096072) (xy 236.60092 -97.096693) (xy 236.693218 -97.106385)
			(xy 236.784003 -97.12564) (xy 236.872288 -97.154249) (xy 236.914944 -97.172526) (xy 236.924886 -97.176332)
			(xy 236.94615 -97.176332) (xy 236.956092 -97.172526) (xy 236.99875 -97.154257) (xy 237.087039 -97.125666)
			(xy 237.177823 -97.106411) (xy 237.270117 -97.0967) (xy 237.316518 -97.096072) (xy 237.357615 -97.096505)
			(xy 237.439458 -97.104088) (xy 237.520253 -97.119186) (xy 237.599312 -97.141671) (xy 237.675959 -97.171353)
			(xy 237.749543 -97.207976) (xy 237.819435 -97.251231) (xy 237.88504 -97.300747) (xy 237.945798 -97.356102)
			(xy 238.001192 -97.416825) (xy 238.05075 -97.482399) (xy 238.094048 -97.552263) (xy 238.112808 -97.588832)
			(xy 238.119158 -97.601786) (xy 238.143034 -97.616772) (xy 238.261906 -97.61855) (xy 238.28629 -97.604326)
			(xy 238.293148 -97.591626) (xy 238.314222 -97.553465) (xy 238.362786 -97.481062) (xy 238.4182 -97.413758)
			(xy 238.479934 -97.352199) (xy 238.547395 -97.296976) (xy 238.619936 -97.248619) (xy 238.69686 -97.207592)
			(xy 238.77743 -97.174288) (xy 238.860871 -97.149028) (xy 238.946384 -97.132052) (xy 239.033147 -97.123526)
			(xy 239.076738 -97.122996) (xy 239.123141 -97.123608) (xy 239.215438 -97.133302) (xy 239.306224 -97.15256)
			(xy 239.394509 -97.181172) (xy 239.437164 -97.19945) (xy 239.447106 -97.203256) (xy 239.46837 -97.203256)
			(xy 239.478312 -97.19945) (xy 239.520968 -97.181176) (xy 239.609258 -97.152586) (xy 239.700042 -97.133332)
			(xy 239.792337 -97.123623) (xy 239.838738 -97.122996) (xy 239.880752 -97.123496) (xy 239.964406 -97.131425)
			(xy 240.04694 -97.147207) (xy 240.127617 -97.170703) (xy 240.205719 -97.201702) (xy 240.280549 -97.239929)
			(xy 240.35144 -97.285043) (xy 240.417761 -97.336642) (xy 240.47892 -97.394265) (xy 240.507012 -97.42551)
			(xy 240.514378 -97.433892) (xy 240.53419 -97.442782) (xy 240.632488 -97.442782) (xy 240.6523 -97.433892)
			(xy 240.659666 -97.42551) (xy 240.687785 -97.394291) (xy 240.748952 -97.336683) (xy 240.815276 -97.285096)
			(xy 240.886166 -97.239989) (xy 240.960991 -97.201763) (xy 241.039086 -97.170759) (xy 241.119755 -97.147252)
			(xy 241.202281 -97.131452) (xy 241.285928 -97.1235) (xy 241.32794 -97.122996) (xy 241.374343 -97.123607)
			(xy 241.46664 -97.133301) (xy 241.557426 -97.15256) (xy 241.645711 -97.181172) (xy 241.688366 -97.19945)
			(xy 241.698308 -97.203256) (xy 241.719572 -97.203256) (xy 241.729514 -97.19945) (xy 241.77217 -97.181176)
			(xy 241.86046 -97.152585) (xy 241.951244 -97.133332) (xy 242.043539 -97.123623) (xy 242.08994 -97.122996)
			(xy 242.132297 -97.123586) (xy 242.216628 -97.131642) (xy 242.299811 -97.147678) (xy 242.381094 -97.171547)
			(xy 242.459739 -97.203035) (xy 242.535035 -97.241856) (xy 242.606301 -97.287659) (xy 242.67289 -97.340028)
			(xy 242.734199 -97.398489) (xy 242.789674 -97.462513) (xy 242.838812 -97.531521) (xy 242.881169 -97.604886)
			(xy 242.916359 -97.681946) (xy 242.944066 -97.762002) (xy 242.964038 -97.844329) (xy 242.976094 -97.928181)
			(xy 242.980125 -98.0128) (xy 242.976094 -98.097419) (xy 242.964038 -98.181271) (xy 242.944066 -98.263598)
			(xy 242.916359 -98.343654) (xy 242.881169 -98.420714) (xy 242.838812 -98.494079) (xy 242.789674 -98.563087)
			(xy 242.734199 -98.627111) (xy 242.67289 -98.685572) (xy 242.606301 -98.737941) (xy 242.535035 -98.783744)
			(xy 242.459739 -98.822565) (xy 242.381094 -98.854053) (xy 242.299811 -98.877922) (xy 242.216628 -98.893958)
			(xy 242.132297 -98.902014) (xy 242.08994 -98.90252) (xy 242.043537 -98.901915) (xy 241.951239 -98.892218)
			(xy 241.860454 -98.872958) (xy 241.772169 -98.844345) (xy 241.729514 -98.826066) (xy 241.719572 -98.82226)
			(xy 241.698308 -98.82226) (xy 241.688366 -98.826066) (xy 241.6457 -98.844315) (xy 241.557414 -98.872912)
			(xy 241.466632 -98.892172) (xy 241.374341 -98.901889) (xy 241.32794 -98.90252) (xy 241.285924 -98.902064)
			(xy 241.202268 -98.894132) (xy 241.119733 -98.878347) (xy 241.039054 -98.854846) (xy 240.960952 -98.823842)
			(xy 240.886122 -98.785609) (xy 240.815232 -98.740489) (xy 240.748913 -98.688884) (xy 240.687757 -98.631255)
			(xy 240.659666 -98.600006) (xy 240.6523 -98.591624) (xy 240.632488 -98.582734) (xy 240.53419 -98.582734)
			(xy 240.514378 -98.591624) (xy 240.507012 -98.600006) (xy 240.478908 -98.631239) (xy 240.417739 -98.688846)
			(xy 240.351413 -98.740432) (xy 240.280521 -98.785537) (xy 240.205693 -98.823762) (xy 240.127596 -98.854764)
			(xy 240.046926 -98.878269) (xy 239.964399 -98.894067) (xy 239.88075 -98.902017) (xy 239.838738 -98.90252)
			(xy 239.792335 -98.901915) (xy 239.700037 -98.892219) (xy 239.609252 -98.872959) (xy 239.520967 -98.844345)
			(xy 239.478312 -98.826066) (xy 239.46837 -98.82226) (xy 239.447106 -98.82226) (xy 239.437164 -98.826066)
			(xy 239.394498 -98.844316) (xy 239.306212 -98.872912) (xy 239.215431 -98.892173) (xy 239.123139 -98.901889)
			(xy 239.076738 -98.90252) (xy 239.035642 -98.902044) (xy 238.9538 -98.894466) (xy 238.873006 -98.879373)
			(xy 238.793948 -98.856892) (xy 238.7173 -98.827215) (xy 238.643717 -98.790595) (xy 238.573825 -98.747345)
			(xy 238.508219 -98.697833) (xy 238.44746 -98.64248) (xy 238.392066 -98.58176) (xy 238.342507 -98.516189)
			(xy 238.299208 -98.446327) (xy 238.280448 -98.40976) (xy 238.274098 -98.396806) (xy 238.250222 -98.38182)
			(xy 238.13135 -98.380042) (xy 238.106966 -98.394266) (xy 238.100108 -98.406966) (xy 238.079063 -98.445144)
			(xy 238.030497 -98.517548) (xy 237.97508 -98.584852) (xy 237.913343 -98.64641) (xy 237.845879 -98.701633)
			(xy 237.773335 -98.749989) (xy 237.696408 -98.791014) (xy 237.615835 -98.824316) (xy 237.532391 -98.849574)
			(xy 237.446875 -98.866545) (xy 237.36011 -98.875068) (xy 237.316518 -98.875596) (xy 237.270115 -98.875)
			(xy 237.177817 -98.865302) (xy 237.087031 -98.846039) (xy 236.998747 -98.817422) (xy 236.956092 -98.799142)
			(xy 236.94615 -98.795336) (xy 236.924886 -98.795336) (xy 236.914944 -98.799142) (xy 236.87228 -98.817397)
			(xy 236.783993 -98.845992) (xy 236.693211 -98.865251) (xy 236.600919 -98.874966) (xy 236.554518 -98.875596)
			(xy 236.512503 -98.875129) (xy 236.428848 -98.867197) (xy 236.346313 -98.85141) (xy 236.265636 -98.827911)
			(xy 236.187534 -98.796907) (xy 236.112704 -98.758676) (xy 236.041813 -98.713558) (xy 235.975493 -98.661956)
			(xy 235.914336 -98.604329) (xy 235.886244 -98.573082) (xy 235.878878 -98.5647) (xy 235.859066 -98.55581)
			(xy 235.760768 -98.55581) (xy 235.740956 -98.5647) (xy 235.73359 -98.573082) (xy 235.705492 -98.604321)
			(xy 235.644323 -98.661928) (xy 235.577996 -98.713514) (xy 235.507103 -98.75862) (xy 235.432275 -98.796844)
			(xy 235.354177 -98.827845) (xy 235.273506 -98.851349) (xy 235.190978 -98.867146) (xy 235.107329 -98.875094)
			(xy 235.065316 -98.875596) (xy 235.018913 -98.875001) (xy 234.926615 -98.865302) (xy 234.835829 -98.846039)
			(xy 234.747545 -98.817422) (xy 234.70489 -98.799142) (xy 234.694948 -98.795336) (xy 234.673684 -98.795336)
			(xy 234.663742 -98.799142) (xy 234.621078 -98.817397) (xy 234.532791 -98.845993) (xy 234.442009 -98.865252)
			(xy 234.349717 -98.874966) (xy 234.303316 -98.875596) (xy 234.259735 -98.875093) (xy 234.172991 -98.866554)
			(xy 234.087498 -98.849575) (xy 234.004075 -98.824318) (xy 233.92352 -98.791027) (xy 233.846606 -98.750019)
			(xy 233.77407 -98.701689) (xy 233.706607 -98.646498) (xy 233.644862 -98.584976) (xy 233.589428 -98.517712)
			(xy 233.540836 -98.445351) (xy 233.519726 -98.40722) (xy 233.512868 -98.39452) (xy 233.488738 -98.380296)
			(xy 233.369612 -98.382074) (xy 233.345736 -98.39706) (xy 233.339386 -98.410014) (xy 233.320611 -98.446555)
			(xy 233.277315 -98.516379) (xy 233.227765 -98.581914) (xy 233.172384 -98.6426) (xy 233.111643 -98.697922)
			(xy 233.04606 -98.747408) (xy 232.976193 -98.790636) (xy 232.902638 -98.827237) (xy 232.826022 -98.856901)
			(xy 232.746997 -98.879374) (xy 232.666237 -98.894464) (xy 232.584429 -98.902044) (xy 232.54335 -98.90252)
			(xy 232.496947 -98.901911) (xy 232.40465 -98.892216) (xy 232.313864 -98.872957) (xy 232.225579 -98.844344)
			(xy 232.182924 -98.826066) (xy 232.172982 -98.82226) (xy 232.151718 -98.82226) (xy 232.141776 -98.826066)
			(xy 232.099108 -98.844312) (xy 232.010823 -98.872909) (xy 231.920042 -98.892171) (xy 231.82775 -98.901888)
			(xy 231.78135 -98.90252) (xy 231.739335 -98.902057) (xy 231.655679 -98.894126) (xy 231.573143 -98.878341)
			(xy 231.492465 -98.854842) (xy 231.414363 -98.823839) (xy 231.339533 -98.785607) (xy 231.268642 -98.740488)
			(xy 231.202323 -98.688883) (xy 231.141167 -98.631254) (xy 231.113076 -98.600006) (xy 231.10571 -98.591624)
			(xy 231.085898 -98.582734) (xy 230.9876 -98.582734) (xy 230.967788 -98.591624) (xy 230.960422 -98.600006)
			(xy 230.932313 -98.631234) (xy 230.871144 -98.688841) (xy 230.804819 -98.740427) (xy 230.733927 -98.785534)
			(xy 230.659101 -98.823758) (xy 230.581005 -98.854761) (xy 230.500334 -98.878267) (xy 230.417808 -98.894066)
			(xy 230.33416 -98.902017) (xy 230.292148 -98.90252) (xy 230.245745 -98.901912) (xy 230.153448 -98.892216)
			(xy 230.062662 -98.872957) (xy 229.974377 -98.844344) (xy 229.931722 -98.826066) (xy 229.92178 -98.82226)
			(xy 229.900516 -98.82226) (xy 229.890574 -98.826066) (xy 229.847907 -98.844312) (xy 229.759621 -98.87291)
			(xy 229.66884 -98.892171) (xy 229.576548 -98.901889) (xy 229.530148 -98.90252) (xy 229.487783 -98.902118)
			(xy 229.403437 -98.894068) (xy 229.320238 -98.878037) (xy 229.238939 -98.854169) (xy 229.160278 -98.822682)
			(xy 229.084966 -98.783859) (xy 229.013685 -98.738053) (xy 228.947082 -98.685679) (xy 228.885758 -98.627211)
			(xy 228.830271 -98.563178) (xy 228.781121 -98.49416) (xy 228.738755 -98.420783) (xy 228.703556 -98.343711)
			(xy 228.675843 -98.263642) (xy 228.655866 -98.181301) (xy 228.643808 -98.097434) (xy 228.639776 -98.0128)
			(xy 228.496115 -98.0128) (xy 228.493369 -98.070428) (xy 228.481312 -98.154289) (xy 228.461338 -98.236624)
			(xy 228.433628 -98.316688) (xy 228.398433 -98.393756) (xy 228.356071 -98.467129) (xy 228.306927 -98.536143)
			(xy 228.251445 -98.600173) (xy 228.190129 -98.658639) (xy 228.123532 -98.711012) (xy 228.052258 -98.756818)
			(xy 227.976953 -98.795642) (xy 227.898299 -98.827131) (xy 227.817008 -98.851002) (xy 227.733816 -98.867037)
			(xy 227.649476 -98.875091) (xy 227.607114 -98.875596) (xy 227.560711 -98.875002) (xy 227.468413 -98.865303)
			(xy 227.377627 -98.84604) (xy 227.289343 -98.817422) (xy 227.246688 -98.799142) (xy 227.236746 -98.795336)
			(xy 227.215482 -98.795336) (xy 227.20554 -98.799142) (xy 227.162877 -98.817398) (xy 227.07459 -98.845993)
			(xy 226.983807 -98.865252) (xy 226.891515 -98.874966) (xy 226.845114 -98.875596) (xy 226.803099 -98.875132)
			(xy 226.719443 -98.867199) (xy 226.636909 -98.851412) (xy 226.556231 -98.827912) (xy 226.47813 -98.796908)
			(xy 226.4033 -98.758677) (xy 226.332409 -98.713559) (xy 226.266089 -98.661956) (xy 226.204932 -98.604329)
			(xy 226.17684 -98.573082) (xy 226.169474 -98.5647) (xy 226.149662 -98.55581) (xy 226.051364 -98.55581)
			(xy 226.031552 -98.5647) (xy 226.024186 -98.573082) (xy 225.996091 -98.604322) (xy 225.93492 -98.66193)
			(xy 225.868594 -98.713516) (xy 225.7977 -98.758621) (xy 225.722872 -98.796845) (xy 225.644774 -98.827847)
			(xy 225.564102 -98.85135) (xy 225.481574 -98.867146) (xy 225.397925 -98.875094) (xy 225.355912 -98.875596)
			(xy 225.309509 -98.875003) (xy 225.217211 -98.865303) (xy 225.126425 -98.84604) (xy 225.038141 -98.817423)
			(xy 224.995486 -98.799142) (xy 224.985544 -98.795336) (xy 224.96428 -98.795336) (xy 224.954338 -98.799142)
			(xy 224.911675 -98.817399) (xy 224.823388 -98.845994) (xy 224.732606 -98.865252) (xy 224.640313 -98.874966)
			(xy 224.593912 -98.875596) (xy 224.550884 -98.875115) (xy 224.46523 -98.866789) (xy 224.380781 -98.850235)
			(xy 224.298323 -98.825606) (xy 224.218628 -98.793132) (xy 224.14244 -98.753118) (xy 224.070471 -98.705935)
			(xy 224.003392 -98.652026) (xy 223.94183 -98.591893) (xy 223.88636 -98.526099) (xy 223.837501 -98.455257)
			(xy 223.816164 -98.417888) (xy 223.811456 -98.410156) (xy 223.797725 -98.398375) (xy 223.78076 -98.392092)
			(xy 223.771714 -98.391726) (xy 223.683068 -98.391726) (xy 223.674022 -98.392104) (xy 223.657053 -98.398374)
			(xy 223.643325 -98.410155) (xy 223.638618 -98.417888) (xy 223.61725 -98.45524) (xy 223.568406 -98.526093)
			(xy 223.512948 -98.591898) (xy 223.451394 -98.652039) (xy 223.38432 -98.705954) (xy 223.312352 -98.753139)
			(xy 223.236163 -98.793153) (xy 223.156466 -98.825623) (xy 223.074006 -98.850243) (xy 222.989554 -98.866785)
			(xy 222.903899 -98.875093) (xy 222.86087 -98.875596) (xy 222.814467 -98.874982) (xy 222.72217 -98.865289)
			(xy 222.631384 -98.846031) (xy 222.5431 -98.81742) (xy 222.500444 -98.799142) (xy 222.490502 -98.795336)
			(xy 222.469238 -98.795336) (xy 222.459296 -98.799142) (xy 222.416639 -98.817413) (xy 222.328349 -98.846004)
			(xy 222.237565 -98.865259) (xy 222.145271 -98.874969) (xy 222.09887 -98.875596) (xy 222.056856 -98.875093)
			(xy 221.973202 -98.867165) (xy 221.890668 -98.851383) (xy 221.809991 -98.827888) (xy 221.731889 -98.796889)
			(xy 221.657059 -98.758662) (xy 221.586168 -98.713549) (xy 221.519847 -98.66195) (xy 221.458688 -98.604327)
			(xy 221.430596 -98.573082) (xy 221.42323 -98.5647) (xy 221.403418 -98.55581) (xy 221.30512 -98.55581)
			(xy 221.285308 -98.5647) (xy 221.277942 -98.573082) (xy 221.249817 -98.604295) (xy 221.188651 -98.661904)
			(xy 221.122328 -98.713491) (xy 221.051439 -98.758599) (xy 220.976614 -98.796826) (xy 220.89852 -98.827831)
			(xy 220.817851 -98.851338) (xy 220.735326 -98.867139) (xy 220.65168 -98.875092) (xy 220.609668 -98.875596)
			(xy 220.563265 -98.874983) (xy 220.470968 -98.865289) (xy 220.380182 -98.846032) (xy 220.291898 -98.81742)
			(xy 220.249242 -98.799142) (xy 220.2393 -98.795336) (xy 220.218036 -98.795336) (xy 220.208094 -98.799142)
			(xy 220.165437 -98.817413) (xy 220.077147 -98.846004) (xy 219.986363 -98.865259) (xy 219.894069 -98.874969)
			(xy 219.847668 -98.875596) (xy 219.806723 -98.875148) (xy 219.725182 -98.867601) (xy 219.644679 -98.852594)
			(xy 219.565896 -98.830252) (xy 219.489499 -98.800765) (xy 219.416135 -98.764383) (xy 219.346425 -98.721413)
			(xy 219.280958 -98.672219) (xy 219.220289 -98.617217) (xy 219.164931 -98.556873) (xy 219.13977 -98.524568)
			(xy 219.132404 -98.514916) (xy 219.110814 -98.504502) (xy 219.004388 -98.50628) (xy 218.983052 -98.517456)
			(xy 218.97594 -98.527362) (xy 218.950986 -98.561702) (xy 218.895528 -98.625977) (xy 218.834198 -98.684675)
			(xy 218.767553 -98.737261) (xy 218.6962 -98.783257) (xy 218.620789 -98.822245) (xy 218.542006 -98.853868)
			(xy 218.460568 -98.87784) (xy 218.377216 -98.893943) (xy 218.292709 -98.902029) (xy 218.250262 -98.90252)
			(xy 218.203867 -98.901914) (xy 218.111579 -98.892276) (xy 218.020796 -98.873086) (xy 217.932501 -98.844555)
			(xy 217.889836 -98.82632) (xy 217.879894 -98.822514) (xy 217.85863 -98.822514) (xy 217.848688 -98.82632)
			(xy 217.806031 -98.844578) (xy 217.717737 -98.873118) (xy 217.62695 -98.892308) (xy 217.534659 -98.901937)
			(xy 217.488262 -98.90252) (xy 217.446255 -98.90201) (xy 217.362615 -98.894097) (xy 217.280094 -98.878335)
			(xy 217.199425 -98.854865) (xy 217.121328 -98.823895) (xy 217.046498 -98.785702) (xy 216.975601 -98.740625)
			(xy 216.909269 -98.689066) (xy 216.848092 -98.631484) (xy 216.819988 -98.60026) (xy 216.812622 -98.591878)
			(xy 216.79281 -98.582988) (xy 216.694512 -98.582988) (xy 216.6747 -98.591878) (xy 216.667334 -98.60026)
			(xy 216.639237 -98.631494) (xy 216.578074 -98.689098) (xy 216.511749 -98.740675) (xy 216.440855 -98.785766)
			(xy 216.366023 -98.823967) (xy 216.287921 -98.854938) (xy 216.207246 -98.878404) (xy 216.124717 -98.894154)
			(xy 216.04107 -98.902048) (xy 215.99906 -98.90252) (xy 215.952665 -98.901915) (xy 215.860377 -98.892276)
			(xy 215.769594 -98.873087) (xy 215.681299 -98.844555) (xy 215.638634 -98.82632) (xy 215.628692 -98.822514)
			(xy 215.607428 -98.822514) (xy 215.597486 -98.82632) (xy 215.55483 -98.844579) (xy 215.466535 -98.873119)
			(xy 215.375748 -98.892308) (xy 215.283457 -98.901937) (xy 215.23706 -98.90252) (xy 215.194713 -98.901991)
			(xy 215.110404 -98.893936) (xy 215.027241 -98.877905) (xy 214.94598 -98.854041) (xy 214.867354 -98.822561)
			(xy 214.792077 -98.78375) (xy 214.720829 -98.737959) (xy 214.654257 -98.685603) (xy 214.592963 -98.627157)
			(xy 214.537502 -98.563148) (xy 214.488376 -98.494158) (xy 214.44603 -98.420811) (xy 214.410848 -98.343771)
			(xy 214.383149 -98.263735) (xy 214.363182 -98.181429) (xy 214.351129 -98.097598) (xy 214.347099 -98.013)
			(xy 0.509016 -98.013) (xy 0.509016 -101.388361) (xy 214.756742 -101.388361) (xy 214.756742 -101.303639)
			(xy 214.764795 -101.219302) (xy 214.780829 -101.136112) (xy 214.804697 -101.054822) (xy 214.836185 -100.97617)
			(xy 214.875007 -100.900867) (xy 214.92081 -100.829595) (xy 214.973181 -100.762999) (xy 215.031646 -100.701684)
			(xy 215.095674 -100.646203) (xy 215.164686 -100.59706) (xy 215.238056 -100.5547) (xy 215.315121 -100.519505)
			(xy 215.395183 -100.491796) (xy 215.477516 -100.471822) (xy 215.561375 -100.459765) (xy 215.646 -100.455734)
			(xy 215.730625 -100.459765) (xy 215.814484 -100.471822) (xy 215.896817 -100.491796) (xy 215.976879 -100.519505)
			(xy 216.053944 -100.5547) (xy 216.127314 -100.59706) (xy 216.196326 -100.646203) (xy 216.260354 -100.701684)
			(xy 216.318819 -100.762999) (xy 216.37119 -100.829595) (xy 216.416993 -100.900867) (xy 216.455815 -100.97617)
			(xy 216.487303 -101.054822) (xy 216.511171 -101.136112) (xy 216.527205 -101.219302) (xy 216.535258 -101.303639)
			(xy 216.535762 -101.346) (xy 216.535258 -101.388361) (xy 216.527205 -101.472698) (xy 216.511171 -101.555888)
			(xy 216.487303 -101.637178) (xy 216.455815 -101.71583) (xy 216.450056 -101.727) (xy 268.350492 -101.727)
			(xy 268.351075 -101.680604) (xy 268.36072 -101.588316) (xy 268.379916 -101.497532) (xy 268.408454 -101.409239)
			(xy 268.426692 -101.366574) (xy 268.430498 -101.356632) (xy 268.430498 -101.335368) (xy 268.426692 -101.325426)
			(xy 268.408447 -101.282764) (xy 268.379903 -101.194471) (xy 268.36071 -101.103686) (xy 268.351077 -101.011396)
			(xy 268.350492 -100.965) (xy 268.351075 -100.918604) (xy 268.36072 -100.826316) (xy 268.379916 -100.735532)
			(xy 268.408454 -100.647239) (xy 268.426692 -100.604574) (xy 268.430498 -100.594632) (xy 268.430498 -100.573368)
			(xy 268.426692 -100.563426) (xy 268.408447 -100.520764) (xy 268.379903 -100.432471) (xy 268.36071 -100.341686)
			(xy 268.351077 -100.249396) (xy 268.350492 -100.203) (xy 268.351075 -100.156604) (xy 268.36072 -100.064316)
			(xy 268.379916 -99.973532) (xy 268.408454 -99.885239) (xy 268.426692 -99.842574) (xy 268.430498 -99.832632)
			(xy 268.430498 -99.811368) (xy 268.426692 -99.801426) (xy 268.408447 -99.758764) (xy 268.379903 -99.670471)
			(xy 268.36071 -99.579686) (xy 268.351077 -99.487396) (xy 268.350492 -99.441) (xy 268.351075 -99.394604)
			(xy 268.36072 -99.302316) (xy 268.379916 -99.211532) (xy 268.408454 -99.123239) (xy 268.426692 -99.080574)
			(xy 268.430498 -99.070632) (xy 268.430498 -99.049368) (xy 268.426692 -99.039426) (xy 268.408447 -98.996764)
			(xy 268.379903 -98.908471) (xy 268.36071 -98.817686) (xy 268.351077 -98.725396) (xy 268.350492 -98.679)
			(xy 268.351075 -98.632604) (xy 268.36072 -98.540316) (xy 268.379916 -98.449532) (xy 268.408454 -98.361239)
			(xy 268.426692 -98.318574) (xy 268.430498 -98.308632) (xy 268.430498 -98.287368) (xy 268.426692 -98.277426)
			(xy 268.408447 -98.234764) (xy 268.379903 -98.146471) (xy 268.36071 -98.055686) (xy 268.351077 -97.963396)
			(xy 268.350492 -97.917) (xy 268.350967 -97.875898) (xy 268.358552 -97.794043) (xy 268.373657 -97.713238)
			(xy 268.396153 -97.634171) (xy 268.425849 -97.557517) (xy 268.462491 -97.48393) (xy 268.505766 -97.414038)
			(xy 268.555306 -97.348437) (xy 268.610687 -97.287687) (xy 268.671437 -97.232306) (xy 268.737038 -97.182766)
			(xy 268.80693 -97.139491) (xy 268.880517 -97.102849) (xy 268.957171 -97.073153) (xy 269.036238 -97.050657)
			(xy 269.117043 -97.035552) (xy 269.198898 -97.027967) (xy 269.24 -97.027492) (xy 269.286396 -97.028075)
			(xy 269.378684 -97.03772) (xy 269.469468 -97.056916) (xy 269.557761 -97.085454) (xy 269.600426 -97.103692)
			(xy 269.610368 -97.107498) (xy 269.631632 -97.107498) (xy 269.641574 -97.103692) (xy 269.684236 -97.085447)
			(xy 269.772529 -97.056903) (xy 269.863314 -97.03771) (xy 269.955604 -97.028077) (xy 270.002 -97.027492)
			(xy 270.048396 -97.028075) (xy 270.140684 -97.03772) (xy 270.231468 -97.056916) (xy 270.319761 -97.085454)
			(xy 270.362426 -97.103692) (xy 270.372368 -97.107498) (xy 270.393632 -97.107498) (xy 270.403574 -97.103692)
			(xy 270.446236 -97.085447) (xy 270.534529 -97.056903) (xy 270.625314 -97.03771) (xy 270.717604 -97.028077)
			(xy 270.764 -97.027492) (xy 270.810396 -97.028075) (xy 270.902684 -97.03772) (xy 270.993468 -97.056916)
			(xy 271.081761 -97.085454) (xy 271.124426 -97.103692) (xy 271.134368 -97.107498) (xy 271.155632 -97.107498)
			(xy 271.165574 -97.103692) (xy 271.208236 -97.085447) (xy 271.296529 -97.056903) (xy 271.387314 -97.03771)
			(xy 271.479604 -97.028077) (xy 271.526 -97.027492) (xy 271.572396 -97.028075) (xy 271.664684 -97.03772)
			(xy 271.755468 -97.056916) (xy 271.843761 -97.085454) (xy 271.886426 -97.103692) (xy 271.896368 -97.107498)
			(xy 271.917632 -97.107498) (xy 271.927574 -97.103692) (xy 271.970236 -97.085447) (xy 272.058529 -97.056903)
			(xy 272.149314 -97.03771) (xy 272.241604 -97.028077) (xy 272.288 -97.027492) (xy 272.329102 -97.027967)
			(xy 272.410957 -97.035552) (xy 272.491762 -97.050657) (xy 272.570829 -97.073153) (xy 272.647483 -97.102849)
			(xy 272.72107 -97.139491) (xy 272.790962 -97.182766) (xy 272.856563 -97.232306) (xy 272.917313 -97.287687)
			(xy 272.972694 -97.348437) (xy 273.022234 -97.414038) (xy 273.065509 -97.48393) (xy 273.102151 -97.557517)
			(xy 273.131847 -97.634171) (xy 273.154343 -97.713238) (xy 273.169448 -97.794043) (xy 273.177033 -97.875898)
			(xy 273.177508 -97.917) (xy 273.176925 -97.963396) (xy 273.16728 -98.055684) (xy 273.148084 -98.146468)
			(xy 273.119546 -98.234761) (xy 273.101308 -98.277426) (xy 273.097502 -98.287368) (xy 273.097502 -98.308632)
			(xy 273.101308 -98.318574) (xy 273.119553 -98.361236) (xy 273.148097 -98.449529) (xy 273.16729 -98.540314)
			(xy 273.176923 -98.632604) (xy 273.177508 -98.679) (xy 273.177033 -98.720102) (xy 273.169448 -98.801957)
			(xy 273.154343 -98.882762) (xy 273.131847 -98.961829) (xy 273.102151 -99.038483) (xy 273.065509 -99.11207)
			(xy 273.022234 -99.181962) (xy 272.972694 -99.247563) (xy 272.917313 -99.308313) (xy 272.856563 -99.363694)
			(xy 272.790962 -99.413234) (xy 272.72107 -99.456509) (xy 272.647483 -99.493151) (xy 272.570829 -99.522847)
			(xy 272.491762 -99.545343) (xy 272.410957 -99.560448) (xy 272.329102 -99.568033) (xy 272.288 -99.568508)
			(xy 272.241604 -99.567925) (xy 272.149316 -99.55828) (xy 272.058532 -99.539084) (xy 271.970239 -99.510546)
			(xy 271.927574 -99.492308) (xy 271.917632 -99.488502) (xy 271.896368 -99.488502) (xy 271.886426 -99.492308)
			(xy 271.853507 -99.506537) (xy 271.785822 -99.530257) (xy 271.716442 -99.548437) (xy 271.681194 -99.555046)
			(xy 271.67107 -99.557344) (xy 271.653749 -99.568749) (xy 271.642344 -99.58607) (xy 271.640046 -99.596194)
			(xy 271.633416 -99.631437) (xy 271.61522 -99.70081) (xy 271.591513 -99.768498) (xy 271.577308 -99.801426)
			(xy 271.573502 -99.811368) (xy 271.573502 -99.832632) (xy 271.577308 -99.842574) (xy 271.591537 -99.875493)
			(xy 271.615257 -99.943178) (xy 271.633437 -100.012558) (xy 271.640046 -100.047806) (xy 271.642344 -100.05793)
			(xy 271.653749 -100.075251) (xy 271.67107 -100.086656) (xy 271.681194 -100.088954) (xy 271.716437 -100.095584)
			(xy 271.78581 -100.11378) (xy 271.853498 -100.137487) (xy 271.886426 -100.151692) (xy 271.896368 -100.155498)
			(xy 271.917632 -100.155498) (xy 271.927574 -100.151692) (xy 271.970236 -100.133447) (xy 272.058529 -100.104903)
			(xy 272.149314 -100.08571) (xy 272.241604 -100.076077) (xy 272.288 -100.075492) (xy 272.329102 -100.075967)
			(xy 272.410957 -100.083552) (xy 272.491762 -100.098657) (xy 272.570829 -100.121153) (xy 272.647483 -100.150849)
			(xy 272.72107 -100.187491) (xy 272.790962 -100.230766) (xy 272.856563 -100.280306) (xy 272.917313 -100.335687)
			(xy 272.972694 -100.396437) (xy 273.022234 -100.462038) (xy 273.065509 -100.53193) (xy 273.102151 -100.605517)
			(xy 273.131847 -100.682171) (xy 273.154343 -100.761238) (xy 273.169448 -100.842043) (xy 273.177033 -100.923898)
			(xy 273.177508 -100.965) (xy 273.176925 -101.011396) (xy 273.16728 -101.103684) (xy 273.148084 -101.194468)
			(xy 273.119546 -101.282761) (xy 273.101308 -101.325426) (xy 273.097502 -101.335368) (xy 273.097502 -101.356632)
			(xy 273.101308 -101.366574) (xy 273.119553 -101.409236) (xy 273.148097 -101.497529) (xy 273.16729 -101.588314)
			(xy 273.176923 -101.680604) (xy 273.177508 -101.727) (xy 273.177087 -101.76701) (xy 273.169907 -101.846708)
			(xy 273.155596 -101.925439) (xy 273.134269 -102.002565) (xy 273.106099 -102.077463) (xy 273.071314 -102.149528)
			(xy 273.030196 -102.218176) (xy 272.983076 -102.282852) (xy 272.957036 -102.313232) (xy 272.947892 -102.3239)
			(xy 272.942812 -102.350824) (xy 272.982436 -102.460806) (xy 273.003518 -102.478332) (xy 273.017488 -102.480618)
			(xy 273.058748 -102.487682) (xy 273.139783 -102.5087) (xy 273.202283 -102.531361) (xy 275.081742 -102.531361)
			(xy 275.081742 -102.446639) (xy 275.089795 -102.362302) (xy 275.105829 -102.279112) (xy 275.129697 -102.197822)
			(xy 275.161185 -102.11917) (xy 275.200007 -102.043867) (xy 275.24581 -101.972595) (xy 275.298181 -101.905999)
			(xy 275.356646 -101.844684) (xy 275.420674 -101.789203) (xy 275.489686 -101.74006) (xy 275.563056 -101.6977)
			(xy 275.640121 -101.662505) (xy 275.720183 -101.634796) (xy 275.802516 -101.614822) (xy 275.886375 -101.602765)
			(xy 275.971 -101.598734) (xy 276.055625 -101.602765) (xy 276.139484 -101.614822) (xy 276.221817 -101.634796)
			(xy 276.301879 -101.662505) (xy 276.378944 -101.6977) (xy 276.452314 -101.74006) (xy 276.521326 -101.789203)
			(xy 276.585354 -101.844684) (xy 276.643819 -101.905999) (xy 276.69619 -101.972595) (xy 276.741993 -102.043867)
			(xy 276.780815 -102.11917) (xy 276.812303 -102.197822) (xy 276.836171 -102.279112) (xy 276.852205 -102.362302)
			(xy 276.860258 -102.446639) (xy 276.860762 -102.489) (xy 276.860258 -102.531361) (xy 276.852205 -102.615698)
			(xy 276.836171 -102.698888) (xy 276.812303 -102.780178) (xy 276.780815 -102.85883) (xy 276.741993 -102.934133)
			(xy 276.69619 -103.005405) (xy 276.643819 -103.072001) (xy 276.585354 -103.133316) (xy 276.521326 -103.188797)
			(xy 276.452314 -103.23794) (xy 276.378944 -103.2803) (xy 276.301879 -103.315495) (xy 276.221817 -103.343204)
			(xy 276.139484 -103.363178) (xy 276.055625 -103.375235) (xy 275.971 -103.379267) (xy 275.886375 -103.375235)
			(xy 275.802516 -103.363178) (xy 275.720183 -103.343204) (xy 275.640121 -103.315495) (xy 275.563056 -103.2803)
			(xy 275.489686 -103.23794) (xy 275.420674 -103.188797) (xy 275.356646 -103.133316) (xy 275.298181 -103.072001)
			(xy 275.24581 -103.005405) (xy 275.200007 -102.934133) (xy 275.161185 -102.85883) (xy 275.129697 -102.780178)
			(xy 275.105829 -102.698888) (xy 275.089795 -102.615698) (xy 275.081742 -102.531361) (xy 273.202283 -102.531361)
			(xy 273.218486 -102.537236) (xy 273.29416 -102.573039) (xy 273.366137 -102.615792) (xy 273.43378 -102.665117)
			(xy 273.49649 -102.720577) (xy 273.553714 -102.781682) (xy 273.604945 -102.847892) (xy 273.649731 -102.918622)
			(xy 273.687675 -102.993246) (xy 273.718442 -103.071104) (xy 273.741759 -103.151508) (xy 273.757421 -103.233746)
			(xy 273.76529 -103.317092) (xy 273.765772 -103.35895) (xy 273.765268 -103.401298) (xy 273.757217 -103.485612)
			(xy 273.741188 -103.568778) (xy 273.717327 -103.650045) (xy 273.685848 -103.728675) (xy 273.647037 -103.803956)
			(xy 273.601247 -103.875208) (xy 273.548891 -103.941784) (xy 273.490443 -104.003082) (xy 273.426433 -104.058547)
			(xy 273.357441 -104.107676) (xy 273.284091 -104.150025) (xy 273.207048 -104.185209) (xy 273.127009 -104.212911)
			(xy 273.0447 -104.232879) (xy 272.960865 -104.244932) (xy 272.876264 -104.248963) (xy 272.791663 -104.244932)
			(xy 272.707828 -104.232879) (xy 272.625519 -104.212911) (xy 272.54548 -104.185209) (xy 272.468437 -104.150025)
			(xy 272.395087 -104.107676) (xy 272.326095 -104.058547) (xy 272.262085 -104.003082) (xy 272.203637 -103.941784)
			(xy 272.151281 -103.875208) (xy 272.105491 -103.803956) (xy 272.06668 -103.728675) (xy 272.035201 -103.650045)
			(xy 272.01134 -103.568778) (xy 271.995311 -103.485612) (xy 271.98726 -103.401298) (xy 271.986756 -103.35895)
			(xy 271.987216 -103.318941) (xy 271.994392 -103.239244) (xy 272.008698 -103.160515) (xy 272.03002 -103.083389)
			(xy 272.058184 -103.008491) (xy 272.092963 -102.936426) (xy 272.134076 -102.867777) (xy 272.181191 -102.803099)
			(xy 272.207228 -102.772718) (xy 272.216372 -102.76205) (xy 272.221452 -102.735126) (xy 272.181828 -102.625144)
			(xy 272.160746 -102.607618) (xy 272.146776 -102.605332) (xy 272.109108 -102.598853) (xy 272.034963 -102.580278)
			(xy 271.962681 -102.555417) (xy 271.927574 -102.540308) (xy 271.917632 -102.536502) (xy 271.896368 -102.536502)
			(xy 271.886426 -102.540308) (xy 271.843764 -102.558553) (xy 271.755471 -102.587097) (xy 271.664686 -102.60629)
			(xy 271.572396 -102.615923) (xy 271.526 -102.616508) (xy 271.479604 -102.615925) (xy 271.387316 -102.60628)
			(xy 271.296532 -102.587084) (xy 271.208239 -102.558546) (xy 271.165574 -102.540308) (xy 271.155632 -102.536502)
			(xy 271.134368 -102.536502) (xy 271.124426 -102.540308) (xy 271.081764 -102.558553) (xy 270.993471 -102.587097)
			(xy 270.902686 -102.60629) (xy 270.810396 -102.615923) (xy 270.764 -102.616508) (xy 270.717604 -102.615925)
			(xy 270.625316 -102.60628) (xy 270.534532 -102.587084) (xy 270.446239 -102.558546) (xy 270.403574 -102.540308)
			(xy 270.393632 -102.536502) (xy 270.372368 -102.536502) (xy 270.362426 -102.540308) (xy 270.319764 -102.558553)
			(xy 270.231471 -102.587097) (xy 270.140686 -102.60629) (xy 270.048396 -102.615923) (xy 270.002 -102.616508)
			(xy 269.955604 -102.615925) (xy 269.863316 -102.60628) (xy 269.772532 -102.587084) (xy 269.684239 -102.558546)
			(xy 269.641574 -102.540308) (xy 269.631632 -102.536502) (xy 269.610368 -102.536502) (xy 269.600426 -102.540308)
			(xy 269.557764 -102.558553) (xy 269.469471 -102.587097) (xy 269.378686 -102.60629) (xy 269.286396 -102.615923)
			(xy 269.24 -102.616508) (xy 269.198898 -102.616033) (xy 269.117043 -102.608448) (xy 269.036238 -102.593343)
			(xy 268.957171 -102.570847) (xy 268.880517 -102.541151) (xy 268.80693 -102.504509) (xy 268.737038 -102.461234)
			(xy 268.671437 -102.411694) (xy 268.610687 -102.356313) (xy 268.555306 -102.295563) (xy 268.505766 -102.229962)
			(xy 268.462491 -102.16007) (xy 268.425849 -102.086483) (xy 268.396153 -102.009829) (xy 268.373657 -101.930762)
			(xy 268.358552 -101.849957) (xy 268.350967 -101.768102) (xy 268.350492 -101.727) (xy 216.450056 -101.727)
			(xy 216.416993 -101.791133) (xy 216.37119 -101.862405) (xy 216.318819 -101.929001) (xy 216.260354 -101.990316)
			(xy 216.196326 -102.045797) (xy 216.127314 -102.09494) (xy 216.053944 -102.1373) (xy 215.976879 -102.172495)
			(xy 215.896817 -102.200204) (xy 215.814484 -102.220178) (xy 215.730625 -102.232235) (xy 215.646 -102.236267)
			(xy 215.561375 -102.232235) (xy 215.477516 -102.220178) (xy 215.395183 -102.200204) (xy 215.315121 -102.172495)
			(xy 215.238056 -102.1373) (xy 215.164686 -102.09494) (xy 215.095674 -102.045797) (xy 215.031646 -101.990316)
			(xy 214.973181 -101.929001) (xy 214.92081 -101.862405) (xy 214.875007 -101.791133) (xy 214.836185 -101.71583)
			(xy 214.804697 -101.637178) (xy 214.780829 -101.555888) (xy 214.764795 -101.472698) (xy 214.756742 -101.388361)
			(xy 0.509016 -101.388361) (xy 0.509016 -108.3818) (xy 28.498292 -108.3818) (xy 28.498875 -108.335404)
			(xy 28.50852 -108.243116) (xy 28.527716 -108.152332) (xy 28.556254 -108.064039) (xy 28.574492 -108.021374)
			(xy 28.578397 -108.011452) (xy 28.578397 -107.990148) (xy 28.574492 -107.980226) (xy 28.556247 -107.937564)
			(xy 28.527703 -107.849271) (xy 28.50851 -107.758486) (xy 28.498877 -107.666196) (xy 28.498292 -107.6198)
			(xy 28.498723 -107.581372) (xy 28.505365 -107.504803) (xy 28.518591 -107.429093) (xy 28.538303 -107.354808)
			(xy 28.564353 -107.282501) (xy 28.58008 -107.247436) (xy 28.584223 -107.237163) (xy 28.584223 -107.215037)
			(xy 28.58008 -107.204764) (xy 28.564356 -107.169698) (xy 28.53831 -107.097389) (xy 28.518597 -107.023104)
			(xy 28.505365 -106.947396) (xy 28.498711 -106.870828) (xy 28.498292 -106.8324) (xy 28.498875 -106.786004)
			(xy 28.50852 -106.693716) (xy 28.527716 -106.602932) (xy 28.556254 -106.514639) (xy 28.574492 -106.471974)
			(xy 28.578397 -106.462052) (xy 28.578397 -106.440748) (xy 28.574492 -106.430826) (xy 28.556247 -106.388164)
			(xy 28.527703 -106.299871) (xy 28.50851 -106.209086) (xy 28.498877 -106.116796) (xy 28.498292 -106.0704)
			(xy 28.498875 -106.024004) (xy 28.50852 -105.931716) (xy 28.527716 -105.840932) (xy 28.556254 -105.752639)
			(xy 28.574492 -105.709974) (xy 28.578397 -105.700052) (xy 28.578397 -105.678748) (xy 28.574492 -105.668826)
			(xy 28.556247 -105.626164) (xy 28.527703 -105.537871) (xy 28.50851 -105.447086) (xy 28.498877 -105.354796)
			(xy 28.498292 -105.3084) (xy 28.498875 -105.262004) (xy 28.50852 -105.169716) (xy 28.527716 -105.078932)
			(xy 28.556254 -104.990639) (xy 28.574492 -104.947974) (xy 28.578397 -104.938052) (xy 28.578397 -104.916748)
			(xy 28.574492 -104.906826) (xy 28.556247 -104.864164) (xy 28.527703 -104.775871) (xy 28.50851 -104.685086)
			(xy 28.498877 -104.592796) (xy 28.498292 -104.5464) (xy 28.498875 -104.500004) (xy 28.50852 -104.407716)
			(xy 28.527716 -104.316932) (xy 28.556254 -104.228639) (xy 28.574492 -104.185974) (xy 28.578397 -104.176052)
			(xy 28.578397 -104.154748) (xy 28.574492 -104.144826) (xy 28.556247 -104.102164) (xy 28.527703 -104.013871)
			(xy 28.50851 -103.923086) (xy 28.498877 -103.830796) (xy 28.498292 -103.7844) (xy 28.498767 -103.743298)
			(xy 28.506352 -103.661443) (xy 28.521457 -103.580638) (xy 28.543953 -103.501571) (xy 28.573649 -103.424917)
			(xy 28.610291 -103.35133) (xy 28.653566 -103.281438) (xy 28.703106 -103.215837) (xy 28.758487 -103.155087)
			(xy 28.819237 -103.099706) (xy 28.884838 -103.050166) (xy 28.95473 -103.006891) (xy 29.028317 -102.970249)
			(xy 29.104971 -102.940553) (xy 29.184038 -102.918057) (xy 29.264843 -102.902952) (xy 29.346698 -102.895367)
			(xy 29.3878 -102.894892) (xy 29.433417 -102.895466) (xy 29.524172 -102.904799) (xy 29.613497 -102.923367)
			(xy 29.700453 -102.950974) (xy 29.78413 -102.987332) (xy 29.824172 -103.009192) (xy 29.832335 -103.013339)
			(xy 29.8504 -103.0162) (xy 29.86831 -103.012491) (xy 29.876242 -103.007922) (xy 29.911906 -102.985856)
			(xy 29.986639 -102.947783) (xy 30.064625 -102.916916) (xy 30.145171 -102.89353) (xy 30.227561 -102.877832)
			(xy 30.311064 -102.869963) (xy 30.353 -102.869492) (xy 30.39679 -102.86998) (xy 30.483949 -102.878545)
			(xy 30.569843 -102.89564) (xy 30.65364 -102.921101) (xy 30.734526 -102.95468) (xy 30.77337 -102.974902)
			(xy 30.784836 -102.98032) (xy 30.810164 -102.98032) (xy 30.82163 -102.974902) (xy 30.860471 -102.954677)
			(xy 30.941366 -102.921126) (xy 31.025164 -102.89568) (xy 31.111056 -102.878584) (xy 31.198212 -102.870005)
			(xy 31.242 -102.869492) (xy 31.283102 -102.869967) (xy 31.364957 -102.877552) (xy 31.445762 -102.892657)
			(xy 31.524829 -102.915153) (xy 31.601483 -102.944849) (xy 31.67507 -102.981491) (xy 31.744962 -103.024766)
			(xy 31.810563 -103.074306) (xy 31.871313 -103.129687) (xy 31.926694 -103.190437) (xy 31.976234 -103.256038)
			(xy 32.019509 -103.32593) (xy 32.056151 -103.399517) (xy 32.085847 -103.476171) (xy 32.108343 -103.555238)
			(xy 32.123448 -103.636043) (xy 32.131033 -103.717898) (xy 32.131508 -103.759) (xy 32.130925 -103.805396)
			(xy 32.12128 -103.897684) (xy 32.102084 -103.988468) (xy 32.073546 -104.076761) (xy 32.055308 -104.119426)
			(xy 32.051502 -104.129368) (xy 32.051502 -104.150632) (xy 32.055308 -104.160574) (xy 32.073553 -104.203236)
			(xy 32.102097 -104.291529) (xy 32.12129 -104.382314) (xy 32.130923 -104.474604) (xy 32.131508 -104.521)
			(xy 32.130925 -104.567396) (xy 32.12128 -104.659684) (xy 32.102084 -104.750468) (xy 32.073546 -104.838761)
			(xy 32.055308 -104.881426) (xy 32.051502 -104.891368) (xy 32.051502 -104.912632) (xy 32.055308 -104.922574)
			(xy 32.073553 -104.965236) (xy 32.102097 -105.053529) (xy 32.12129 -105.144314) (xy 32.130923 -105.236604)
			(xy 32.131508 -105.283) (xy 32.130925 -105.329396) (xy 32.12128 -105.421684) (xy 32.102084 -105.512468)
			(xy 32.073546 -105.600761) (xy 32.055308 -105.643426) (xy 32.051502 -105.653368) (xy 32.051502 -105.674632)
			(xy 32.055308 -105.684574) (xy 32.073553 -105.727236) (xy 32.102097 -105.815529) (xy 32.12129 -105.906314)
			(xy 32.130923 -105.998604) (xy 32.131508 -106.045) (xy 32.130925 -106.091396) (xy 32.12128 -106.183684)
			(xy 32.102084 -106.274468) (xy 32.073546 -106.362761) (xy 32.055308 -106.405426) (xy 32.051502 -106.415368)
			(xy 32.051502 -106.436632) (xy 32.055308 -106.446574) (xy 32.073553 -106.489236) (xy 32.102097 -106.577529)
			(xy 32.12129 -106.668314) (xy 32.130923 -106.760604) (xy 32.131508 -106.807) (xy 32.131149 -106.845449)
			(xy 32.124566 -106.922065) (xy 32.111388 -106.997826) (xy 32.091715 -107.072165) (xy 32.065692 -107.144526)
			(xy 32.049974 -107.179618) (xy 32.045874 -107.189831) (xy 32.045885 -107.211818) (xy 32.049974 -107.222036)
			(xy 32.065681 -107.257103) (xy 32.091668 -107.329421) (xy 32.111325 -107.40371) (xy 32.124505 -107.479417)
			(xy 32.131112 -107.555977) (xy 32.131508 -107.5944) (xy 32.130925 -107.640796) (xy 32.12128 -107.733084)
			(xy 32.102084 -107.823868) (xy 32.073546 -107.912161) (xy 32.055308 -107.954826) (xy 32.051403 -107.964748)
			(xy 32.051403 -107.986052) (xy 32.055308 -107.995974) (xy 32.073553 -108.038636) (xy 32.102097 -108.126929)
			(xy 32.12129 -108.217714) (xy 32.130923 -108.310004) (xy 32.131508 -108.3564) (xy 38.937692 -108.3564)
			(xy 38.938275 -108.310004) (xy 38.94792 -108.217716) (xy 38.967116 -108.126932) (xy 38.995654 -108.038639)
			(xy 39.013892 -107.995974) (xy 39.017797 -107.986052) (xy 39.017797 -107.964748) (xy 39.013892 -107.954826)
			(xy 38.995647 -107.912164) (xy 38.967103 -107.823871) (xy 38.94791 -107.733086) (xy 38.938277 -107.640796)
			(xy 38.937692 -107.5944) (xy 38.938251 -107.550173) (xy 38.947033 -107.462156) (xy 38.964509 -107.375446)
			(xy 38.990508 -107.2909) (xy 39.024773 -107.209352) (xy 39.045388 -107.17022) (xy 39.050228 -107.160228)
			(xy 39.051661 -107.138093) (xy 39.048182 -107.127548) (xy 39.033858 -107.089132) (xy 39.011486 -107.010251)
			(xy 38.996473 -106.929644) (xy 38.988949 -106.847997) (xy 38.988492 -106.807) (xy 38.989075 -106.760604)
			(xy 38.99872 -106.668316) (xy 39.017916 -106.577532) (xy 39.046454 -106.489239) (xy 39.064692 -106.446574)
			(xy 39.068498 -106.436632) (xy 39.068498 -106.415368) (xy 39.064692 -106.405426) (xy 39.046447 -106.362764)
			(xy 39.017903 -106.274471) (xy 38.99871 -106.183686) (xy 38.989077 -106.091396) (xy 38.988492 -106.045)
			(xy 38.989075 -105.998604) (xy 38.99872 -105.906316) (xy 39.017916 -105.815532) (xy 39.046454 -105.727239)
			(xy 39.064692 -105.684574) (xy 39.068498 -105.674632) (xy 39.068498 -105.653368) (xy 39.064692 -105.643426)
			(xy 39.046447 -105.600764) (xy 39.017903 -105.512471) (xy 38.99871 -105.421686) (xy 38.989077 -105.329396)
			(xy 38.988492 -105.283) (xy 38.989075 -105.236604) (xy 38.99872 -105.144316) (xy 39.017916 -105.053532)
			(xy 39.046454 -104.965239) (xy 39.064692 -104.922574) (xy 39.068498 -104.912632) (xy 39.068498 -104.891368)
			(xy 39.064692 -104.881426) (xy 39.046447 -104.838764) (xy 39.017903 -104.750471) (xy 38.99871 -104.659686)
			(xy 38.989077 -104.567396) (xy 38.988492 -104.521) (xy 38.989075 -104.474604) (xy 38.99872 -104.382316)
			(xy 39.017916 -104.291532) (xy 39.046454 -104.203239) (xy 39.064692 -104.160574) (xy 39.068498 -104.150632)
			(xy 39.068498 -104.129368) (xy 39.064692 -104.119426) (xy 39.046447 -104.076764) (xy 39.017903 -103.988471)
			(xy 38.99871 -103.897686) (xy 38.989077 -103.805396) (xy 38.988492 -103.759) (xy 38.988967 -103.717898)
			(xy 38.996552 -103.636043) (xy 39.011657 -103.555238) (xy 39.034153 -103.476171) (xy 39.063849 -103.399517)
			(xy 39.100491 -103.32593) (xy 39.143766 -103.256038) (xy 39.193306 -103.190437) (xy 39.248687 -103.129687)
			(xy 39.309437 -103.074306) (xy 39.375038 -103.024766) (xy 39.44493 -102.981491) (xy 39.518517 -102.944849)
			(xy 39.595171 -102.915153) (xy 39.674238 -102.892657) (xy 39.755043 -102.877552) (xy 39.836898 -102.869967)
			(xy 39.878 -102.869492) (xy 39.92179 -102.86998) (xy 40.008949 -102.878545) (xy 40.094843 -102.89564)
			(xy 40.17864 -102.921101) (xy 40.259526 -102.95468) (xy 40.29837 -102.974902) (xy 40.309836 -102.98032)
			(xy 40.335164 -102.98032) (xy 40.34663 -102.974902) (xy 40.385471 -102.954677) (xy 40.466366 -102.921126)
			(xy 40.550164 -102.89568) (xy 40.636056 -102.878584) (xy 40.723212 -102.870005) (xy 40.767 -102.869492)
			(xy 40.813379 -102.870097) (xy 40.905633 -102.879747) (xy 40.996382 -102.898942) (xy 41.084642 -102.927473)
			(xy 41.169455 -102.965032) (xy 41.209976 -102.987602) (xy 41.221253 -102.993254) (xy 41.246432 -102.993937)
			(xy 41.257982 -102.988872) (xy 41.295102 -102.970822) (xy 41.372033 -102.940898) (xy 41.451405 -102.918227)
			(xy 41.532535 -102.903004) (xy 41.614727 -102.89536) (xy 41.656 -102.894892) (xy 41.697102 -102.895367)
			(xy 41.778957 -102.902952) (xy 41.859762 -102.918057) (xy 41.938829 -102.940553) (xy 42.015483 -102.970249)
			(xy 42.08907 -103.006891) (xy 42.158962 -103.050166) (xy 42.224563 -103.099706) (xy 42.285313 -103.155087)
			(xy 42.340694 -103.215837) (xy 42.390234 -103.281438) (xy 42.433509 -103.35133) (xy 42.470151 -103.424917)
			(xy 42.499847 -103.501571) (xy 42.522343 -103.580638) (xy 42.537448 -103.661443) (xy 42.545033 -103.743298)
			(xy 42.545508 -103.7844) (xy 42.544925 -103.830796) (xy 42.53528 -103.923084) (xy 42.516084 -104.013868)
			(xy 42.487546 -104.102161) (xy 42.469308 -104.144826) (xy 42.465403 -104.154748) (xy 42.465403 -104.176052)
			(xy 42.469308 -104.185974) (xy 42.487553 -104.228636) (xy 42.516097 -104.316929) (xy 42.53529 -104.407714)
			(xy 42.544923 -104.500004) (xy 42.545508 -104.5464) (xy 42.544925 -104.592796) (xy 42.53528 -104.685084)
			(xy 42.516084 -104.775868) (xy 42.487546 -104.864161) (xy 42.469308 -104.906826) (xy 42.465403 -104.916748)
			(xy 42.465403 -104.938052) (xy 42.469308 -104.947974) (xy 42.487553 -104.990636) (xy 42.516097 -105.078929)
			(xy 42.53529 -105.169714) (xy 42.544923 -105.262004) (xy 42.545508 -105.3084) (xy 42.544925 -105.354796)
			(xy 42.53528 -105.447084) (xy 42.516084 -105.537868) (xy 42.487546 -105.626161) (xy 42.469308 -105.668826)
			(xy 42.465403 -105.678748) (xy 42.465403 -105.700052) (xy 42.469308 -105.709974) (xy 42.487553 -105.752636)
			(xy 42.516097 -105.840929) (xy 42.525034 -105.883202) (xy 201.446892 -105.883202) (xy 201.447476 -105.836806)
			(xy 201.45712 -105.744518) (xy 201.476316 -105.653734) (xy 201.504854 -105.565441) (xy 201.523092 -105.522776)
			(xy 201.526896 -105.512833) (xy 201.526897 -105.49157) (xy 201.523092 -105.481628) (xy 201.504848 -105.438966)
			(xy 201.476304 -105.350673) (xy 201.45711 -105.259888) (xy 201.447477 -105.167598) (xy 201.446892 -105.121202)
			(xy 201.447364 -105.078635) (xy 201.455472 -104.993887) (xy 201.471642 -104.910303) (xy 201.495727 -104.828647)
			(xy 201.511154 -104.78897) (xy 201.514396 -104.779715) (xy 201.514403 -104.760122) (xy 201.511154 -104.75087)
			(xy 201.495726 -104.711195) (xy 201.47165 -104.629536) (xy 201.455485 -104.545952) (xy 201.447378 -104.461205)
			(xy 201.446892 -104.418638) (xy 201.447488 -104.372243) (xy 201.457129 -104.279955) (xy 201.476321 -104.189171)
			(xy 201.504856 -104.100877) (xy 201.523092 -104.058212) (xy 201.526875 -104.048263) (xy 201.526889 -104.027006)
			(xy 201.523092 -104.017064) (xy 201.50486 -103.974397) (xy 201.476312 -103.886106) (xy 201.457116 -103.795323)
			(xy 201.447479 -103.703034) (xy 201.446892 -103.656638) (xy 201.447488 -103.610243) (xy 201.457129 -103.517955)
			(xy 201.476321 -103.427171) (xy 201.504856 -103.338877) (xy 201.523092 -103.296212) (xy 201.526875 -103.286263)
			(xy 201.526889 -103.265006) (xy 201.523092 -103.255064) (xy 201.50486 -103.212397) (xy 201.476312 -103.124106)
			(xy 201.457116 -103.033323) (xy 201.447479 -102.941034) (xy 201.446892 -102.894638) (xy 201.447449 -102.853533)
			(xy 201.455029 -102.771674) (xy 201.470129 -102.690863) (xy 201.492619 -102.61179) (xy 201.522308 -102.535128)
			(xy 201.558942 -102.461532) (xy 201.60221 -102.39163) (xy 201.651741 -102.326017) (xy 201.707115 -102.265254)
			(xy 201.767857 -102.209858) (xy 201.833451 -102.160301) (xy 201.903337 -102.117007) (xy 201.976919 -102.080345)
			(xy 202.053569 -102.050627) (xy 202.132634 -102.028106) (xy 202.213439 -102.012976) (xy 202.295295 -102.005364)
			(xy 202.3364 -102.004876) (xy 202.38045 -102.00545) (xy 202.468114 -102.014227) (xy 202.554483 -102.031616)
			(xy 202.638713 -102.057447) (xy 202.679554 -102.073964) (xy 202.688564 -102.077299) (xy 202.707756 -102.077697)
			(xy 202.716892 -102.074726) (xy 202.754276 -102.061238) (xy 202.83092 -102.040197) (xy 202.909137 -102.026086)
			(xy 202.988302 -102.019017) (xy 203.028042 -102.018592) (xy 203.074437 -102.019195) (xy 203.166725 -102.028834)
			(xy 203.257509 -102.048024) (xy 203.345803 -102.076557) (xy 203.388468 -102.094792) (xy 203.39841 -102.098598)
			(xy 203.419674 -102.098598) (xy 203.429616 -102.094792) (xy 203.472273 -102.076533) (xy 203.560567 -102.047993)
			(xy 203.651354 -102.028804) (xy 203.743645 -102.019175) (xy 203.790042 -102.018592) (xy 203.836437 -102.019195)
			(xy 203.928725 -102.028834) (xy 204.019509 -102.048024) (xy 204.107803 -102.076557) (xy 204.150468 -102.094792)
			(xy 204.16041 -102.098598) (xy 204.181674 -102.098598) (xy 204.191616 -102.094792) (xy 204.234273 -102.076533)
			(xy 204.322567 -102.047993) (xy 204.413354 -102.028804) (xy 204.505645 -102.019175) (xy 204.552042 -102.018592)
			(xy 204.598437 -102.019195) (xy 204.690725 -102.028834) (xy 204.781509 -102.048024) (xy 204.869803 -102.076557)
			(xy 204.912468 -102.094792) (xy 204.92241 -102.098598) (xy 204.943674 -102.098598) (xy 204.953616 -102.094792)
			(xy 204.996273 -102.076533) (xy 205.084567 -102.047993) (xy 205.175354 -102.028804) (xy 205.267645 -102.019175)
			(xy 205.314042 -102.018592) (xy 205.360437 -102.019195) (xy 205.452725 -102.028834) (xy 205.543509 -102.048024)
			(xy 205.631803 -102.076557) (xy 205.674468 -102.094792) (xy 205.68441 -102.098598) (xy 205.705674 -102.098598)
			(xy 205.715616 -102.094792) (xy 205.758273 -102.076533) (xy 205.846567 -102.047993) (xy 205.937354 -102.028804)
			(xy 206.029645 -102.019175) (xy 206.076042 -102.018592) (xy 206.122437 -102.019195) (xy 206.214725 -102.028834)
			(xy 206.305509 -102.048024) (xy 206.393803 -102.076557) (xy 206.436468 -102.094792) (xy 206.44641 -102.098598)
			(xy 206.467674 -102.098598) (xy 206.477616 -102.094792) (xy 206.520273 -102.076533) (xy 206.608567 -102.047993)
			(xy 206.699354 -102.028804) (xy 206.791645 -102.019175) (xy 206.838042 -102.018592) (xy 206.879551 -102.019069)
			(xy 206.962209 -102.026787) (xy 207.043788 -102.042181) (xy 207.123575 -102.065115) (xy 207.1624 -102.079806)
			(xy 207.171897 -102.08298) (xy 207.191897 -102.082587) (xy 207.201262 -102.079044) (xy 207.243424 -102.061305)
			(xy 207.330583 -102.033534) (xy 207.420131 -102.014855) (xy 207.511124 -102.005463) (xy 207.556862 -102.004876)
			(xy 207.597969 -102.005349) (xy 207.679833 -102.01293) (xy 207.760649 -102.028032) (xy 207.839727 -102.050525)
			(xy 207.916392 -102.080217) (xy 207.989991 -102.116856) (xy 208.059896 -102.160128) (xy 208.125511 -102.209665)
			(xy 208.186276 -102.265044) (xy 208.241672 -102.325793) (xy 208.291228 -102.391394) (xy 208.334521 -102.461287)
			(xy 208.37118 -102.534875) (xy 208.400895 -102.611532) (xy 208.42341 -102.690604) (xy 208.438535 -102.771415)
			(xy 208.446139 -102.853277) (xy 208.446624 -102.894384) (xy 208.446027 -102.940787) (xy 208.436328 -103.033085)
			(xy 208.417066 -103.12387) (xy 208.38845 -103.212155) (xy 208.37017 -103.25481) (xy 208.366371 -103.264755)
			(xy 208.366365 -103.286016) (xy 208.37017 -103.295958) (xy 208.388427 -103.338621) (xy 208.417021 -103.426908)
			(xy 208.43628 -103.51769) (xy 208.445994 -103.609983) (xy 208.446624 -103.656384) (xy 208.446027 -103.702787)
			(xy 208.436328 -103.795085) (xy 208.417066 -103.88587) (xy 208.38845 -103.974155) (xy 208.37017 -104.01681)
			(xy 208.366371 -104.026755) (xy 208.366365 -104.048016) (xy 208.37017 -104.057958) (xy 208.388427 -104.100621)
			(xy 208.417021 -104.188908) (xy 208.43628 -104.27969) (xy 208.445994 -104.371983) (xy 208.446624 -104.418384)
			(xy 208.446109 -104.460957) (xy 208.437948 -104.545711) (xy 208.421718 -104.629296) (xy 208.397568 -104.710946)
			(xy 208.382108 -104.750616) (xy 208.378875 -104.759874) (xy 208.378863 -104.779464) (xy 208.382108 -104.788716)
			(xy 208.39754 -104.828395) (xy 208.421676 -104.910046) (xy 208.43791 -104.993628) (xy 208.446096 -105.078377)
			(xy 208.446624 -105.120948) (xy 208.446014 -105.167351) (xy 208.436319 -105.259648) (xy 208.417061 -105.350434)
			(xy 208.388448 -105.438718) (xy 208.37017 -105.481374) (xy 208.366333 -105.491307) (xy 208.366351 -105.51258)
			(xy 208.37017 -105.522522) (xy 208.388448 -105.565176) (xy 208.417037 -105.653467) (xy 208.43629 -105.744252)
			(xy 208.445997 -105.836546) (xy 208.446624 -105.882948) (xy 208.446621 -105.883202) (xy 215.929464 -105.883202)
			(xy 215.930093 -105.8368) (xy 215.939782 -105.744503) (xy 215.959035 -105.653717) (xy 215.987643 -105.565432)
			(xy 216.005918 -105.522776) (xy 216.009721 -105.512833) (xy 216.009721 -105.49157) (xy 216.005918 -105.481628)
			(xy 215.987656 -105.438967) (xy 215.959063 -105.350679) (xy 215.939806 -105.259896) (xy 215.930093 -105.167603)
			(xy 215.929464 -105.121202) (xy 215.929976 -105.078629) (xy 215.938138 -104.993875) (xy 215.954369 -104.910289)
			(xy 215.978519 -104.82864) (xy 215.99398 -104.78897) (xy 215.997221 -104.779714) (xy 215.997228 -104.760122)
			(xy 215.99398 -104.75087) (xy 215.978542 -104.711193) (xy 215.954408 -104.629541) (xy 215.938175 -104.545959)
			(xy 215.929991 -104.461209) (xy 215.929464 -104.418638) (xy 215.93007 -104.372235) (xy 215.939766 -104.279937)
			(xy 215.959026 -104.189152) (xy 215.98764 -104.100867) (xy 216.005918 -104.058212) (xy 216.0097 -104.048263)
			(xy 216.009714 -104.027006) (xy 216.005918 -104.017064) (xy 215.987667 -103.974398) (xy 215.959071 -103.886112)
			(xy 215.939811 -103.795331) (xy 215.930095 -103.703039) (xy 215.929464 -103.656638) (xy 215.93007 -103.610235)
			(xy 215.939766 -103.517937) (xy 215.959026 -103.427152) (xy 215.98764 -103.338867) (xy 216.005918 -103.296212)
			(xy 216.0097 -103.286263) (xy 216.009714 -103.265006) (xy 216.005918 -103.255064) (xy 215.987667 -103.212398)
			(xy 215.959071 -103.124112) (xy 215.939811 -103.033331) (xy 215.930095 -102.941039) (xy 215.929464 -102.894638)
			(xy 215.929935 -102.853523) (xy 215.937519 -102.771643) (xy 215.952626 -102.690813) (xy 215.975127 -102.611721)
			(xy 216.00483 -102.535043) (xy 216.041481 -102.461433) (xy 216.084768 -102.391519) (xy 216.134322 -102.325897)
			(xy 216.18972 -102.265128) (xy 216.250488 -102.20973) (xy 216.316109 -102.160175) (xy 216.386023 -102.116887)
			(xy 216.459632 -102.080234) (xy 216.53631 -102.050531) (xy 216.615401 -102.028029) (xy 216.696232 -102.01292)
			(xy 216.778111 -102.005335) (xy 216.819226 -102.004876) (xy 216.863277 -102.005441) (xy 216.950941 -102.014221)
			(xy 217.03731 -102.031612) (xy 217.12154 -102.057446) (xy 217.16238 -102.073964) (xy 217.171386 -102.077313)
			(xy 217.190582 -102.077702) (xy 217.199718 -102.074726) (xy 217.237099 -102.061231) (xy 217.313744 -102.040192)
			(xy 217.391962 -102.026083) (xy 217.471128 -102.019016) (xy 217.510868 -102.018592) (xy 217.557263 -102.019186)
			(xy 217.649551 -102.028828) (xy 217.740335 -102.048021) (xy 217.828629 -102.076556) (xy 217.871294 -102.094792)
			(xy 217.881236 -102.098598) (xy 217.9025 -102.098598) (xy 217.912442 -102.094792) (xy 217.955109 -102.076558)
			(xy 218.043399 -102.048011) (xy 218.134183 -102.028815) (xy 218.226472 -102.019179) (xy 218.272868 -102.018592)
			(xy 218.319263 -102.019186) (xy 218.411551 -102.028828) (xy 218.502335 -102.048021) (xy 218.590629 -102.076556)
			(xy 218.633294 -102.094792) (xy 218.643236 -102.098598) (xy 218.6645 -102.098598) (xy 218.674442 -102.094792)
			(xy 218.717109 -102.076558) (xy 218.805399 -102.048011) (xy 218.896183 -102.028815) (xy 218.988472 -102.019179)
			(xy 219.034868 -102.018592) (xy 219.081263 -102.019186) (xy 219.173551 -102.028828) (xy 219.264335 -102.048021)
			(xy 219.352629 -102.076556) (xy 219.395294 -102.094792) (xy 219.405236 -102.098598) (xy 219.4265 -102.098598)
			(xy 219.436442 -102.094792) (xy 219.479109 -102.076558) (xy 219.567399 -102.048011) (xy 219.658183 -102.028815)
			(xy 219.750472 -102.019179) (xy 219.796868 -102.018592) (xy 219.843263 -102.019186) (xy 219.935551 -102.028828)
			(xy 220.026335 -102.048021) (xy 220.114629 -102.076556) (xy 220.157294 -102.094792) (xy 220.167236 -102.098598)
			(xy 220.1885 -102.098598) (xy 220.198442 -102.094792) (xy 220.241109 -102.076558) (xy 220.329399 -102.048011)
			(xy 220.420183 -102.028815) (xy 220.512472 -102.019179) (xy 220.558868 -102.018592) (xy 220.605263 -102.019186)
			(xy 220.697551 -102.028828) (xy 220.788335 -102.048021) (xy 220.876629 -102.076556) (xy 220.919294 -102.094792)
			(xy 220.929236 -102.098598) (xy 220.9505 -102.098598) (xy 220.960442 -102.094792) (xy 221.003109 -102.076558)
			(xy 221.091399 -102.048011) (xy 221.182183 -102.028815) (xy 221.274472 -102.019179) (xy 221.320868 -102.018592)
			(xy 221.362377 -102.01906) (xy 221.445036 -102.026781) (xy 221.526614 -102.042177) (xy 221.606401 -102.065114)
			(xy 221.645226 -102.079806) (xy 221.654719 -102.082995) (xy 221.674723 -102.082593) (xy 221.684088 -102.079044)
			(xy 221.726247 -102.061296) (xy 221.813407 -102.033528) (xy 221.902956 -102.014851) (xy 221.99395 -102.005462)
			(xy 222.039688 -102.004876) (xy 222.08079 -102.005378) (xy 222.162643 -102.012962) (xy 222.243447 -102.028065)
			(xy 222.322513 -102.05056) (xy 222.399166 -102.080255) (xy 222.472752 -102.116895) (xy 222.542644 -102.160169)
			(xy 222.608245 -102.209706) (xy 222.668995 -102.265086) (xy 222.724376 -102.325834) (xy 222.773916 -102.391433)
			(xy 222.817191 -102.461323) (xy 222.853834 -102.534908) (xy 222.883531 -102.61156) (xy 222.906028 -102.690626)
			(xy 222.921134 -102.771429) (xy 222.928721 -102.853282) (xy 222.929196 -102.894384) (xy 222.928609 -102.940779)
			(xy 222.918965 -103.033068) (xy 222.89977 -103.123852) (xy 222.871233 -103.212145) (xy 222.852996 -103.25481)
			(xy 222.849201 -103.264755) (xy 222.849195 -103.286016) (xy 222.852996 -103.295958) (xy 222.871235 -103.338623)
			(xy 222.899781 -103.426914) (xy 222.918975 -103.517698) (xy 222.92861 -103.609988) (xy 222.929196 -103.656384)
			(xy 222.928609 -103.702779) (xy 222.918965 -103.795068) (xy 222.89977 -103.885852) (xy 222.871233 -103.974145)
			(xy 222.852996 -104.01681) (xy 222.849201 -104.026755) (xy 222.849195 -104.048016) (xy 222.852996 -104.057958)
			(xy 222.871235 -104.100623) (xy 222.899781 -104.188914) (xy 222.918975 -104.279698) (xy 222.92861 -104.371988)
			(xy 222.929196 -104.418384) (xy 222.928713 -104.460951) (xy 222.920608 -104.545698) (xy 222.90444 -104.629282)
			(xy 222.880359 -104.710939) (xy 222.864934 -104.750616) (xy 222.8617 -104.759874) (xy 222.861688 -104.779464)
			(xy 222.864934 -104.788716) (xy 222.880357 -104.828393) (xy 222.904434 -104.910051) (xy 222.908221 -104.929629)
			(xy 270.263616 -104.929629) (xy 270.263616 -104.844907) (xy 270.271669 -104.76057) (xy 270.287703 -104.67738)
			(xy 270.311571 -104.59609) (xy 270.343059 -104.517438) (xy 270.381881 -104.442135) (xy 270.427684 -104.370863)
			(xy 270.480055 -104.304267) (xy 270.53852 -104.242952) (xy 270.602548 -104.187471) (xy 270.67156 -104.138328)
			(xy 270.74493 -104.095968) (xy 270.821995 -104.060773) (xy 270.902057 -104.033064) (xy 270.98439 -104.01309)
			(xy 271.068249 -104.001033) (xy 271.152874 -103.997002) (xy 271.237499 -104.001033) (xy 271.321358 -104.01309)
			(xy 271.403691 -104.033064) (xy 271.483753 -104.060773) (xy 271.560818 -104.095968) (xy 271.634188 -104.138328)
			(xy 271.7032 -104.187471) (xy 271.767228 -104.242952) (xy 271.825693 -104.304267) (xy 271.878064 -104.370863)
			(xy 271.923867 -104.442135) (xy 271.962689 -104.517438) (xy 271.994177 -104.59609) (xy 272.018045 -104.67738)
			(xy 272.034079 -104.76057) (xy 272.042132 -104.844907) (xy 272.042636 -104.887268) (xy 272.042132 -104.929629)
			(xy 272.034079 -105.013966) (xy 272.018045 -105.097156) (xy 271.994177 -105.178446) (xy 271.962689 -105.257098)
			(xy 271.923867 -105.332401) (xy 271.878064 -105.403673) (xy 271.825693 -105.470269) (xy 271.767228 -105.531584)
			(xy 271.7032 -105.587065) (xy 271.634188 -105.636208) (xy 271.560818 -105.678568) (xy 271.483753 -105.713763)
			(xy 271.403691 -105.741472) (xy 271.321358 -105.761446) (xy 271.237499 -105.773503) (xy 271.152874 -105.777535)
			(xy 271.068249 -105.773503) (xy 270.98439 -105.761446) (xy 270.902057 -105.741472) (xy 270.821995 -105.713763)
			(xy 270.74493 -105.678568) (xy 270.67156 -105.636208) (xy 270.602548 -105.587065) (xy 270.53852 -105.531584)
			(xy 270.480055 -105.470269) (xy 270.427684 -105.403673) (xy 270.381881 -105.332401) (xy 270.343059 -105.257098)
			(xy 270.311571 -105.178446) (xy 270.287703 -105.097156) (xy 270.271669 -105.013966) (xy 270.263616 -104.929629)
			(xy 222.908221 -104.929629) (xy 222.920601 -104.993635) (xy 222.92871 -105.078381) (xy 222.929196 -105.120948)
			(xy 222.928596 -105.167343) (xy 222.918956 -105.259631) (xy 222.899765 -105.350415) (xy 222.871232 -105.438709)
			(xy 222.852996 -105.481374) (xy 222.849163 -105.491308) (xy 222.849181 -105.512579) (xy 222.852996 -105.522522)
			(xy 222.871223 -105.565192) (xy 222.899772 -105.653481) (xy 222.91897 -105.744264) (xy 222.928608 -105.836553)
			(xy 222.929196 -105.882948) (xy 222.928779 -105.924052) (xy 222.92119 -106.005908) (xy 222.90608 -106.086715)
			(xy 222.883579 -106.165783) (xy 222.853879 -106.242437) (xy 222.817233 -106.316025) (xy 222.773954 -106.385917)
			(xy 222.761182 -106.402829) (xy 268.600678 -106.402829) (xy 268.600678 -106.318107) (xy 268.608731 -106.23377)
			(xy 268.624765 -106.15058) (xy 268.648633 -106.06929) (xy 268.680121 -105.990638) (xy 268.718943 -105.915335)
			(xy 268.764746 -105.844063) (xy 268.817117 -105.777467) (xy 268.875582 -105.716152) (xy 268.93961 -105.660671)
			(xy 269.008622 -105.611528) (xy 269.081992 -105.569168) (xy 269.159057 -105.533973) (xy 269.239119 -105.506264)
			(xy 269.321452 -105.48629) (xy 269.405311 -105.474233) (xy 269.489936 -105.470202) (xy 269.574561 -105.474233)
			(xy 269.65842 -105.48629) (xy 269.740753 -105.506264) (xy 269.820815 -105.533973) (xy 269.89788 -105.569168)
			(xy 269.97125 -105.611528) (xy 270.040262 -105.660671) (xy 270.10429 -105.716152) (xy 270.162755 -105.777467)
			(xy 270.215126 -105.844063) (xy 270.260929 -105.915335) (xy 270.299751 -105.990638) (xy 270.331239 -106.06929)
			(xy 270.355107 -106.15058) (xy 270.371141 -106.23377) (xy 270.379194 -106.318107) (xy 270.379698 -106.360468)
			(xy 270.379194 -106.402829) (xy 270.371141 -106.487166) (xy 270.355107 -106.570356) (xy 270.331239 -106.651646)
			(xy 270.299751 -106.730298) (xy 270.260929 -106.805601) (xy 270.215126 -106.876873) (xy 270.162755 -106.943469)
			(xy 270.10429 -107.004784) (xy 270.040262 -107.060265) (xy 269.97125 -107.109408) (xy 269.89788 -107.151768)
			(xy 269.820815 -107.186963) (xy 269.740753 -107.214672) (xy 269.65842 -107.234646) (xy 269.574561 -107.246703)
			(xy 269.489936 -107.250735) (xy 269.405311 -107.246703) (xy 269.321452 -107.234646) (xy 269.239119 -107.214672)
			(xy 269.159057 -107.186963) (xy 269.081992 -107.151768) (xy 269.008622 -107.109408) (xy 268.93961 -107.060265)
			(xy 268.875582 -107.004784) (xy 268.817117 -106.943469) (xy 268.764746 -106.876873) (xy 268.718943 -106.805601)
			(xy 268.680121 -106.730298) (xy 268.648633 -106.651646) (xy 268.624765 -106.570356) (xy 268.608731 -106.487166)
			(xy 268.600678 -106.402829) (xy 222.761182 -106.402829) (xy 222.724411 -106.451518) (xy 222.669026 -106.512268)
			(xy 222.608272 -106.567649) (xy 222.542668 -106.617188) (xy 222.472772 -106.660463) (xy 222.399183 -106.697104)
			(xy 222.322526 -106.726799) (xy 222.243456 -106.749294) (xy 222.162648 -106.764398) (xy 222.080792 -106.771982)
			(xy 222.039688 -106.772456) (xy 221.998179 -106.771973) (xy 221.915521 -106.764257) (xy 221.833943 -106.748865)
			(xy 221.754155 -106.725932) (xy 221.71533 -106.711242) (xy 221.705829 -106.708082) (xy 221.685833 -106.708464)
			(xy 221.676468 -106.712004) (xy 221.634314 -106.729763) (xy 221.547152 -106.757529) (xy 221.457601 -106.776203)
			(xy 221.366607 -106.785588) (xy 221.320868 -106.786172) (xy 221.274473 -106.785568) (xy 221.182185 -106.77593)
			(xy 221.091401 -106.75674) (xy 221.003107 -106.728207) (xy 220.960442 -106.709972) (xy 220.9505 -106.706166)
			(xy 220.929236 -106.706166) (xy 220.919294 -106.709972) (xy 220.876635 -106.728225) (xy 220.788342 -106.756768)
			(xy 220.697556 -106.775958) (xy 220.605264 -106.785589) (xy 220.558868 -106.786172) (xy 220.512473 -106.785568)
			(xy 220.420185 -106.77593) (xy 220.329401 -106.75674) (xy 220.241107 -106.728207) (xy 220.198442 -106.709972)
			(xy 220.1885 -106.706166) (xy 220.167236 -106.706166) (xy 220.157294 -106.709972) (xy 220.114635 -106.728225)
			(xy 220.026342 -106.756768) (xy 219.935556 -106.775958) (xy 219.843264 -106.785589) (xy 219.796868 -106.786172)
			(xy 219.750473 -106.785568) (xy 219.658185 -106.77593) (xy 219.567401 -106.75674) (xy 219.479107 -106.728207)
			(xy 219.436442 -106.709972) (xy 219.4265 -106.706166) (xy 219.405236 -106.706166) (xy 219.395294 -106.709972)
			(xy 219.352635 -106.728225) (xy 219.264342 -106.756768) (xy 219.173556 -106.775958) (xy 219.081264 -106.785589)
			(xy 219.034868 -106.786172) (xy 218.988473 -106.785568) (xy 218.896185 -106.77593) (xy 218.805401 -106.75674)
			(xy 218.717107 -106.728207) (xy 218.674442 -106.709972) (xy 218.6645 -106.706166) (xy 218.643236 -106.706166)
			(xy 218.633294 -106.709972) (xy 218.590635 -106.728225) (xy 218.502342 -106.756768) (xy 218.411556 -106.775958)
			(xy 218.319264 -106.785589) (xy 218.272868 -106.786172) (xy 218.226473 -106.785568) (xy 218.134185 -106.77593)
			(xy 218.043401 -106.75674) (xy 217.955107 -106.728207) (xy 217.912442 -106.709972) (xy 217.9025 -106.706166)
			(xy 217.881236 -106.706166) (xy 217.871294 -106.709972) (xy 217.828635 -106.728225) (xy 217.740342 -106.756768)
			(xy 217.649556 -106.775958) (xy 217.557264 -106.785589) (xy 217.510868 -106.786172) (xy 217.466823 -106.785646)
			(xy 217.379163 -106.776938) (xy 217.292793 -106.759609) (xy 217.208558 -106.733831) (xy 217.167714 -106.717338)
			(xy 217.158709 -106.713986) (xy 217.139512 -106.713599) (xy 217.130376 -106.716576) (xy 217.093 -106.7301)
			(xy 217.016359 -106.751198) (xy 216.938142 -106.765371) (xy 216.858971 -106.772505) (xy 216.819226 -106.772964)
			(xy 216.778112 -106.772477) (xy 216.696233 -106.764892) (xy 216.615404 -106.749785) (xy 216.536314 -106.727283)
			(xy 216.459637 -106.697581) (xy 216.386028 -106.66093) (xy 216.316115 -106.617643) (xy 216.250494 -106.568091)
			(xy 216.189725 -106.512694) (xy 216.134327 -106.451927) (xy 216.084773 -106.386308) (xy 216.041484 -106.316396)
			(xy 216.004831 -106.242788) (xy 215.975125 -106.166113) (xy 215.952622 -106.087023) (xy 215.937512 -106.006194)
			(xy 215.929925 -105.924316) (xy 215.929464 -105.883202) (xy 208.446621 -105.883202) (xy 208.446193 -105.924059)
			(xy 208.438601 -106.00593) (xy 208.423487 -106.08675) (xy 208.400978 -106.165831) (xy 208.371268 -106.242498)
			(xy 208.33461 -106.316096) (xy 208.291317 -106.385997) (xy 208.241758 -106.451604) (xy 208.186356 -106.512358)
			(xy 208.125584 -106.567741) (xy 208.059961 -106.617279) (xy 207.990046 -106.66055) (xy 207.916436 -106.697184)
			(xy 207.83976 -106.726869) (xy 207.760672 -106.749352) (xy 207.679846 -106.764441) (xy 207.597973 -106.772007)
			(xy 207.556862 -106.772456) (xy 207.515353 -106.771982) (xy 207.432694 -106.764263) (xy 207.351116 -106.748869)
			(xy 207.271329 -106.725933) (xy 207.232504 -106.711242) (xy 207.223007 -106.708067) (xy 207.203007 -106.708459)
			(xy 207.193642 -106.712004) (xy 207.151478 -106.729739) (xy 207.06432 -106.757511) (xy 206.974772 -106.776192)
			(xy 206.88378 -106.785585) (xy 206.838042 -106.786172) (xy 206.791647 -106.785577) (xy 206.699359 -106.775936)
			(xy 206.608575 -106.756744) (xy 206.520281 -106.728209) (xy 206.477616 -106.709972) (xy 206.467674 -106.706166)
			(xy 206.44641 -106.706166) (xy 206.436468 -106.709972) (xy 206.393799 -106.728201) (xy 206.305509 -106.756749)
			(xy 206.214726 -106.775947) (xy 206.122438 -106.785585) (xy 206.076042 -106.786172) (xy 206.029647 -106.785577)
			(xy 205.937359 -106.775936) (xy 205.846575 -106.756744) (xy 205.758281 -106.728209) (xy 205.715616 -106.709972)
			(xy 205.705674 -106.706166) (xy 205.68441 -106.706166) (xy 205.674468 -106.709972) (xy 205.631799 -106.728201)
			(xy 205.543509 -106.756749) (xy 205.452726 -106.775947) (xy 205.360438 -106.785585) (xy 205.314042 -106.786172)
			(xy 205.267647 -106.785577) (xy 205.175359 -106.775936) (xy 205.084575 -106.756744) (xy 204.996281 -106.728209)
			(xy 204.953616 -106.709972) (xy 204.943674 -106.706166) (xy 204.92241 -106.706166) (xy 204.912468 -106.709972)
			(xy 204.869799 -106.728201) (xy 204.781509 -106.756749) (xy 204.690726 -106.775947) (xy 204.598438 -106.785585)
			(xy 204.552042 -106.786172) (xy 204.505647 -106.785577) (xy 204.413359 -106.775936) (xy 204.322575 -106.756744)
			(xy 204.234281 -106.728209) (xy 204.191616 -106.709972) (xy 204.181674 -106.706166) (xy 204.16041 -106.706166)
			(xy 204.150468 -106.709972) (xy 204.107799 -106.728201) (xy 204.019509 -106.756749) (xy 203.928726 -106.775947)
			(xy 203.836438 -106.785585) (xy 203.790042 -106.786172) (xy 203.743647 -106.785577) (xy 203.651359 -106.775936)
			(xy 203.560575 -106.756744) (xy 203.472281 -106.728209) (xy 203.429616 -106.709972) (xy 203.419674 -106.706166)
			(xy 203.39841 -106.706166) (xy 203.388468 -106.709972) (xy 203.345799 -106.728201) (xy 203.257509 -106.756749)
			(xy 203.166726 -106.775947) (xy 203.074438 -106.785585) (xy 203.028042 -106.786172) (xy 202.983997 -106.785621)
			(xy 202.896338 -106.77692) (xy 202.809969 -106.759599) (xy 202.725733 -106.733828) (xy 202.684888 -106.717338)
			(xy 202.675887 -106.713972) (xy 202.656687 -106.713594) (xy 202.64755 -106.716576) (xy 202.610166 -106.730079)
			(xy 202.533529 -106.751183) (xy 202.455313 -106.765361) (xy 202.376145 -106.772501) (xy 202.3364 -106.772964)
			(xy 202.295288 -106.772547) (xy 202.213415 -106.764959) (xy 202.132592 -106.749847) (xy 202.053508 -106.727341)
			(xy 201.976839 -106.697632) (xy 201.903239 -106.660975) (xy 201.833336 -106.617681) (xy 201.767727 -106.568121)
			(xy 201.706971 -106.512718) (xy 201.651588 -106.451944) (xy 201.60205 -106.386318) (xy 201.55878 -106.316401)
			(xy 201.522147 -106.242788) (xy 201.492464 -106.166109) (xy 201.469984 -106.087018) (xy 201.4549 -106.00619)
			(xy 201.447339 -105.924314) (xy 201.446892 -105.883202) (xy 42.525034 -105.883202) (xy 42.53529 -105.931714)
			(xy 42.544923 -106.024004) (xy 42.545508 -106.0704) (xy 42.544925 -106.116796) (xy 42.53528 -106.209084)
			(xy 42.516084 -106.299868) (xy 42.487546 -106.388161) (xy 42.469308 -106.430826) (xy 42.465403 -106.440748)
			(xy 42.465403 -106.462052) (xy 42.469308 -106.471974) (xy 42.487553 -106.514636) (xy 42.516097 -106.602929)
			(xy 42.53529 -106.693714) (xy 42.544923 -106.786004) (xy 42.545508 -106.8324) (xy 42.544974 -106.876652)
			(xy 42.53619 -106.964719) (xy 42.51871 -107.05148) (xy 42.492705 -107.136077) (xy 42.458433 -107.217676)
			(xy 42.437812 -107.256834) (xy 42.432976 -107.266759) (xy 42.431544 -107.28877) (xy 42.435018 -107.299252)
			(xy 42.449342 -107.337668) (xy 42.471714 -107.416549) (xy 42.486727 -107.497156) (xy 42.494251 -107.578803)
			(xy 42.494708 -107.6198) (xy 42.494125 -107.666196) (xy 42.48448 -107.758484) (xy 42.465284 -107.849268)
			(xy 42.436746 -107.937561) (xy 42.418508 -107.980226) (xy 42.414603 -107.990148) (xy 42.414603 -108.011452)
			(xy 42.418508 -108.021374) (xy 42.436753 -108.064036) (xy 42.465297 -108.152329) (xy 42.48449 -108.243114)
			(xy 42.494123 -108.335404) (xy 42.494708 -108.3818) (xy 42.494233 -108.422902) (xy 42.486648 -108.504757)
			(xy 42.471543 -108.585562) (xy 42.449047 -108.664629) (xy 42.419351 -108.741283) (xy 42.382709 -108.81487)
			(xy 42.339434 -108.884762) (xy 42.289894 -108.950363) (xy 42.234513 -109.011113) (xy 42.173763 -109.066494)
			(xy 42.108162 -109.116034) (xy 42.03827 -109.159309) (xy 41.964683 -109.195951) (xy 41.888029 -109.225647)
			(xy 41.808962 -109.248143) (xy 41.728157 -109.263248) (xy 41.646302 -109.270833) (xy 41.6052 -109.271308)
			(xy 41.558821 -109.270703) (xy 41.466567 -109.261053) (xy 41.375818 -109.241858) (xy 41.287558 -109.213327)
			(xy 41.202745 -109.175768) (xy 41.162224 -109.153198) (xy 41.150947 -109.147546) (xy 41.125768 -109.146863)
			(xy 41.114218 -109.151928) (xy 41.077098 -109.169978) (xy 41.000167 -109.199902) (xy 40.920795 -109.222573)
			(xy 40.839665 -109.237796) (xy 40.757473 -109.24544) (xy 40.7162 -109.245908) (xy 40.672407 -109.245348)
			(xy 40.585246 -109.236718) (xy 40.499354 -109.219572) (xy 40.41556 -109.194075) (xy 40.334675 -109.160474)
			(xy 40.29583 -109.140244) (xy 40.284364 -109.134826) (xy 40.259036 -109.134826) (xy 40.24757 -109.140244)
			(xy 40.208728 -109.160483) (xy 40.127852 -109.194119) (xy 40.044059 -109.219632) (xy 39.958163 -109.236777)
			(xy 39.870996 -109.245387) (xy 39.8272 -109.245908) (xy 39.786098 -109.245433) (xy 39.704243 -109.237848)
			(xy 39.623438 -109.222743) (xy 39.544371 -109.200247) (xy 39.467717 -109.170551) (xy 39.39413 -109.133909)
			(xy 39.324238 -109.090634) (xy 39.258637 -109.041094) (xy 39.197887 -108.985713) (xy 39.142506 -108.924963)
			(xy 39.092966 -108.859362) (xy 39.049691 -108.78947) (xy 39.013049 -108.715883) (xy 38.983353 -108.639229)
			(xy 38.960857 -108.560162) (xy 38.945752 -108.479357) (xy 38.938167 -108.397502) (xy 38.937692 -108.3564)
			(xy 32.131508 -108.3564) (xy 32.131033 -108.397502) (xy 32.123448 -108.479357) (xy 32.108343 -108.560162)
			(xy 32.085847 -108.639229) (xy 32.056151 -108.715883) (xy 32.019509 -108.78947) (xy 31.976234 -108.859362)
			(xy 31.926694 -108.924963) (xy 31.871313 -108.985713) (xy 31.810563 -109.041094) (xy 31.744962 -109.090634)
			(xy 31.67507 -109.133909) (xy 31.601483 -109.170551) (xy 31.524829 -109.200247) (xy 31.445762 -109.222743)
			(xy 31.364957 -109.237848) (xy 31.283102 -109.245433) (xy 31.242 -109.245908) (xy 31.198207 -109.245348)
			(xy 31.111046 -109.236718) (xy 31.025154 -109.219572) (xy 30.94136 -109.194075) (xy 30.860475 -109.160474)
			(xy 30.82163 -109.140244) (xy 30.810164 -109.134826) (xy 30.784836 -109.134826) (xy 30.77337 -109.140244)
			(xy 30.734528 -109.160483) (xy 30.653652 -109.194119) (xy 30.569859 -109.219632) (xy 30.483963 -109.236777)
			(xy 30.396796 -109.245387) (xy 30.353 -109.245908) (xy 30.307377 -109.245294) (xy 30.216612 -109.235924)
			(xy 30.127284 -109.217312) (xy 30.040329 -109.189655) (xy 29.956662 -109.153242) (xy 29.916628 -109.131354)
			(xy 29.908405 -109.127232) (xy 29.890238 -109.12446) (xy 29.872258 -109.128261) (xy 29.864304 -109.132878)
			(xy 29.82866 -109.154937) (xy 29.753965 -109.19299) (xy 29.67602 -109.223846) (xy 29.595518 -109.247231)
			(xy 29.513173 -109.262937) (xy 29.429715 -109.270825) (xy 29.3878 -109.271308) (xy 29.346698 -109.270833)
			(xy 29.264843 -109.263248) (xy 29.184038 -109.248143) (xy 29.104971 -109.225647) (xy 29.028317 -109.195951)
			(xy 28.95473 -109.159309) (xy 28.884838 -109.116034) (xy 28.819237 -109.066494) (xy 28.758487 -109.011113)
			(xy 28.703106 -108.950363) (xy 28.653566 -108.884762) (xy 28.610291 -108.81487) (xy 28.573649 -108.741283)
			(xy 28.543953 -108.664629) (xy 28.521457 -108.585562) (xy 28.506352 -108.504757) (xy 28.498767 -108.422902)
			(xy 28.498292 -108.3818) (xy 0.509016 -108.3818) (xy 0.509016 -112.268) (xy 141.857988 -112.268)
			(xy 141.862018 -112.183399) (xy 141.874071 -112.099564) (xy 141.894039 -112.017255) (xy 141.921741 -111.937216)
			(xy 141.956925 -111.860173) (xy 141.999274 -111.786823) (xy 142.048403 -111.717831) (xy 142.103868 -111.653821)
			(xy 142.165166 -111.595373) (xy 142.231742 -111.543017) (xy 142.302994 -111.497227) (xy 142.378275 -111.458416)
			(xy 142.456905 -111.426937) (xy 142.538172 -111.403076) (xy 142.621338 -111.387047) (xy 142.705652 -111.378996)
			(xy 142.748 -111.378492) (xy 142.786284 -111.37888) (xy 142.862573 -111.385419) (xy 142.938015 -111.3985)
			(xy 143.012052 -111.418027) (xy 143.048228 -111.430562) (xy 143.056665 -111.433213) (xy 143.074335 -111.433213)
			(xy 143.082772 -111.430562) (xy 143.11895 -111.418037) (xy 143.19299 -111.398529) (xy 143.268431 -111.385449)
			(xy 143.344717 -111.378894) (xy 143.383 -111.378492) (xy 143.425348 -111.378996) (xy 143.509662 -111.387047)
			(xy 143.592828 -111.403076) (xy 143.674095 -111.426937) (xy 143.752725 -111.458416) (xy 143.828006 -111.497227)
			(xy 143.899258 -111.543017) (xy 143.965834 -111.595373) (xy 144.027132 -111.653821) (xy 144.082597 -111.717831)
			(xy 144.131726 -111.786823) (xy 144.174075 -111.860173) (xy 144.209259 -111.937216) (xy 144.236961 -112.017255)
			(xy 144.256929 -112.099564) (xy 144.268982 -112.183399) (xy 144.273013 -112.268) (xy 144.268982 -112.352601)
			(xy 144.256929 -112.436436) (xy 144.236961 -112.518745) (xy 144.209259 -112.598784) (xy 144.174075 -112.675827)
			(xy 144.131726 -112.749177) (xy 144.082597 -112.818169) (xy 144.027132 -112.882179) (xy 143.965834 -112.940627)
			(xy 143.899258 -112.992983) (xy 143.828006 -113.038773) (xy 143.752725 -113.077584) (xy 143.674095 -113.109063)
			(xy 143.592828 -113.132924) (xy 143.509662 -113.148953) (xy 143.425348 -113.157004) (xy 143.383 -113.157508)
			(xy 143.344716 -113.15712) (xy 143.268427 -113.150581) (xy 143.192985 -113.1375) (xy 143.118948 -113.117973)
			(xy 143.082772 -113.105438) (xy 143.074335 -113.102787) (xy 143.056665 -113.102787) (xy 143.048228 -113.105438)
			(xy 143.01205 -113.117963) (xy 142.93801 -113.137471) (xy 142.862569 -113.150551) (xy 142.786283 -113.157106)
			(xy 142.748 -113.157508) (xy 142.705652 -113.157004) (xy 142.621338 -113.148953) (xy 142.538172 -113.132924)
			(xy 142.456905 -113.109063) (xy 142.378275 -113.077584) (xy 142.302994 -113.038773) (xy 142.231742 -112.992983)
			(xy 142.165166 -112.940627) (xy 142.103868 -112.882179) (xy 142.048403 -112.818169) (xy 141.999274 -112.749177)
			(xy 141.956925 -112.675827) (xy 141.921741 -112.598784) (xy 141.894039 -112.518745) (xy 141.874071 -112.436436)
			(xy 141.862018 -112.352601) (xy 141.857988 -112.268) (xy 0.509016 -112.268) (xy 0.509016 -113.229898)
			(xy 0.509506 -113.299774) (xy 0.517342 -113.439307) (xy 0.53299 -113.578181) (xy 0.556399 -113.715959)
			(xy 0.573755 -113.792) (xy 268.350492 -113.792) (xy 268.351075 -113.745604) (xy 268.36072 -113.653316)
			(xy 268.379916 -113.562532) (xy 268.408454 -113.474239) (xy 268.426692 -113.431574) (xy 268.430498 -113.421632)
			(xy 268.430498 -113.400368) (xy 268.426692 -113.390426) (xy 268.408447 -113.347764) (xy 268.379903 -113.259471)
			(xy 268.36071 -113.168686) (xy 268.351077 -113.076396) (xy 268.350492 -113.03) (xy 268.351075 -112.983604)
			(xy 268.36072 -112.891316) (xy 268.379916 -112.800532) (xy 268.408454 -112.712239) (xy 268.426692 -112.669574)
			(xy 268.430498 -112.659632) (xy 268.430498 -112.638368) (xy 268.426692 -112.628426) (xy 268.408447 -112.585764)
			(xy 268.379903 -112.497471) (xy 268.36071 -112.406686) (xy 268.351077 -112.314396) (xy 268.350492 -112.268)
			(xy 268.351075 -112.221604) (xy 268.36072 -112.129316) (xy 268.379916 -112.038532) (xy 268.408454 -111.950239)
			(xy 268.426692 -111.907574) (xy 268.430498 -111.897632) (xy 268.430498 -111.876368) (xy 268.426692 -111.866426)
			(xy 268.408447 -111.823764) (xy 268.379903 -111.735471) (xy 268.36071 -111.644686) (xy 268.351077 -111.552396)
			(xy 268.350492 -111.506) (xy 268.351075 -111.459604) (xy 268.36072 -111.367316) (xy 268.379916 -111.276532)
			(xy 268.408454 -111.188239) (xy 268.426692 -111.145574) (xy 268.430498 -111.135632) (xy 268.430498 -111.114368)
			(xy 268.426692 -111.104426) (xy 268.408447 -111.061764) (xy 268.379903 -110.973471) (xy 268.36071 -110.882686)
			(xy 268.351077 -110.790396) (xy 268.350492 -110.744) (xy 268.351075 -110.697604) (xy 268.36072 -110.605316)
			(xy 268.379916 -110.514532) (xy 268.408454 -110.426239) (xy 268.426692 -110.383574) (xy 268.430498 -110.373632)
			(xy 268.430498 -110.352368) (xy 268.426692 -110.342426) (xy 268.408447 -110.299764) (xy 268.379903 -110.211471)
			(xy 268.36071 -110.120686) (xy 268.351077 -110.028396) (xy 268.350492 -109.982) (xy 268.350967 -109.940898)
			(xy 268.358552 -109.859043) (xy 268.373657 -109.778238) (xy 268.396153 -109.699171) (xy 268.425849 -109.622517)
			(xy 268.462491 -109.54893) (xy 268.505766 -109.479038) (xy 268.555306 -109.413437) (xy 268.610687 -109.352687)
			(xy 268.671437 -109.297306) (xy 268.737038 -109.247766) (xy 268.80693 -109.204491) (xy 268.880517 -109.167849)
			(xy 268.957171 -109.138153) (xy 269.036238 -109.115657) (xy 269.117043 -109.100552) (xy 269.198898 -109.092967)
			(xy 269.24 -109.092492) (xy 269.286396 -109.093075) (xy 269.378684 -109.10272) (xy 269.469468 -109.121916)
			(xy 269.557761 -109.150454) (xy 269.600426 -109.168692) (xy 269.610368 -109.172498) (xy 269.631632 -109.172498)
			(xy 269.641574 -109.168692) (xy 269.684236 -109.150447) (xy 269.772529 -109.121903) (xy 269.863314 -109.10271)
			(xy 269.955604 -109.093077) (xy 270.002 -109.092492) (xy 270.048396 -109.093075) (xy 270.140684 -109.10272)
			(xy 270.231468 -109.121916) (xy 270.319761 -109.150454) (xy 270.362426 -109.168692) (xy 270.372368 -109.172498)
			(xy 270.393632 -109.172498) (xy 270.403574 -109.168692) (xy 270.446236 -109.150447) (xy 270.534529 -109.121903)
			(xy 270.625314 -109.10271) (xy 270.717604 -109.093077) (xy 270.764 -109.092492) (xy 270.810396 -109.093075)
			(xy 270.902684 -109.10272) (xy 270.993468 -109.121916) (xy 271.081761 -109.150454) (xy 271.124426 -109.168692)
			(xy 271.134368 -109.172498) (xy 271.155632 -109.172498) (xy 271.165574 -109.168692) (xy 271.208236 -109.150447)
			(xy 271.296529 -109.121903) (xy 271.387314 -109.10271) (xy 271.479604 -109.093077) (xy 271.526 -109.092492)
			(xy 271.572396 -109.093075) (xy 271.664684 -109.10272) (xy 271.755468 -109.121916) (xy 271.843761 -109.150454)
			(xy 271.886426 -109.168692) (xy 271.896368 -109.172498) (xy 271.917632 -109.172498) (xy 271.927574 -109.168692)
			(xy 271.970236 -109.150447) (xy 272.058529 -109.121903) (xy 272.149314 -109.10271) (xy 272.241604 -109.093077)
			(xy 272.288 -109.092492) (xy 272.329102 -109.092967) (xy 272.410957 -109.100552) (xy 272.491762 -109.115657)
			(xy 272.570829 -109.138153) (xy 272.647483 -109.167849) (xy 272.72107 -109.204491) (xy 272.790962 -109.247766)
			(xy 272.856563 -109.297306) (xy 272.917313 -109.352687) (xy 272.972694 -109.413437) (xy 273.022234 -109.479038)
			(xy 273.065509 -109.54893) (xy 273.102151 -109.622517) (xy 273.131847 -109.699171) (xy 273.154343 -109.778238)
			(xy 273.169448 -109.859043) (xy 273.177033 -109.940898) (xy 273.177508 -109.982) (xy 273.176925 -110.028396)
			(xy 273.16728 -110.120684) (xy 273.148084 -110.211468) (xy 273.119546 -110.299761) (xy 273.101308 -110.342426)
			(xy 273.097502 -110.352368) (xy 273.097502 -110.373632) (xy 273.101308 -110.383574) (xy 273.119553 -110.426236)
			(xy 273.148097 -110.514529) (xy 273.16729 -110.605314) (xy 273.176923 -110.697604) (xy 273.177508 -110.744)
			(xy 273.177033 -110.785102) (xy 273.169448 -110.866957) (xy 273.154343 -110.947762) (xy 273.131847 -111.026829)
			(xy 273.102151 -111.103483) (xy 273.065509 -111.17707) (xy 273.022234 -111.246962) (xy 272.972694 -111.312563)
			(xy 272.917313 -111.373313) (xy 272.856563 -111.428694) (xy 272.790962 -111.478234) (xy 272.72107 -111.521509)
			(xy 272.647483 -111.558151) (xy 272.570829 -111.587847) (xy 272.491762 -111.610343) (xy 272.410957 -111.625448)
			(xy 272.329102 -111.633033) (xy 272.288 -111.633508) (xy 272.241604 -111.632925) (xy 272.149316 -111.62328)
			(xy 272.058532 -111.604084) (xy 271.970239 -111.575546) (xy 271.927574 -111.557308) (xy 271.917632 -111.553502)
			(xy 271.896368 -111.553502) (xy 271.886426 -111.557308) (xy 271.853507 -111.571537) (xy 271.785822 -111.595257)
			(xy 271.716442 -111.613437) (xy 271.681194 -111.620046) (xy 271.67107 -111.622344) (xy 271.653749 -111.633749)
			(xy 271.642344 -111.65107) (xy 271.640046 -111.661194) (xy 271.633416 -111.696437) (xy 271.61522 -111.76581)
			(xy 271.591513 -111.833498) (xy 271.577308 -111.866426) (xy 271.573502 -111.876368) (xy 271.573502 -111.897632)
			(xy 271.577308 -111.907574) (xy 271.591537 -111.940493) (xy 271.615257 -112.008178) (xy 271.633437 -112.077558)
			(xy 271.640046 -112.112806) (xy 271.642344 -112.12293) (xy 271.653749 -112.140251) (xy 271.67107 -112.151656)
			(xy 271.681194 -112.153954) (xy 271.716437 -112.160584) (xy 271.78581 -112.17878) (xy 271.853498 -112.202487)
			(xy 271.886426 -112.216692) (xy 271.896368 -112.220498) (xy 271.917632 -112.220498) (xy 271.927574 -112.216692)
			(xy 271.970236 -112.198447) (xy 272.058529 -112.169903) (xy 272.149314 -112.15071) (xy 272.241604 -112.141077)
			(xy 272.288 -112.140492) (xy 272.329102 -112.140967) (xy 272.410957 -112.148552) (xy 272.491762 -112.163657)
			(xy 272.570829 -112.186153) (xy 272.647483 -112.215849) (xy 272.72107 -112.252491) (xy 272.790962 -112.295766)
			(xy 272.856563 -112.345306) (xy 272.917313 -112.400687) (xy 272.972694 -112.461437) (xy 273.022234 -112.527038)
			(xy 273.065509 -112.59693) (xy 273.102151 -112.670517) (xy 273.131847 -112.747171) (xy 273.154343 -112.826238)
			(xy 273.169448 -112.907043) (xy 273.177033 -112.988898) (xy 273.177508 -113.03) (xy 273.176925 -113.076396)
			(xy 273.16728 -113.168684) (xy 273.148084 -113.259468) (xy 273.119546 -113.347761) (xy 273.101308 -113.390426)
			(xy 273.097502 -113.400368) (xy 273.097502 -113.421632) (xy 273.101308 -113.431574) (xy 273.119553 -113.474236)
			(xy 273.148097 -113.562529) (xy 273.16729 -113.653314) (xy 273.176923 -113.745604) (xy 273.177508 -113.792)
			(xy 273.177033 -113.833102) (xy 273.169448 -113.914957) (xy 273.154343 -113.995762) (xy 273.131847 -114.074829)
			(xy 273.102151 -114.151483) (xy 273.065509 -114.22507) (xy 273.022234 -114.294962) (xy 272.972694 -114.360563)
			(xy 272.917313 -114.421313) (xy 272.856563 -114.476694) (xy 272.790962 -114.526234) (xy 272.72107 -114.569509)
			(xy 272.647483 -114.606151) (xy 272.570829 -114.635847) (xy 272.491762 -114.658343) (xy 272.410957 -114.673448)
			(xy 272.329102 -114.681033) (xy 272.288 -114.681508) (xy 272.241604 -114.680925) (xy 272.149316 -114.67128)
			(xy 272.058532 -114.652084) (xy 271.970239 -114.623546) (xy 271.927574 -114.605308) (xy 271.917632 -114.601502)
			(xy 271.896368 -114.601502) (xy 271.886426 -114.605308) (xy 271.843764 -114.623553) (xy 271.755471 -114.652097)
			(xy 271.664686 -114.67129) (xy 271.572396 -114.680923) (xy 271.526 -114.681508) (xy 271.479604 -114.680925)
			(xy 271.387316 -114.67128) (xy 271.296532 -114.652084) (xy 271.208239 -114.623546) (xy 271.165574 -114.605308)
			(xy 271.155632 -114.601502) (xy 271.134368 -114.601502) (xy 271.124426 -114.605308) (xy 271.081764 -114.623553)
			(xy 270.993471 -114.652097) (xy 270.902686 -114.67129) (xy 270.810396 -114.680923) (xy 270.764 -114.681508)
			(xy 270.717604 -114.680925) (xy 270.625316 -114.67128) (xy 270.534532 -114.652084) (xy 270.446239 -114.623546)
			(xy 270.403574 -114.605308) (xy 270.393632 -114.601502) (xy 270.372368 -114.601502) (xy 270.362426 -114.605308)
			(xy 270.319764 -114.623553) (xy 270.231471 -114.652097) (xy 270.140686 -114.67129) (xy 270.048396 -114.680923)
			(xy 270.002 -114.681508) (xy 269.955604 -114.680925) (xy 269.863316 -114.67128) (xy 269.772532 -114.652084)
			(xy 269.684239 -114.623546) (xy 269.641574 -114.605308) (xy 269.631632 -114.601502) (xy 269.610368 -114.601502)
			(xy 269.600426 -114.605308) (xy 269.557764 -114.623553) (xy 269.469471 -114.652097) (xy 269.378686 -114.67129)
			(xy 269.286396 -114.680923) (xy 269.24 -114.681508) (xy 269.198898 -114.681033) (xy 269.117043 -114.673448)
			(xy 269.036238 -114.658343) (xy 268.957171 -114.635847) (xy 268.880517 -114.606151) (xy 268.80693 -114.569509)
			(xy 268.737038 -114.526234) (xy 268.671437 -114.476694) (xy 268.610687 -114.421313) (xy 268.555306 -114.360563)
			(xy 268.505766 -114.294962) (xy 268.462491 -114.22507) (xy 268.425849 -114.151483) (xy 268.396153 -114.074829)
			(xy 268.373657 -113.995762) (xy 268.358552 -113.914957) (xy 268.350967 -113.833102) (xy 268.350492 -113.792)
			(xy 0.573755 -113.792) (xy 0.587497 -113.852208) (xy 0.626186 -113.986499) (xy 0.672343 -114.118409)
			(xy 0.725824 -114.247524) (xy 0.78646 -114.373436) (xy 0.854061 -114.495751) (xy 0.928414 -114.614083)
			(xy 1.009285 -114.72806) (xy 1.09642 -114.837323) (xy 1.189543 -114.941529) (xy 1.288363 -115.040349)
			(xy 1.392569 -115.133472) (xy 1.501832 -115.220607) (xy 1.615809 -115.301478) (xy 1.734141 -115.375831)
			(xy 1.856456 -115.443432) (xy 1.982368 -115.504068) (xy 2.111483 -115.557549) (xy 2.243393 -115.603706)
			(xy 2.377684 -115.642395) (xy 2.513933 -115.673493) (xy 2.651711 -115.696902) (xy 2.790585 -115.71255)
			(xy 2.930118 -115.720386) (xy 2.999994 -115.720876) (xy 9.59993 -115.720876) (xy 9.643968 -115.721358)
			(xy 9.731709 -115.729037) (xy 9.818446 -115.744333) (xy 9.90352 -115.767131) (xy 9.986284 -115.797257)
			(xy 10.066107 -115.834482) (xy 10.142382 -115.878522) (xy 10.214528 -115.929042) (xy 10.281997 -115.985658)
			(xy 10.344275 -116.047939) (xy 10.400887 -116.11541) (xy 10.451404 -116.187559) (xy 10.49544 -116.263836)
			(xy 10.532661 -116.34366) (xy 10.562783 -116.426425) (xy 10.585577 -116.511501) (xy 10.60087 -116.598239)
			(xy 10.608544 -116.68598) (xy 10.609072 -116.730018) (xy 10.609072 -116.971769) (xy 270.314162 -116.971769)
			(xy 270.314162 -116.887047) (xy 270.322215 -116.80271) (xy 270.338249 -116.71952) (xy 270.362117 -116.63823)
			(xy 270.393605 -116.559578) (xy 270.432427 -116.484275) (xy 270.47823 -116.413003) (xy 270.530601 -116.346407)
			(xy 270.589066 -116.285092) (xy 270.653094 -116.229611) (xy 270.722106 -116.180468) (xy 270.795476 -116.138108)
			(xy 270.872541 -116.102913) (xy 270.952603 -116.075204) (xy 271.034936 -116.05523) (xy 271.118795 -116.043173)
			(xy 271.20342 -116.039142) (xy 271.288045 -116.043173) (xy 271.371904 -116.05523) (xy 271.454237 -116.075204)
			(xy 271.534299 -116.102913) (xy 271.611364 -116.138108) (xy 271.684734 -116.180468) (xy 271.753746 -116.229611)
			(xy 271.817774 -116.285092) (xy 271.876239 -116.346407) (xy 271.92861 -116.413003) (xy 271.974413 -116.484275)
			(xy 272.013235 -116.559578) (xy 272.044723 -116.63823) (xy 272.068591 -116.71952) (xy 272.084625 -116.80271)
			(xy 272.092678 -116.887047) (xy 272.093182 -116.929408) (xy 272.092678 -116.971769) (xy 272.084625 -117.056106)
			(xy 272.068591 -117.139296) (xy 272.044723 -117.220586) (xy 272.013235 -117.299238) (xy 271.974413 -117.374541)
			(xy 271.92861 -117.445813) (xy 271.876239 -117.512409) (xy 271.817774 -117.573724) (xy 271.753746 -117.629205)
			(xy 271.684734 -117.678348) (xy 271.611364 -117.720708) (xy 271.534299 -117.755903) (xy 271.454237 -117.783612)
			(xy 271.371904 -117.803586) (xy 271.288045 -117.815643) (xy 271.20342 -117.819675) (xy 271.118795 -117.815643)
			(xy 271.034936 -117.803586) (xy 270.952603 -117.783612) (xy 270.872541 -117.755903) (xy 270.795476 -117.720708)
			(xy 270.722106 -117.678348) (xy 270.653094 -117.629205) (xy 270.589066 -117.573724) (xy 270.530601 -117.512409)
			(xy 270.47823 -117.445813) (xy 270.432427 -117.374541) (xy 270.393605 -117.299238) (xy 270.362117 -117.220586)
			(xy 270.338249 -117.139296) (xy 270.322215 -117.056106) (xy 270.314162 -116.971769) (xy 10.609072 -116.971769)
			(xy 10.609072 -122.48007) (xy 12.909653 -122.48007) (xy 12.913615 -122.339639) (xy 12.92549 -122.199655)
			(xy 12.94524 -122.060564) (xy 12.972802 -121.922808) (xy 13.008088 -121.786825) (xy 13.050986 -121.653048)
			(xy 13.101359 -121.521903) (xy 13.159047 -121.393807) (xy 13.223867 -121.269168) (xy 13.295611 -121.148382)
			(xy 13.374053 -121.031834) (xy 13.458942 -120.919895) (xy 13.550008 -120.812921) (xy 13.646962 -120.711253)
			(xy 13.749494 -120.615213) (xy 13.857279 -120.525108) (xy 13.969973 -120.441224) (xy 14.087218 -120.363828)
			(xy 14.208641 -120.293167) (xy 14.333855 -120.229466) (xy 14.462462 -120.172926) (xy 14.594052 -120.123729)
			(xy 14.728208 -120.08203) (xy 14.864501 -120.047962) (xy 15.002499 -120.021634) (xy 15.141762 -120.00313)
			(xy 15.281846 -119.992508) (xy 15.422307 -119.989803) (xy 15.562696 -119.995022) (xy 15.702568 -120.008149)
			(xy 15.841477 -120.029143) (xy 15.978981 -120.057936) (xy 16.114643 -120.094438) (xy 16.248031 -120.138531)
			(xy 16.37872 -120.190076) (xy 16.506295 -120.248908) (xy 16.630349 -120.31484) (xy 16.750487 -120.387663)
			(xy 16.866328 -120.467145) (xy 16.977503 -120.553032) (xy 17.083658 -120.645052) (xy 17.184455 -120.742911)
			(xy 17.232376 -120.794272) (xy 17.241266 -120.803924) (xy 17.264888 -120.812052) (xy 17.3736 -120.795542)
			(xy 17.393666 -120.780556) (xy 17.399 -120.768872) (xy 17.438151 -120.687) (xy 17.522868 -120.526483)
			(xy 17.614754 -120.36996) (xy 17.713621 -120.21775) (xy 17.819267 -120.070165) (xy 17.931475 -119.927505)
			(xy 18.050018 -119.790064) (xy 18.174651 -119.65812) (xy 18.305121 -119.531945) (xy 18.441161 -119.411797)
			(xy 18.582492 -119.29792) (xy 18.728826 -119.190548) (xy 18.879864 -119.089899) (xy 19.035297 -118.996181)
			(xy 19.194807 -118.909584) (xy 19.358068 -118.830285) (xy 19.524747 -118.758447) (xy 19.694502 -118.694216)
			(xy 19.866987 -118.637724) (xy 20.04185 -118.589086) (xy 20.218732 -118.548401) (xy 20.397272 -118.515753)
			(xy 20.577105 -118.491209) (xy 20.757864 -118.474818) (xy 20.93918 -118.466614) (xy 21.02993 -118.466108)
			(xy 21.120007 -118.466613) (xy 21.147082 -118.467829) (xy 268.757142 -118.467829) (xy 268.757142 -118.383107)
			(xy 268.765195 -118.29877) (xy 268.781229 -118.21558) (xy 268.805097 -118.13429) (xy 268.836585 -118.055638)
			(xy 268.875407 -117.980335) (xy 268.92121 -117.909063) (xy 268.973581 -117.842467) (xy 269.032046 -117.781152)
			(xy 269.096074 -117.725671) (xy 269.165086 -117.676528) (xy 269.238456 -117.634168) (xy 269.315521 -117.598973)
			(xy 269.395583 -117.571264) (xy 269.477916 -117.55129) (xy 269.561775 -117.539233) (xy 269.6464 -117.535202)
			(xy 269.731025 -117.539233) (xy 269.814884 -117.55129) (xy 269.897217 -117.571264) (xy 269.977279 -117.598973)
			(xy 270.054344 -117.634168) (xy 270.127714 -117.676528) (xy 270.196726 -117.725671) (xy 270.260754 -117.781152)
			(xy 270.319219 -117.842467) (xy 270.37159 -117.909063) (xy 270.417393 -117.980335) (xy 270.456215 -118.055638)
			(xy 270.487703 -118.13429) (xy 270.511571 -118.21558) (xy 270.527605 -118.29877) (xy 270.535658 -118.383107)
			(xy 270.536162 -118.425468) (xy 270.535658 -118.467829) (xy 270.527605 -118.552166) (xy 270.511571 -118.635356)
			(xy 270.487703 -118.716646) (xy 270.456215 -118.795298) (xy 270.417393 -118.870601) (xy 270.37159 -118.941873)
			(xy 270.319219 -119.008469) (xy 270.260754 -119.069784) (xy 270.196726 -119.125265) (xy 270.127714 -119.174408)
			(xy 270.054344 -119.216768) (xy 269.977279 -119.251963) (xy 269.897217 -119.279672) (xy 269.814884 -119.299646)
			(xy 269.731025 -119.311703) (xy 269.6464 -119.315735) (xy 269.561775 -119.311703) (xy 269.477916 -119.299646)
			(xy 269.395583 -119.279672) (xy 269.315521 -119.251963) (xy 269.238456 -119.216768) (xy 269.165086 -119.174408)
			(xy 269.096074 -119.125265) (xy 269.032046 -119.069784) (xy 268.973581 -119.008469) (xy 268.92121 -118.941873)
			(xy 268.875407 -118.870601) (xy 268.836585 -118.795298) (xy 268.805097 -118.716646) (xy 268.781229 -118.635356)
			(xy 268.765195 -118.552166) (xy 268.757142 -118.467829) (xy 21.147082 -118.467829) (xy 21.299979 -118.474696)
			(xy 21.479408 -118.490845) (xy 21.657931 -118.515027) (xy 21.83519 -118.547195) (xy 22.010827 -118.587283)
			(xy 22.184488 -118.63521) (xy 22.355825 -118.690881) (xy 22.524491 -118.754183) (xy 22.690147 -118.824987)
			(xy 22.85246 -118.903153) (xy 23.011103 -118.988522) (xy 23.165755 -119.080923) (xy 23.316107 -119.180169)
			(xy 23.461854 -119.286061) (xy 23.602704 -119.398385) (xy 23.738373 -119.516915) (xy 23.868587 -119.641413)
			(xy 23.993085 -119.771627) (xy 24.111615 -119.907296) (xy 24.223939 -120.048146) (xy 24.329831 -120.193893)
			(xy 24.429077 -120.344245) (xy 24.521478 -120.498897) (xy 24.606847 -120.65754) (xy 24.685013 -120.819853)
			(xy 24.755817 -120.985509) (xy 24.819119 -121.154175) (xy 24.87479 -121.325512) (xy 24.922717 -121.499173)
			(xy 24.962805 -121.67481) (xy 24.994973 -121.852069) (xy 25.019155 -122.030592) (xy 25.035304 -122.210021)
			(xy 25.043387 -122.389993) (xy 25.043387 -122.48007) (xy 25.159471 -122.48007) (xy 25.16346 -122.339172)
			(xy 25.175414 -122.198725) (xy 25.195294 -122.05918) (xy 25.223037 -121.920983) (xy 25.258555 -121.784577)
			(xy 25.301732 -121.650398) (xy 25.352432 -121.518878) (xy 25.410492 -121.390436) (xy 25.475724 -121.265485)
			(xy 25.547922 -121.144424) (xy 25.626853 -121.027642) (xy 25.712264 -120.915513) (xy 25.803883 -120.808395)
			(xy 25.901415 -120.706632) (xy 26.004547 -120.61055) (xy 26.112951 -120.520457) (xy 26.226278 -120.43664)
			(xy 26.344165 -120.35937) (xy 26.466235 -120.288893) (xy 26.592097 -120.225434) (xy 26.721347 -120.169199)
			(xy 26.853572 -120.120365) (xy 26.988348 -120.07909) (xy 27.125243 -120.045507) (xy 27.263819 -120.019722)
			(xy 27.403632 -120.001818) (xy 27.544234 -119.991853) (xy 27.685174 -119.989858) (xy 27.826002 -119.995841)
			(xy 27.966265 -120.009781) (xy 28.105515 -120.031634) (xy 28.243306 -120.06133) (xy 28.379196 -120.098774)
			(xy 28.51275 -120.143846) (xy 28.64354 -120.196402) (xy 28.771147 -120.256273) (xy 28.895163 -120.323268)
			(xy 29.015189 -120.397171) (xy 29.130843 -120.477747) (xy 29.241752 -120.564736) (xy 29.347563 -120.657861)
			(xy 29.447935 -120.756823) (xy 29.542548 -120.861305) (xy 29.631099 -120.970973) (xy 29.713303 -121.085475)
			(xy 29.788897 -121.204444) (xy 29.791898 -121.209816) (xy 62.652667 -121.209816) (xy 62.65664 -121.089706)
			(xy 62.668543 -120.970121) (xy 62.688324 -120.851584) (xy 62.715895 -120.734613) (xy 62.751137 -120.61972)
			(xy 62.793894 -120.507408) (xy 62.843982 -120.398167) (xy 62.901179 -120.292476) (xy 62.965237 -120.190795)
			(xy 63.035874 -120.093571) (xy 63.112783 -120.001228) (xy 63.195627 -119.914169) (xy 63.284043 -119.832776)
			(xy 63.377646 -119.757405) (xy 63.476025 -119.688384) (xy 63.57875 -119.626016) (xy 63.685373 -119.570574)
			(xy 63.795427 -119.5223) (xy 63.908431 -119.481405) (xy 64.023891 -119.448068) (xy 64.141301 -119.422434)
			(xy 64.260149 -119.404616) (xy 64.379915 -119.394692) (xy 64.500074 -119.392705) (xy 64.620102 -119.398664)
			(xy 64.739474 -119.412543) (xy 64.857668 -119.43428) (xy 64.974167 -119.463782) (xy 65.088461 -119.500918)
			(xy 65.200051 -119.545527) (xy 65.308449 -119.597414) (xy 65.41318 -119.656351) (xy 65.513787 -119.722081)
			(xy 65.609831 -119.794316) (xy 65.70089 -119.872742) (xy 65.786567 -119.957013) (xy 65.866487 -120.046763)
			(xy 65.9403 -120.141599) (xy 66.007685 -120.241106) (xy 66.068346 -120.344849) (xy 66.122017 -120.452374)
			(xy 66.168465 -120.563211) (xy 66.207486 -120.676875) (xy 66.23891 -120.79287) (xy 66.262599 -120.910689)
			(xy 66.278449 -121.029815) (xy 66.286391 -121.149728) (xy 66.286888 -121.209816) (xy 102.652587 -121.209816)
			(xy 102.65656 -121.089706) (xy 102.668463 -120.970121) (xy 102.688244 -120.851584) (xy 102.715815 -120.734613)
			(xy 102.751057 -120.61972) (xy 102.793814 -120.507408) (xy 102.843902 -120.398167) (xy 102.901099 -120.292476)
			(xy 102.965157 -120.190795) (xy 103.035794 -120.093571) (xy 103.112703 -120.001228) (xy 103.195547 -119.914169)
			(xy 103.283963 -119.832776) (xy 103.377566 -119.757405) (xy 103.475945 -119.688384) (xy 103.57867 -119.626016)
			(xy 103.685293 -119.570574) (xy 103.795347 -119.5223) (xy 103.908351 -119.481405) (xy 104.023811 -119.448068)
			(xy 104.141221 -119.422434) (xy 104.260069 -119.404616) (xy 104.379835 -119.394692) (xy 104.499994 -119.392705)
			(xy 104.620022 -119.398664) (xy 104.739394 -119.412543) (xy 104.857588 -119.43428) (xy 104.974087 -119.463782)
			(xy 105.088381 -119.500918) (xy 105.199971 -119.545527) (xy 105.308369 -119.597414) (xy 105.4131 -119.656351)
			(xy 105.513707 -119.722081) (xy 105.609751 -119.794316) (xy 105.70081 -119.872742) (xy 105.786487 -119.957013)
			(xy 105.866407 -120.046763) (xy 105.94022 -120.141599) (xy 106.007605 -120.241106) (xy 106.068266 -120.344849)
			(xy 106.121937 -120.452374) (xy 106.168385 -120.563211) (xy 106.207406 -120.676875) (xy 106.23883 -120.79287)
			(xy 106.262519 -120.910689) (xy 106.278369 -121.029815) (xy 106.286311 -121.149728) (xy 106.286808 -121.209816)
			(xy 142.652761 -121.209816) (xy 142.656734 -121.089706) (xy 142.668637 -120.970121) (xy 142.688418 -120.851584)
			(xy 142.715989 -120.734613) (xy 142.751231 -120.61972) (xy 142.793988 -120.507408) (xy 142.844076 -120.398167)
			(xy 142.901273 -120.292476) (xy 142.965331 -120.190795) (xy 143.035968 -120.093571) (xy 143.112877 -120.001228)
			(xy 143.195721 -119.914169) (xy 143.284137 -119.832776) (xy 143.37774 -119.757405) (xy 143.476119 -119.688384)
			(xy 143.578844 -119.626016) (xy 143.685467 -119.570574) (xy 143.795521 -119.5223) (xy 143.908525 -119.481405)
			(xy 144.023985 -119.448068) (xy 144.141395 -119.422434) (xy 144.260243 -119.404616) (xy 144.380009 -119.394692)
			(xy 144.500168 -119.392705) (xy 144.620196 -119.398664) (xy 144.739568 -119.412543) (xy 144.857762 -119.43428)
			(xy 144.974261 -119.463782) (xy 145.088555 -119.500918) (xy 145.200145 -119.545527) (xy 145.308543 -119.597414)
			(xy 145.413274 -119.656351) (xy 145.513881 -119.722081) (xy 145.609925 -119.794316) (xy 145.700984 -119.872742)
			(xy 145.786661 -119.957013) (xy 145.866581 -120.046763) (xy 145.940394 -120.141599) (xy 146.007779 -120.241106)
			(xy 146.06844 -120.344849) (xy 146.122111 -120.452374) (xy 146.168559 -120.563211) (xy 146.20758 -120.676875)
			(xy 146.239004 -120.79287) (xy 146.262693 -120.910689) (xy 146.278543 -121.029815) (xy 146.286485 -121.149728)
			(xy 146.286982 -121.209816) (xy 182.652935 -121.209816) (xy 182.656908 -121.089706) (xy 182.668811 -120.970121)
			(xy 182.688592 -120.851584) (xy 182.716163 -120.734613) (xy 182.751405 -120.61972) (xy 182.794162 -120.507408)
			(xy 182.84425 -120.398167) (xy 182.901447 -120.292476) (xy 182.965505 -120.190795) (xy 183.036142 -120.093571)
			(xy 183.113051 -120.001228) (xy 183.195895 -119.914169) (xy 183.284311 -119.832776) (xy 183.377914 -119.757405)
			(xy 183.476293 -119.688384) (xy 183.579018 -119.626016) (xy 183.685641 -119.570574) (xy 183.795695 -119.5223)
			(xy 183.908699 -119.481405) (xy 184.024159 -119.448068) (xy 184.141569 -119.422434) (xy 184.260417 -119.404616)
			(xy 184.380183 -119.394692) (xy 184.500342 -119.392705) (xy 184.62037 -119.398664) (xy 184.739742 -119.412543)
			(xy 184.857936 -119.43428) (xy 184.974435 -119.463782) (xy 185.088729 -119.500918) (xy 185.200319 -119.545527)
			(xy 185.308717 -119.597414) (xy 185.413448 -119.656351) (xy 185.514055 -119.722081) (xy 185.610099 -119.794316)
			(xy 185.701158 -119.872742) (xy 185.786835 -119.957013) (xy 185.866755 -120.046763) (xy 185.940568 -120.141599)
			(xy 186.007953 -120.241106) (xy 186.068614 -120.344849) (xy 186.122285 -120.452374) (xy 186.168733 -120.563211)
			(xy 186.207754 -120.676875) (xy 186.239178 -120.79287) (xy 186.262867 -120.910689) (xy 186.278717 -121.029815)
			(xy 186.286659 -121.149728) (xy 186.287156 -121.209816) (xy 186.286659 -121.269904) (xy 186.278717 -121.389817)
			(xy 186.262867 -121.508943) (xy 186.239178 -121.626762) (xy 186.207754 -121.742757) (xy 186.168733 -121.856421)
			(xy 186.122285 -121.967258) (xy 186.068614 -122.074783) (xy 186.007953 -122.178526) (xy 185.940568 -122.278033)
			(xy 185.866755 -122.372869) (xy 185.786835 -122.462619) (xy 185.701158 -122.54689) (xy 185.610099 -122.625316)
			(xy 185.514055 -122.697551) (xy 185.413448 -122.763281) (xy 185.330851 -122.809762) (xy 201.460608 -122.809762)
			(xy 201.461219 -122.763359) (xy 201.470913 -122.671062) (xy 201.490171 -122.580276) (xy 201.518784 -122.491991)
			(xy 201.537062 -122.449336) (xy 201.540892 -122.439401) (xy 201.540877 -122.41813) (xy 201.537062 -122.408188)
			(xy 201.518789 -122.365532) (xy 201.490198 -122.277242) (xy 201.470944 -122.186458) (xy 201.461235 -122.094163)
			(xy 201.460608 -122.047762) (xy 201.461152 -122.004334) (xy 201.469646 -121.917893) (xy 201.486519 -121.83269)
			(xy 201.511611 -121.749536) (xy 201.527664 -121.70918) (xy 201.531108 -121.699762) (xy 201.531126 -121.679728)
			(xy 201.527664 -121.670318) (xy 201.511607 -121.629963) (xy 201.486507 -121.54681) (xy 201.469633 -121.461607)
			(xy 201.461143 -121.375165) (xy 201.460608 -121.331736) (xy 201.46121 -121.285333) (xy 201.470907 -121.193035)
			(xy 201.490167 -121.10225) (xy 201.518783 -121.013965) (xy 201.537062 -120.97131) (xy 201.540848 -120.961362)
			(xy 201.540862 -120.940104) (xy 201.537062 -120.930162) (xy 201.518813 -120.887496) (xy 201.490216 -120.79921)
			(xy 201.470955 -120.708428) (xy 201.461239 -120.616137) (xy 201.460608 -120.569736) (xy 201.461087 -120.528625)
			(xy 201.468672 -120.446755) (xy 201.48378 -120.365934) (xy 201.506282 -120.286852) (xy 201.535987 -120.210185)
			(xy 201.57264 -120.136586) (xy 201.61593 -120.066683) (xy 201.665486 -120.001075) (xy 201.720885 -119.940319)
			(xy 201.781655 -119.884936) (xy 201.847277 -119.835397) (xy 201.91719 -119.792126) (xy 201.990799 -119.755492)
			(xy 202.067474 -119.725808) (xy 202.146562 -119.703326) (xy 202.227387 -119.688239) (xy 202.309259 -119.680676)
			(xy 202.35037 -119.680228) (xy 202.396765 -119.680818) (xy 202.489054 -119.690461) (xy 202.579837 -119.709654)
			(xy 202.668131 -119.738191) (xy 202.710796 -119.756428) (xy 202.720738 -119.760234) (xy 202.742002 -119.760234)
			(xy 202.751944 -119.756428) (xy 202.794611 -119.738195) (xy 202.882902 -119.709648) (xy 202.973685 -119.690451)
			(xy 203.065974 -119.680814) (xy 203.11237 -119.680228) (xy 203.158765 -119.680818) (xy 203.251054 -119.690461)
			(xy 203.341837 -119.709654) (xy 203.430131 -119.738191) (xy 203.472796 -119.756428) (xy 203.482738 -119.760234)
			(xy 203.504002 -119.760234) (xy 203.513944 -119.756428) (xy 203.556611 -119.738195) (xy 203.644902 -119.709648)
			(xy 203.735685 -119.690451) (xy 203.827974 -119.680814) (xy 203.87437 -119.680228) (xy 203.920765 -119.680818)
			(xy 204.013054 -119.690461) (xy 204.103837 -119.709654) (xy 204.192131 -119.738191) (xy 204.234796 -119.756428)
			(xy 204.244738 -119.760234) (xy 204.266002 -119.760234) (xy 204.275944 -119.756428) (xy 204.318611 -119.738195)
			(xy 204.406902 -119.709648) (xy 204.497685 -119.690451) (xy 204.589974 -119.680814) (xy 204.63637 -119.680228)
			(xy 204.682765 -119.680818) (xy 204.775054 -119.690461) (xy 204.865837 -119.709654) (xy 204.954131 -119.738191)
			(xy 204.996796 -119.756428) (xy 205.006738 -119.760234) (xy 205.028002 -119.760234) (xy 205.037944 -119.756428)
			(xy 205.080611 -119.738195) (xy 205.168902 -119.709648) (xy 205.259685 -119.690451) (xy 205.351974 -119.680814)
			(xy 205.39837 -119.680228) (xy 205.444765 -119.680818) (xy 205.537054 -119.690461) (xy 205.627837 -119.709654)
			(xy 205.716131 -119.738191) (xy 205.758796 -119.756428) (xy 205.768738 -119.760234) (xy 205.790002 -119.760234)
			(xy 205.799944 -119.756428) (xy 205.842611 -119.738195) (xy 205.930902 -119.709648) (xy 206.021685 -119.690451)
			(xy 206.113974 -119.680814) (xy 206.16037 -119.680228) (xy 206.206765 -119.680818) (xy 206.299054 -119.690461)
			(xy 206.389837 -119.709654) (xy 206.478131 -119.738191) (xy 206.520796 -119.756428) (xy 206.530738 -119.760234)
			(xy 206.552002 -119.760234) (xy 206.561944 -119.756428) (xy 206.604611 -119.738195) (xy 206.692902 -119.709648)
			(xy 206.783685 -119.690451) (xy 206.875974 -119.680814) (xy 206.92237 -119.680228) (xy 206.968765 -119.680818)
			(xy 207.061054 -119.690461) (xy 207.151837 -119.709654) (xy 207.240131 -119.738191) (xy 207.282796 -119.756428)
			(xy 207.292738 -119.760234) (xy 207.314002 -119.760234) (xy 207.323944 -119.756428) (xy 207.366611 -119.738195)
			(xy 207.454902 -119.709648) (xy 207.545685 -119.690451) (xy 207.637974 -119.680814) (xy 207.68437 -119.680228)
			(xy 207.725476 -119.680741) (xy 207.807338 -119.688323) (xy 207.888151 -119.703424) (xy 207.967226 -119.725916)
			(xy 208.043889 -119.755607) (xy 208.117486 -119.792244) (xy 208.18739 -119.835514) (xy 208.253003 -119.885048)
			(xy 208.313767 -119.940425) (xy 208.369164 -120.00117) (xy 208.41872 -120.066768) (xy 208.462013 -120.136657)
			(xy 208.498674 -120.210242) (xy 208.528391 -120.286895) (xy 208.550909 -120.365963) (xy 208.566037 -120.446771)
			(xy 208.573645 -120.52863) (xy 208.574132 -120.569736) (xy 208.573517 -120.616138) (xy 208.563823 -120.708436)
			(xy 208.544566 -120.799221) (xy 208.515955 -120.887506) (xy 208.497678 -120.930162) (xy 208.493853 -120.940098)
			(xy 208.493867 -120.961367) (xy 208.497678 -120.97131) (xy 208.515953 -121.013966) (xy 208.544542 -121.102256)
			(xy 208.563796 -121.19304) (xy 208.573505 -121.285335) (xy 208.574132 -121.331736) (xy 208.573584 -121.375164)
			(xy 208.565091 -121.461605) (xy 208.548219 -121.546808) (xy 208.523128 -121.629962) (xy 208.507076 -121.670318)
			(xy 208.503705 -121.679744) (xy 208.503722 -121.699746) (xy 208.507076 -121.70918) (xy 208.523129 -121.749537)
			(xy 208.54823 -121.832688) (xy 208.565107 -121.917891) (xy 208.573597 -122.004333) (xy 208.574132 -122.047762)
			(xy 208.573526 -122.094165) (xy 208.56383 -122.186463) (xy 208.54457 -122.277248) (xy 208.515957 -122.365533)
			(xy 208.497678 -122.408188) (xy 208.493897 -122.418137) (xy 208.493882 -122.439394) (xy 208.497678 -122.449336)
			(xy 208.515928 -122.492002) (xy 208.544524 -122.580288) (xy 208.563785 -122.671069) (xy 208.573501 -122.763361)
			(xy 208.574132 -122.809762) (xy 215.837516 -122.809762) (xy 215.838126 -122.763359) (xy 215.847821 -122.671062)
			(xy 215.867079 -122.580276) (xy 215.895692 -122.491991) (xy 215.91397 -122.449336) (xy 215.917799 -122.439401)
			(xy 215.917785 -122.41813) (xy 215.91397 -122.408188) (xy 215.895691 -122.365534) (xy 215.867103 -122.277243)
			(xy 215.847851 -122.186458) (xy 215.838143 -122.094164) (xy 215.837516 -122.047762) (xy 215.83806 -122.004334)
			(xy 215.846553 -121.917893) (xy 215.863427 -121.83269) (xy 215.888519 -121.749536) (xy 215.904572 -121.70918)
			(xy 215.908015 -121.699762) (xy 215.908033 -121.679728) (xy 215.904572 -121.670318) (xy 215.888515 -121.629963)
			(xy 215.863416 -121.54681) (xy 215.846541 -121.461607) (xy 215.838051 -121.375165) (xy 215.837516 -121.331736)
			(xy 215.838117 -121.285333) (xy 215.847814 -121.193035) (xy 215.867075 -121.10225) (xy 215.89569 -121.013965)
			(xy 215.91397 -120.97131) (xy 215.917755 -120.961361) (xy 215.917769 -120.940104) (xy 215.91397 -120.930162)
			(xy 215.895716 -120.887498) (xy 215.867121 -120.799211) (xy 215.847862 -120.708429) (xy 215.838147 -120.616137)
			(xy 215.837516 -120.569736) (xy 215.837987 -120.528625) (xy 215.845572 -120.446754) (xy 215.86068 -120.365933)
			(xy 215.883183 -120.286851) (xy 215.912888 -120.210183) (xy 215.949542 -120.136583) (xy 215.992832 -120.066681)
			(xy 216.042388 -120.001072) (xy 216.097788 -119.940317) (xy 216.158558 -119.884933) (xy 216.224181 -119.835395)
			(xy 216.294095 -119.792124) (xy 216.367704 -119.75549) (xy 216.44438 -119.725806) (xy 216.523469 -119.703324)
			(xy 216.604294 -119.688238) (xy 216.686167 -119.680676) (xy 216.727278 -119.680228) (xy 216.773673 -119.680816)
			(xy 216.865962 -119.690459) (xy 216.956746 -119.709653) (xy 217.045039 -119.738191) (xy 217.087704 -119.756428)
			(xy 217.097646 -119.760234) (xy 217.11891 -119.760234) (xy 217.128852 -119.756428) (xy 217.171518 -119.738193)
			(xy 217.259809 -119.709646) (xy 217.350593 -119.69045) (xy 217.442882 -119.680814) (xy 217.489278 -119.680228)
			(xy 217.535673 -119.680816) (xy 217.627962 -119.690459) (xy 217.718746 -119.709653) (xy 217.807039 -119.738191)
			(xy 217.849704 -119.756428) (xy 217.859646 -119.760234) (xy 217.88091 -119.760234) (xy 217.890852 -119.756428)
			(xy 217.933518 -119.738193) (xy 218.021809 -119.709646) (xy 218.112593 -119.69045) (xy 218.204882 -119.680814)
			(xy 218.251278 -119.680228) (xy 218.297673 -119.680816) (xy 218.389962 -119.690459) (xy 218.480746 -119.709653)
			(xy 218.569039 -119.738191) (xy 218.611704 -119.756428) (xy 218.621646 -119.760234) (xy 218.64291 -119.760234)
			(xy 218.652852 -119.756428) (xy 218.695518 -119.738193) (xy 218.783809 -119.709646) (xy 218.874593 -119.69045)
			(xy 218.966882 -119.680814) (xy 219.013278 -119.680228) (xy 219.059673 -119.680816) (xy 219.151962 -119.690459)
			(xy 219.242746 -119.709653) (xy 219.331039 -119.738191) (xy 219.373704 -119.756428) (xy 219.383646 -119.760234)
			(xy 219.40491 -119.760234) (xy 219.414852 -119.756428) (xy 219.457518 -119.738193) (xy 219.545809 -119.709646)
			(xy 219.636593 -119.69045) (xy 219.728882 -119.680814) (xy 219.775278 -119.680228) (xy 219.821673 -119.680816)
			(xy 219.913962 -119.690459) (xy 220.004746 -119.709653) (xy 220.093039 -119.738191) (xy 220.135704 -119.756428)
			(xy 220.145646 -119.760234) (xy 220.16691 -119.760234) (xy 220.176852 -119.756428) (xy 220.219518 -119.738193)
			(xy 220.307809 -119.709646) (xy 220.398593 -119.69045) (xy 220.490882 -119.680814) (xy 220.537278 -119.680228)
			(xy 220.583673 -119.680816) (xy 220.675962 -119.690459) (xy 220.766746 -119.709653) (xy 220.855039 -119.738191)
			(xy 220.897704 -119.756428) (xy 220.907646 -119.760234) (xy 220.92891 -119.760234) (xy 220.938852 -119.756428)
			(xy 220.981518 -119.738193) (xy 221.069809 -119.709646) (xy 221.160593 -119.69045) (xy 221.252882 -119.680814)
			(xy 221.299278 -119.680228) (xy 221.345673 -119.680816) (xy 221.437962 -119.690459) (xy 221.528746 -119.709653)
			(xy 221.617039 -119.738191) (xy 221.659704 -119.756428) (xy 221.669646 -119.760234) (xy 221.69091 -119.760234)
			(xy 221.700852 -119.756428) (xy 221.743518 -119.738193) (xy 221.831809 -119.709646) (xy 221.922593 -119.69045)
			(xy 222.014882 -119.680814) (xy 222.061278 -119.680228) (xy 222.102384 -119.680733) (xy 222.184246 -119.688316)
			(xy 222.265059 -119.703418) (xy 222.344135 -119.72591) (xy 222.420798 -119.755602) (xy 222.494395 -119.792239)
			(xy 222.564298 -119.83551) (xy 222.629912 -119.885045) (xy 222.690676 -119.940422) (xy 222.746072 -120.001168)
			(xy 222.795628 -120.066766) (xy 222.838921 -120.136655) (xy 222.875582 -120.21024) (xy 222.905299 -120.286894)
			(xy 222.927817 -120.365962) (xy 222.942945 -120.446771) (xy 222.950553 -120.52863) (xy 222.95104 -120.569736)
			(xy 222.950424 -120.616138) (xy 222.940731 -120.708436) (xy 222.921474 -120.799221) (xy 222.892863 -120.887506)
			(xy 222.874586 -120.930162) (xy 222.87076 -120.940098) (xy 222.870774 -120.961367) (xy 222.874586 -120.97131)
			(xy 222.892861 -121.013965) (xy 222.921451 -121.102256) (xy 222.940704 -121.19304) (xy 222.950413 -121.285335)
			(xy 222.95104 -121.331736) (xy 222.950499 -121.375165) (xy 222.942005 -121.461606) (xy 222.925131 -121.546808)
			(xy 222.900038 -121.629962) (xy 222.883984 -121.670318) (xy 222.880612 -121.679744) (xy 222.88063 -121.699746)
			(xy 222.883984 -121.70918) (xy 222.900038 -121.749536) (xy 222.925139 -121.832688) (xy 222.942015 -121.917891)
			(xy 222.950505 -122.004333) (xy 222.95104 -122.047762) (xy 222.950434 -122.094165) (xy 222.940737 -122.186463)
			(xy 222.921478 -122.277248) (xy 222.892864 -122.365533) (xy 222.874586 -122.408188) (xy 222.870804 -122.418137)
			(xy 222.87079 -122.439394) (xy 222.874586 -122.449336) (xy 222.892837 -122.492001) (xy 222.921433 -122.580288)
			(xy 222.940693 -122.671069) (xy 222.950409 -122.763361) (xy 222.95104 -122.809762) (xy 222.950563 -122.851239)
			(xy 222.942823 -122.933832) (xy 222.927426 -123.015345) (xy 222.904504 -123.09507) (xy 222.889826 -123.133866)
			(xy 222.886651 -123.143365) (xy 222.887035 -123.163366) (xy 222.890588 -123.172728) (xy 222.908345 -123.214883)
			(xy 222.936112 -123.302044) (xy 222.954787 -123.391595) (xy 222.964172 -123.482589) (xy 222.964756 -123.528328)
			(xy 222.964274 -123.569438) (xy 222.956685 -123.651306) (xy 222.941572 -123.732125) (xy 222.919067 -123.811204)
			(xy 222.88936 -123.887869) (xy 222.852705 -123.961465) (xy 222.809414 -124.031365) (xy 222.759859 -124.096972)
			(xy 222.70446 -124.157726) (xy 222.643692 -124.213108) (xy 222.578072 -124.262647) (xy 222.508161 -124.305918)
			(xy 222.434555 -124.342554) (xy 222.357882 -124.372241) (xy 222.278797 -124.394726) (xy 222.197974 -124.409817)
			(xy 222.116104 -124.417385) (xy 222.074994 -124.417836) (xy 222.028598 -124.417253) (xy 221.93631 -124.407607)
			(xy 221.845526 -124.388412) (xy 221.757233 -124.359874) (xy 221.714568 -124.341636) (xy 221.704626 -124.33783)
			(xy 221.683362 -124.33783) (xy 221.67342 -124.341636) (xy 221.630759 -124.359884) (xy 221.542466 -124.388427)
			(xy 221.451681 -124.407619) (xy 221.35939 -124.417251) (xy 221.312994 -124.417836) (xy 221.266598 -124.417253)
			(xy 221.17431 -124.407607) (xy 221.083526 -124.388412) (xy 220.995233 -124.359874) (xy 220.952568 -124.341636)
			(xy 220.942626 -124.33783) (xy 220.921362 -124.33783) (xy 220.91142 -124.341636) (xy 220.868759 -124.359884)
			(xy 220.780466 -124.388427) (xy 220.689681 -124.407619) (xy 220.59739 -124.417251) (xy 220.550994 -124.417836)
			(xy 220.504598 -124.417253) (xy 220.41231 -124.407607) (xy 220.321526 -124.388412) (xy 220.233233 -124.359874)
			(xy 220.190568 -124.341636) (xy 220.180626 -124.33783) (xy 220.159362 -124.33783) (xy 220.14942 -124.341636)
			(xy 220.106759 -124.359884) (xy 220.018466 -124.388427) (xy 219.927681 -124.407619) (xy 219.83539 -124.417251)
			(xy 219.788994 -124.417836) (xy 219.742598 -124.417253) (xy 219.65031 -124.407607) (xy 219.559526 -124.388412)
			(xy 219.471233 -124.359874) (xy 219.428568 -124.341636) (xy 219.418626 -124.33783) (xy 219.397362 -124.33783)
			(xy 219.38742 -124.341636) (xy 219.344759 -124.359884) (xy 219.256466 -124.388427) (xy 219.165681 -124.407619)
			(xy 219.07339 -124.417251) (xy 219.026994 -124.417836) (xy 218.980598 -124.417253) (xy 218.88831 -124.407607)
			(xy 218.797526 -124.388412) (xy 218.709233 -124.359874) (xy 218.666568 -124.341636) (xy 218.656626 -124.33783)
			(xy 218.635362 -124.33783) (xy 218.62542 -124.341636) (xy 218.582759 -124.359884) (xy 218.494466 -124.388427)
			(xy 218.403681 -124.407619) (xy 218.31139 -124.417251) (xy 218.264994 -124.417836) (xy 218.218598 -124.417253)
			(xy 218.12631 -124.407607) (xy 218.035526 -124.388412) (xy 217.947233 -124.359874) (xy 217.904568 -124.341636)
			(xy 217.894626 -124.33783) (xy 217.873362 -124.33783) (xy 217.86342 -124.341636) (xy 217.820759 -124.359884)
			(xy 217.732466 -124.388427) (xy 217.641681 -124.407619) (xy 217.54939 -124.417251) (xy 217.502994 -124.417836)
			(xy 217.456598 -124.417253) (xy 217.36431 -124.407607) (xy 217.273526 -124.388412) (xy 217.185233 -124.359874)
			(xy 217.142568 -124.341636) (xy 217.132626 -124.33783) (xy 217.111362 -124.33783) (xy 217.10142 -124.341636)
			(xy 217.058759 -124.359884) (xy 216.970466 -124.388427) (xy 216.879681 -124.407619) (xy 216.78739 -124.417251)
			(xy 216.740994 -124.417836) (xy 216.699886 -124.417393) (xy 216.618022 -124.409808) (xy 216.537206 -124.394703)
			(xy 216.458128 -124.372207) (xy 216.381463 -124.342511) (xy 216.307865 -124.30587) (xy 216.23796 -124.262595)
			(xy 216.172346 -124.213056) (xy 216.111582 -124.157675) (xy 216.056186 -124.096925) (xy 216.00663 -124.031323)
			(xy 215.963338 -123.961429) (xy 215.926678 -123.88784) (xy 215.896964 -123.811182) (xy 215.874448 -123.73211)
			(xy 215.859323 -123.651298) (xy 215.851717 -123.569436) (xy 215.851232 -123.528328) (xy 215.851707 -123.486851)
			(xy 215.859448 -123.404258) (xy 215.874846 -123.322745) (xy 215.897768 -123.24302) (xy 215.912446 -123.204224)
			(xy 215.915622 -123.194726) (xy 215.915236 -123.174725) (xy 215.911684 -123.165362) (xy 215.893922 -123.123209)
			(xy 215.866157 -123.036047) (xy 215.847484 -122.946496) (xy 215.838099 -122.855501) (xy 215.837516 -122.809762)
			(xy 208.574132 -122.809762) (xy 208.573649 -122.851239) (xy 208.56591 -122.933831) (xy 208.550514 -123.015344)
			(xy 208.527595 -123.09507) (xy 208.512918 -123.133866) (xy 208.509744 -123.143365) (xy 208.510127 -123.163365)
			(xy 208.51368 -123.172728) (xy 208.531436 -123.214883) (xy 208.559204 -123.302044) (xy 208.577878 -123.391595)
			(xy 208.587264 -123.482589) (xy 208.587848 -123.528328) (xy 208.587374 -123.569438) (xy 208.579784 -123.651307)
			(xy 208.564672 -123.732126) (xy 208.542166 -123.811205) (xy 208.512459 -123.887871) (xy 208.475803 -123.961467)
			(xy 208.432513 -124.031368) (xy 208.382957 -124.096975) (xy 208.327557 -124.157729) (xy 208.266788 -124.213111)
			(xy 208.201168 -124.26265) (xy 208.131256 -124.305921) (xy 208.057649 -124.342556) (xy 207.980976 -124.372243)
			(xy 207.90189 -124.394727) (xy 207.821067 -124.409818) (xy 207.739196 -124.417385) (xy 207.698086 -124.417836)
			(xy 207.65169 -124.417256) (xy 207.559402 -124.407609) (xy 207.468618 -124.388413) (xy 207.380325 -124.359874)
			(xy 207.33766 -124.341636) (xy 207.327718 -124.33783) (xy 207.306454 -124.33783) (xy 207.296512 -124.341636)
			(xy 207.253852 -124.359887) (xy 207.165559 -124.388429) (xy 207.074773 -124.40762) (xy 206.982482 -124.417252)
			(xy 206.936086 -124.417836) (xy 206.88969 -124.417256) (xy 206.797402 -124.407609) (xy 206.706618 -124.388413)
			(xy 206.618325 -124.359874) (xy 206.57566 -124.341636) (xy 206.565718 -124.33783) (xy 206.544454 -124.33783)
			(xy 206.534512 -124.341636) (xy 206.491852 -124.359887) (xy 206.403559 -124.388429) (xy 206.312773 -124.40762)
			(xy 206.220482 -124.417252) (xy 206.174086 -124.417836) (xy 206.12769 -124.417256) (xy 206.035402 -124.407609)
			(xy 205.944618 -124.388413) (xy 205.856325 -124.359874) (xy 205.81366 -124.341636) (xy 205.803718 -124.33783)
			(xy 205.782454 -124.33783) (xy 205.772512 -124.341636) (xy 205.729852 -124.359887) (xy 205.641559 -124.388429)
			(xy 205.550773 -124.40762) (xy 205.458482 -124.417252) (xy 205.412086 -124.417836) (xy 205.36569 -124.417256)
			(xy 205.273402 -124.407609) (xy 205.182618 -124.388413) (xy 205.094325 -124.359874) (xy 205.05166 -124.341636)
			(xy 205.041718 -124.33783) (xy 205.020454 -124.33783) (xy 205.010512 -124.341636) (xy 204.967852 -124.359887)
			(xy 204.879559 -124.388429) (xy 204.788773 -124.40762) (xy 204.696482 -124.417252) (xy 204.650086 -124.417836)
			(xy 204.60369 -124.417256) (xy 204.511402 -124.407609) (xy 204.420618 -124.388413) (xy 204.332325 -124.359874)
			(xy 204.28966 -124.341636) (xy 204.279718 -124.33783) (xy 204.258454 -124.33783) (xy 204.248512 -124.341636)
			(xy 204.205852 -124.359887) (xy 204.117559 -124.388429) (xy 204.026773 -124.40762) (xy 203.934482 -124.417252)
			(xy 203.888086 -124.417836) (xy 203.84169 -124.417256) (xy 203.749402 -124.407609) (xy 203.658618 -124.388413)
			(xy 203.570325 -124.359874) (xy 203.52766 -124.341636) (xy 203.517718 -124.33783) (xy 203.496454 -124.33783)
			(xy 203.486512 -124.341636) (xy 203.443852 -124.359887) (xy 203.355559 -124.388429) (xy 203.264773 -124.40762)
			(xy 203.172482 -124.417252) (xy 203.126086 -124.417836) (xy 203.07969 -124.417256) (xy 202.987402 -124.407609)
			(xy 202.896618 -124.388413) (xy 202.808325 -124.359874) (xy 202.76566 -124.341636) (xy 202.755718 -124.33783)
			(xy 202.734454 -124.33783) (xy 202.724512 -124.341636) (xy 202.681852 -124.359887) (xy 202.593559 -124.388429)
			(xy 202.502773 -124.40762) (xy 202.410482 -124.417252) (xy 202.364086 -124.417836) (xy 202.322978 -124.417401)
			(xy 202.241113 -124.409815) (xy 202.160298 -124.394709) (xy 202.08122 -124.372212) (xy 202.004555 -124.342516)
			(xy 201.930956 -124.305875) (xy 201.861052 -124.262599) (xy 201.795437 -124.21306) (xy 201.734673 -124.157678)
			(xy 201.679277 -124.096927) (xy 201.629722 -124.031325) (xy 201.58643 -123.961431) (xy 201.54977 -123.887841)
			(xy 201.520056 -123.811183) (xy 201.49754 -123.732111) (xy 201.482415 -123.651299) (xy 201.474809 -123.569436)
			(xy 201.474324 -123.528328) (xy 201.4748 -123.486851) (xy 201.48254 -123.404258) (xy 201.497938 -123.322745)
			(xy 201.52086 -123.24302) (xy 201.535538 -123.204224) (xy 201.538714 -123.194726) (xy 201.538328 -123.174725)
			(xy 201.534776 -123.165362) (xy 201.517014 -123.123209) (xy 201.489249 -123.036047) (xy 201.470576 -122.946496)
			(xy 201.461191 -122.855501) (xy 201.460608 -122.809762) (xy 185.330851 -122.809762) (xy 185.308717 -122.822218)
			(xy 185.200319 -122.874105) (xy 185.088729 -122.918714) (xy 184.974435 -122.95585) (xy 184.857936 -122.985352)
			(xy 184.739742 -123.007089) (xy 184.62037 -123.020968) (xy 184.500342 -123.026927) (xy 184.380183 -123.02494)
			(xy 184.260417 -123.015016) (xy 184.141569 -122.997198) (xy 184.024159 -122.971564) (xy 183.908699 -122.938227)
			(xy 183.795695 -122.897332) (xy 183.685641 -122.849058) (xy 183.579018 -122.793616) (xy 183.476293 -122.731248)
			(xy 183.377914 -122.662227) (xy 183.284311 -122.586856) (xy 183.195895 -122.505463) (xy 183.113051 -122.418404)
			(xy 183.036142 -122.326061) (xy 182.965505 -122.228837) (xy 182.901447 -122.127156) (xy 182.84425 -122.021465)
			(xy 182.794162 -121.912224) (xy 182.751405 -121.799912) (xy 182.716163 -121.685019) (xy 182.688592 -121.568048)
			(xy 182.668811 -121.449511) (xy 182.656908 -121.329926) (xy 182.652935 -121.209816) (xy 146.286982 -121.209816)
			(xy 146.286485 -121.269904) (xy 146.278543 -121.389817) (xy 146.262693 -121.508943) (xy 146.239004 -121.626762)
			(xy 146.20758 -121.742757) (xy 146.168559 -121.856421) (xy 146.122111 -121.967258) (xy 146.06844 -122.074783)
			(xy 146.007779 -122.178526) (xy 145.940394 -122.278033) (xy 145.866581 -122.372869) (xy 145.786661 -122.462619)
			(xy 145.700984 -122.54689) (xy 145.609925 -122.625316) (xy 145.513881 -122.697551) (xy 145.413274 -122.763281)
			(xy 145.308543 -122.822218) (xy 145.200145 -122.874105) (xy 145.088555 -122.918714) (xy 144.974261 -122.95585)
			(xy 144.857762 -122.985352) (xy 144.739568 -123.007089) (xy 144.620196 -123.020968) (xy 144.500168 -123.026927)
			(xy 144.380009 -123.02494) (xy 144.260243 -123.015016) (xy 144.141395 -122.997198) (xy 144.023985 -122.971564)
			(xy 143.908525 -122.938227) (xy 143.795521 -122.897332) (xy 143.685467 -122.849058) (xy 143.578844 -122.793616)
			(xy 143.476119 -122.731248) (xy 143.37774 -122.662227) (xy 143.284137 -122.586856) (xy 143.195721 -122.505463)
			(xy 143.112877 -122.418404) (xy 143.035968 -122.326061) (xy 142.965331 -122.228837) (xy 142.901273 -122.127156)
			(xy 142.844076 -122.021465) (xy 142.793988 -121.912224) (xy 142.751231 -121.799912) (xy 142.715989 -121.685019)
			(xy 142.688418 -121.568048) (xy 142.668637 -121.449511) (xy 142.656734 -121.329926) (xy 142.652761 -121.209816)
			(xy 106.286808 -121.209816) (xy 106.286311 -121.269904) (xy 106.278369 -121.389817) (xy 106.262519 -121.508943)
			(xy 106.23883 -121.626762) (xy 106.207406 -121.742757) (xy 106.168385 -121.856421) (xy 106.121937 -121.967258)
			(xy 106.068266 -122.074783) (xy 106.007605 -122.178526) (xy 105.94022 -122.278033) (xy 105.866407 -122.372869)
			(xy 105.786487 -122.462619) (xy 105.70081 -122.54689) (xy 105.609751 -122.625316) (xy 105.513707 -122.697551)
			(xy 105.4131 -122.763281) (xy 105.308369 -122.822218) (xy 105.199971 -122.874105) (xy 105.088381 -122.918714)
			(xy 104.974087 -122.95585) (xy 104.857588 -122.985352) (xy 104.739394 -123.007089) (xy 104.620022 -123.020968)
			(xy 104.499994 -123.026927) (xy 104.379835 -123.02494) (xy 104.260069 -123.015016) (xy 104.141221 -122.997198)
			(xy 104.023811 -122.971564) (xy 103.908351 -122.938227) (xy 103.795347 -122.897332) (xy 103.685293 -122.849058)
			(xy 103.57867 -122.793616) (xy 103.475945 -122.731248) (xy 103.377566 -122.662227) (xy 103.283963 -122.586856)
			(xy 103.195547 -122.505463) (xy 103.112703 -122.418404) (xy 103.035794 -122.326061) (xy 102.965157 -122.228837)
			(xy 102.901099 -122.127156) (xy 102.843902 -122.021465) (xy 102.793814 -121.912224) (xy 102.751057 -121.799912)
			(xy 102.715815 -121.685019) (xy 102.688244 -121.568048) (xy 102.668463 -121.449511) (xy 102.65656 -121.329926)
			(xy 102.652587 -121.209816) (xy 66.286888 -121.209816) (xy 66.286391 -121.269904) (xy 66.278449 -121.389817)
			(xy 66.262599 -121.508943) (xy 66.23891 -121.626762) (xy 66.207486 -121.742757) (xy 66.168465 -121.856421)
			(xy 66.122017 -121.967258) (xy 66.068346 -122.074783) (xy 66.007685 -122.178526) (xy 65.9403 -122.278033)
			(xy 65.866487 -122.372869) (xy 65.786567 -122.462619) (xy 65.70089 -122.54689) (xy 65.609831 -122.625316)
			(xy 65.513787 -122.697551) (xy 65.41318 -122.763281) (xy 65.308449 -122.822218) (xy 65.200051 -122.874105)
			(xy 65.088461 -122.918714) (xy 64.974167 -122.95585) (xy 64.857668 -122.985352) (xy 64.739474 -123.007089)
			(xy 64.620102 -123.020968) (xy 64.500074 -123.026927) (xy 64.379915 -123.02494) (xy 64.260149 -123.015016)
			(xy 64.141301 -122.997198) (xy 64.023891 -122.971564) (xy 63.908431 -122.938227) (xy 63.795427 -122.897332)
			(xy 63.685373 -122.849058) (xy 63.57875 -122.793616) (xy 63.476025 -122.731248) (xy 63.377646 -122.662227)
			(xy 63.284043 -122.586856) (xy 63.195627 -122.505463) (xy 63.112783 -122.418404) (xy 63.035874 -122.326061)
			(xy 62.965237 -122.228837) (xy 62.901179 -122.127156) (xy 62.843982 -122.021465) (xy 62.793894 -121.912224)
			(xy 62.751137 -121.799912) (xy 62.715895 -121.685019) (xy 62.688324 -121.568048) (xy 62.668543 -121.449511)
			(xy 62.65664 -121.329926) (xy 62.652667 -121.209816) (xy 29.791898 -121.209816) (xy 29.85764 -121.327499)
			(xy 29.919311 -121.454246) (xy 29.973712 -121.584279) (xy 30.02067 -121.717182) (xy 30.060033 -121.852528)
			(xy 30.091676 -121.989885) (xy 30.115498 -122.128812) (xy 30.131421 -122.268864) (xy 30.139396 -122.409593)
			(xy 30.139894 -122.48007) (xy 30.139396 -122.550547) (xy 30.131421 -122.691276) (xy 30.115498 -122.831328)
			(xy 30.091676 -122.970255) (xy 30.060033 -123.107612) (xy 30.02067 -123.242958) (xy 29.973712 -123.375861)
			(xy 29.919311 -123.505894) (xy 29.85764 -123.632641) (xy 29.788897 -123.755696) (xy 29.713303 -123.874665)
			(xy 29.631099 -123.989167) (xy 29.542548 -124.098835) (xy 29.447935 -124.203317) (xy 29.347563 -124.302279)
			(xy 29.241752 -124.395404) (xy 29.130843 -124.482393) (xy 29.015189 -124.562969) (xy 28.895163 -124.636872)
			(xy 28.771147 -124.703867) (xy 28.64354 -124.763738) (xy 28.51275 -124.816294) (xy 28.379196 -124.861366)
			(xy 28.243306 -124.89881) (xy 28.105515 -124.928506) (xy 27.966265 -124.950359) (xy 27.826002 -124.964299)
			(xy 27.685174 -124.970282) (xy 27.544234 -124.968287) (xy 27.403632 -124.958322) (xy 27.263819 -124.940418)
			(xy 27.125243 -124.914633) (xy 26.988348 -124.88105) (xy 26.853572 -124.839775) (xy 26.721347 -124.790941)
			(xy 26.592097 -124.734706) (xy 26.466235 -124.671247) (xy 26.344165 -124.60077) (xy 26.226278 -124.5235)
			(xy 26.112951 -124.439683) (xy 26.004547 -124.34959) (xy 25.901415 -124.253508) (xy 25.803883 -124.151745)
			(xy 25.712264 -124.044627) (xy 25.626853 -123.932498) (xy 25.547922 -123.815716) (xy 25.475724 -123.694655)
			(xy 25.410492 -123.569704) (xy 25.352432 -123.441262) (xy 25.301732 -123.309742) (xy 25.258555 -123.175563)
			(xy 25.223037 -123.039157) (xy 25.195294 -122.90096) (xy 25.175414 -122.761415) (xy 25.16346 -122.620968)
			(xy 25.159471 -122.48007) (xy 25.043387 -122.48007) (xy 25.043387 -122.570147) (xy 25.035304 -122.750119)
			(xy 25.019155 -122.929548) (xy 24.994973 -123.108071) (xy 24.962805 -123.28533) (xy 24.922717 -123.460967)
			(xy 24.87479 -123.634628) (xy 24.819119 -123.805965) (xy 24.755817 -123.974631) (xy 24.685013 -124.140287)
			(xy 24.606847 -124.3026) (xy 24.521478 -124.461243) (xy 24.429077 -124.615895) (xy 24.329831 -124.766247)
			(xy 24.223939 -124.911994) (xy 24.111615 -125.052844) (xy 23.993085 -125.188513) (xy 23.868587 -125.318727)
			(xy 23.738373 -125.443225) (xy 23.602704 -125.561755) (xy 23.461854 -125.674079) (xy 23.316107 -125.779971)
			(xy 23.165755 -125.879217) (xy 23.011103 -125.971618) (xy 22.85246 -126.056987) (xy 22.690147 -126.135153)
			(xy 22.524491 -126.205957) (xy 22.355825 -126.269259) (xy 22.184488 -126.32493) (xy 22.010827 -126.372857)
			(xy 21.83519 -126.412945) (xy 21.657931 -126.445113) (xy 21.479408 -126.469295) (xy 21.299979 -126.485444)
			(xy 21.154006 -126.492) (xy 42.020472 -126.492) (xy 42.024502 -126.407397) (xy 42.036556 -126.32356)
			(xy 42.056525 -126.241249) (xy 42.084227 -126.161209) (xy 42.119412 -126.084164) (xy 42.161762 -126.010813)
			(xy 42.210892 -125.941819) (xy 42.266358 -125.877808) (xy 42.327658 -125.81936) (xy 42.394236 -125.767002)
			(xy 42.465489 -125.721211) (xy 42.540773 -125.6824) (xy 42.619405 -125.650921) (xy 42.700673 -125.627059)
			(xy 42.783841 -125.61103) (xy 42.868157 -125.60298) (xy 42.910506 -125.602492) (xy 42.956902 -125.603073)
			(xy 43.04919 -125.612718) (xy 43.139974 -125.631915) (xy 43.228267 -125.660454) (xy 43.270932 -125.678692)
			(xy 43.280874 -125.682498) (xy 43.302138 -125.682498) (xy 43.31208 -125.678692) (xy 43.354741 -125.660445)
			(xy 43.443034 -125.631902) (xy 43.533819 -125.612709) (xy 43.62611 -125.603077) (xy 43.672506 -125.602492)
			(xy 43.714854 -125.602996) (xy 43.799167 -125.611047) (xy 43.882333 -125.627077) (xy 43.963599 -125.650939)
			(xy 44.042229 -125.682418) (xy 44.11751 -125.721229) (xy 44.188761 -125.767019) (xy 44.255337 -125.819376)
			(xy 44.316634 -125.877823) (xy 44.372099 -125.941833) (xy 44.421227 -126.010825) (xy 44.463575 -126.084174)
			(xy 44.49876 -126.161217) (xy 44.526461 -126.241256) (xy 44.546429 -126.323565) (xy 44.558482 -126.407399)
			(xy 44.562513 -126.492) (xy 54.212472 -126.492) (xy 54.216502 -126.407397) (xy 54.228556 -126.32356)
			(xy 54.248525 -126.241249) (xy 54.276227 -126.161209) (xy 54.311412 -126.084164) (xy 54.353762 -126.010813)
			(xy 54.402892 -125.941819) (xy 54.458358 -125.877808) (xy 54.519658 -125.81936) (xy 54.586236 -125.767002)
			(xy 54.657489 -125.721211) (xy 54.732773 -125.6824) (xy 54.811405 -125.650921) (xy 54.892673 -125.627059)
			(xy 54.975841 -125.61103) (xy 55.060157 -125.60298) (xy 55.102506 -125.602492) (xy 55.148902 -125.603073)
			(xy 55.24119 -125.612718) (xy 55.331974 -125.631915) (xy 55.420267 -125.660454) (xy 55.462932 -125.678692)
			(xy 55.472874 -125.682498) (xy 55.494138 -125.682498) (xy 55.50408 -125.678692) (xy 55.546741 -125.660445)
			(xy 55.635034 -125.631902) (xy 55.725819 -125.612709) (xy 55.81811 -125.603077) (xy 55.864506 -125.602492)
			(xy 55.906854 -125.602996) (xy 55.991167 -125.611047) (xy 56.074333 -125.627077) (xy 56.155599 -125.650939)
			(xy 56.234229 -125.682418) (xy 56.30951 -125.721229) (xy 56.380761 -125.767019) (xy 56.447337 -125.819376)
			(xy 56.508634 -125.877823) (xy 56.564099 -125.941833) (xy 56.613227 -126.010825) (xy 56.655575 -126.084174)
			(xy 56.69076 -126.161217) (xy 56.718461 -126.241256) (xy 56.738429 -126.323565) (xy 56.750482 -126.407399)
			(xy 56.754513 -126.492) (xy 66.404472 -126.492) (xy 66.408502 -126.407397) (xy 66.420556 -126.32356)
			(xy 66.440525 -126.241249) (xy 66.468227 -126.161209) (xy 66.503412 -126.084164) (xy 66.545762 -126.010813)
			(xy 66.594892 -125.941819) (xy 66.650358 -125.877808) (xy 66.711658 -125.81936) (xy 66.778236 -125.767002)
			(xy 66.849489 -125.721211) (xy 66.924773 -125.6824) (xy 67.003405 -125.650921) (xy 67.084673 -125.627059)
			(xy 67.167841 -125.61103) (xy 67.252157 -125.60298) (xy 67.294506 -125.602492) (xy 67.340902 -125.603073)
			(xy 67.43319 -125.612718) (xy 67.523974 -125.631915) (xy 67.612267 -125.660454) (xy 67.654932 -125.678692)
			(xy 67.664874 -125.682498) (xy 67.686138 -125.682498) (xy 67.69608 -125.678692) (xy 67.738741 -125.660445)
			(xy 67.827034 -125.631902) (xy 67.917819 -125.612709) (xy 68.01011 -125.603077) (xy 68.056506 -125.602492)
			(xy 68.098854 -125.602996) (xy 68.183167 -125.611047) (xy 68.266333 -125.627077) (xy 68.347599 -125.650939)
			(xy 68.426229 -125.682418) (xy 68.50151 -125.721229) (xy 68.572761 -125.767019) (xy 68.639337 -125.819376)
			(xy 68.700634 -125.877823) (xy 68.756099 -125.941833) (xy 68.805227 -126.010825) (xy 68.847575 -126.084174)
			(xy 68.88276 -126.161217) (xy 68.910461 -126.241256) (xy 68.930429 -126.323565) (xy 68.942482 -126.407399)
			(xy 68.946513 -126.492) (xy 82.020372 -126.492) (xy 82.024402 -126.407396) (xy 82.036457 -126.323558)
			(xy 82.056426 -126.241246) (xy 82.084129 -126.161204) (xy 82.119315 -126.084159) (xy 82.161666 -126.010807)
			(xy 82.210798 -125.941813) (xy 82.266265 -125.877801) (xy 82.327566 -125.819352) (xy 82.394146 -125.766995)
			(xy 82.465401 -125.721204) (xy 82.540686 -125.682394) (xy 82.61932 -125.650916) (xy 82.700589 -125.627055)
			(xy 82.783759 -125.611028) (xy 82.868076 -125.602979) (xy 82.910426 -125.602492) (xy 82.956821 -125.603101)
			(xy 83.049109 -125.612738) (xy 83.139892 -125.631927) (xy 83.228187 -125.660458) (xy 83.270852 -125.678692)
			(xy 83.280794 -125.682498) (xy 83.302058 -125.682498) (xy 83.312 -125.678692) (xy 83.354659 -125.660439)
			(xy 83.442952 -125.631897) (xy 83.533738 -125.612706) (xy 83.62603 -125.603076) (xy 83.672426 -125.602492)
			(xy 83.714774 -125.602997) (xy 83.799085 -125.61105) (xy 83.88225 -125.627081) (xy 83.963514 -125.650944)
			(xy 84.042142 -125.682424) (xy 84.117421 -125.721235) (xy 84.188671 -125.767026) (xy 84.255245 -125.819383)
			(xy 84.316541 -125.87783) (xy 84.372004 -125.941839) (xy 84.421131 -126.010831) (xy 84.463478 -126.08418)
			(xy 84.498661 -126.161222) (xy 84.526362 -126.241259) (xy 84.546329 -126.323567) (xy 84.558383 -126.407401)
			(xy 84.562413 -126.492) (xy 94.212372 -126.492) (xy 94.216402 -126.407396) (xy 94.228457 -126.323558)
			(xy 94.248426 -126.241246) (xy 94.276129 -126.161204) (xy 94.311315 -126.084159) (xy 94.353666 -126.010807)
			(xy 94.402798 -125.941813) (xy 94.458265 -125.877801) (xy 94.519566 -125.819352) (xy 94.586146 -125.766995)
			(xy 94.657401 -125.721204) (xy 94.732686 -125.682394) (xy 94.81132 -125.650916) (xy 94.892589 -125.627055)
			(xy 94.975759 -125.611028) (xy 95.060076 -125.602979) (xy 95.102426 -125.602492) (xy 95.148821 -125.603101)
			(xy 95.241109 -125.612738) (xy 95.331892 -125.631927) (xy 95.420187 -125.660458) (xy 95.462852 -125.678692)
			(xy 95.472794 -125.682498) (xy 95.494058 -125.682498) (xy 95.504 -125.678692) (xy 95.546659 -125.660439)
			(xy 95.634952 -125.631897) (xy 95.725738 -125.612706) (xy 95.81803 -125.603076) (xy 95.864426 -125.602492)
			(xy 95.906774 -125.602997) (xy 95.991085 -125.61105) (xy 96.07425 -125.627081) (xy 96.155514 -125.650944)
			(xy 96.234142 -125.682424) (xy 96.309421 -125.721235) (xy 96.380671 -125.767026) (xy 96.447245 -125.819383)
			(xy 96.508541 -125.87783) (xy 96.564004 -125.941839) (xy 96.613131 -126.010831) (xy 96.655478 -126.08418)
			(xy 96.690661 -126.161222) (xy 96.718362 -126.241259) (xy 96.738329 -126.323567) (xy 96.750383 -126.407401)
			(xy 96.754413 -126.492) (xy 106.404372 -126.492) (xy 106.408402 -126.407396) (xy 106.420457 -126.323558)
			(xy 106.440426 -126.241246) (xy 106.468129 -126.161204) (xy 106.503315 -126.084159) (xy 106.545666 -126.010807)
			(xy 106.594798 -125.941813) (xy 106.650265 -125.877801) (xy 106.711566 -125.819352) (xy 106.778146 -125.766995)
			(xy 106.849401 -125.721204) (xy 106.924686 -125.682394) (xy 107.00332 -125.650916) (xy 107.084589 -125.627055)
			(xy 107.167759 -125.611028) (xy 107.252076 -125.602979) (xy 107.294426 -125.602492) (xy 107.340821 -125.603101)
			(xy 107.433109 -125.612738) (xy 107.523892 -125.631927) (xy 107.612187 -125.660458) (xy 107.654852 -125.678692)
			(xy 107.664794 -125.682498) (xy 107.686058 -125.682498) (xy 107.696 -125.678692) (xy 107.738659 -125.660439)
			(xy 107.826952 -125.631897) (xy 107.917738 -125.612706) (xy 108.01003 -125.603076) (xy 108.056426 -125.602492)
			(xy 108.098774 -125.602997) (xy 108.183085 -125.61105) (xy 108.26625 -125.627081) (xy 108.347514 -125.650944)
			(xy 108.426142 -125.682424) (xy 108.501421 -125.721235) (xy 108.572671 -125.767026) (xy 108.639245 -125.819383)
			(xy 108.700541 -125.87783) (xy 108.756004 -125.941839) (xy 108.805131 -126.010831) (xy 108.847478 -126.08418)
			(xy 108.882661 -126.161222) (xy 108.910362 -126.241259) (xy 108.930329 -126.323567) (xy 108.942383 -126.407401)
			(xy 108.946413 -126.492) (xy 122.020588 -126.492) (xy 122.024618 -126.407399) (xy 122.036671 -126.323564)
			(xy 122.056639 -126.241255) (xy 122.084341 -126.161216) (xy 122.119525 -126.084173) (xy 122.161874 -126.010823)
			(xy 122.211003 -125.941831) (xy 122.266468 -125.877821) (xy 122.327766 -125.819373) (xy 122.394342 -125.767017)
			(xy 122.465594 -125.721227) (xy 122.540875 -125.682416) (xy 122.619505 -125.650937) (xy 122.700772 -125.627076)
			(xy 122.783938 -125.611047) (xy 122.868252 -125.602996) (xy 122.9106 -125.602492) (xy 122.956996 -125.603075)
			(xy 123.049284 -125.61272) (xy 123.140068 -125.631916) (xy 123.228361 -125.660454) (xy 123.271026 -125.678692)
			(xy 123.280968 -125.682498) (xy 123.302232 -125.682498) (xy 123.312174 -125.678692) (xy 123.354836 -125.660447)
			(xy 123.443129 -125.631903) (xy 123.533914 -125.61271) (xy 123.626204 -125.603077) (xy 123.6726 -125.602492)
			(xy 123.714948 -125.602996) (xy 123.799262 -125.611047) (xy 123.882428 -125.627076) (xy 123.963695 -125.650937)
			(xy 124.042325 -125.682416) (xy 124.117606 -125.721227) (xy 124.188858 -125.767017) (xy 124.255434 -125.819373)
			(xy 124.316732 -125.877821) (xy 124.372197 -125.941831) (xy 124.421326 -126.010823) (xy 124.463675 -126.084173)
			(xy 124.498859 -126.161216) (xy 124.526561 -126.241255) (xy 124.546529 -126.323564) (xy 124.558582 -126.407399)
			(xy 124.562613 -126.492) (xy 134.212588 -126.492) (xy 134.216618 -126.407399) (xy 134.228671 -126.323564)
			(xy 134.248639 -126.241255) (xy 134.276341 -126.161216) (xy 134.311525 -126.084173) (xy 134.353874 -126.010823)
			(xy 134.403003 -125.941831) (xy 134.458468 -125.877821) (xy 134.519766 -125.819373) (xy 134.586342 -125.767017)
			(xy 134.657594 -125.721227) (xy 134.732875 -125.682416) (xy 134.811505 -125.650937) (xy 134.892772 -125.627076)
			(xy 134.975938 -125.611047) (xy 135.060252 -125.602996) (xy 135.1026 -125.602492) (xy 135.148996 -125.603075)
			(xy 135.241284 -125.61272) (xy 135.332068 -125.631916) (xy 135.420361 -125.660454) (xy 135.463026 -125.678692)
			(xy 135.472968 -125.682498) (xy 135.494232 -125.682498) (xy 135.504174 -125.678692) (xy 135.546836 -125.660447)
			(xy 135.635129 -125.631903) (xy 135.725914 -125.61271) (xy 135.818204 -125.603077) (xy 135.8646 -125.602492)
			(xy 135.906948 -125.602996) (xy 135.991262 -125.611047) (xy 136.074428 -125.627076) (xy 136.155695 -125.650937)
			(xy 136.234325 -125.682416) (xy 136.309606 -125.721227) (xy 136.380858 -125.767017) (xy 136.447434 -125.819373)
			(xy 136.508732 -125.877821) (xy 136.564197 -125.941831) (xy 136.613326 -126.010823) (xy 136.655675 -126.084173)
			(xy 136.690859 -126.161216) (xy 136.718561 -126.241255) (xy 136.738529 -126.323564) (xy 136.750582 -126.407399)
			(xy 136.754613 -126.492) (xy 146.404588 -126.492) (xy 146.408618 -126.407399) (xy 146.420671 -126.323564)
			(xy 146.440639 -126.241255) (xy 146.468341 -126.161216) (xy 146.503525 -126.084173) (xy 146.545874 -126.010823)
			(xy 146.595003 -125.941831) (xy 146.650468 -125.877821) (xy 146.711766 -125.819373) (xy 146.778342 -125.767017)
			(xy 146.849594 -125.721227) (xy 146.924875 -125.682416) (xy 147.003505 -125.650937) (xy 147.084772 -125.627076)
			(xy 147.167938 -125.611047) (xy 147.252252 -125.602996) (xy 147.2946 -125.602492) (xy 147.340996 -125.603075)
			(xy 147.433284 -125.61272) (xy 147.524068 -125.631916) (xy 147.612361 -125.660454) (xy 147.655026 -125.678692)
			(xy 147.664968 -125.682498) (xy 147.686232 -125.682498) (xy 147.696174 -125.678692) (xy 147.738836 -125.660447)
			(xy 147.827129 -125.631903) (xy 147.917914 -125.61271) (xy 148.010204 -125.603077) (xy 148.0566 -125.602492)
			(xy 148.098948 -125.602996) (xy 148.183262 -125.611047) (xy 148.266428 -125.627076) (xy 148.347695 -125.650937)
			(xy 148.426325 -125.682416) (xy 148.501606 -125.721227) (xy 148.572858 -125.767017) (xy 148.639434 -125.819373)
			(xy 148.700732 -125.877821) (xy 148.756197 -125.941831) (xy 148.805326 -126.010823) (xy 148.847675 -126.084173)
			(xy 148.882859 -126.161216) (xy 148.910561 -126.241255) (xy 148.930529 -126.323564) (xy 148.942582 -126.407399)
			(xy 148.946613 -126.492) (xy 162.020787 -126.492) (xy 162.024817 -126.407401) (xy 162.036871 -126.323567)
			(xy 162.056838 -126.241259) (xy 162.084539 -126.161222) (xy 162.119722 -126.08418) (xy 162.162069 -126.010831)
			(xy 162.211196 -125.941839) (xy 162.266659 -125.87783) (xy 162.327955 -125.819383) (xy 162.394529 -125.767026)
			(xy 162.465779 -125.721235) (xy 162.541058 -125.682424) (xy 162.619686 -125.650944) (xy 162.70095 -125.627081)
			(xy 162.784115 -125.61105) (xy 162.868426 -125.602997) (xy 162.910774 -125.602492) (xy 162.957169 -125.603084)
			(xy 163.049457 -125.612726) (xy 163.140241 -125.63192) (xy 163.228535 -125.660455) (xy 163.2712 -125.678692)
			(xy 163.281142 -125.682498) (xy 163.302406 -125.682498) (xy 163.312348 -125.678692) (xy 163.355014 -125.660456)
			(xy 163.443305 -125.63191) (xy 163.534089 -125.612714) (xy 163.626378 -125.603078) (xy 163.672774 -125.602492)
			(xy 163.715124 -125.602979) (xy 163.799441 -125.611028) (xy 163.882611 -125.627055) (xy 163.96388 -125.650916)
			(xy 164.042514 -125.682394) (xy 164.117799 -125.721204) (xy 164.189054 -125.766995) (xy 164.255634 -125.819352)
			(xy 164.316935 -125.877801) (xy 164.372402 -125.941813) (xy 164.421534 -126.010807) (xy 164.463885 -126.084159)
			(xy 164.499071 -126.161204) (xy 164.526774 -126.241246) (xy 164.546743 -126.323558) (xy 164.558798 -126.407396)
			(xy 164.562828 -126.492) (xy 174.212787 -126.492) (xy 174.216817 -126.407401) (xy 174.228871 -126.323567)
			(xy 174.248838 -126.241259) (xy 174.276539 -126.161222) (xy 174.311722 -126.08418) (xy 174.354069 -126.010831)
			(xy 174.403196 -125.941839) (xy 174.458659 -125.87783) (xy 174.519955 -125.819383) (xy 174.586529 -125.767026)
			(xy 174.657779 -125.721235) (xy 174.733058 -125.682424) (xy 174.811686 -125.650944) (xy 174.89295 -125.627081)
			(xy 174.976115 -125.61105) (xy 175.060426 -125.602997) (xy 175.102774 -125.602492) (xy 175.149169 -125.603084)
			(xy 175.241457 -125.612726) (xy 175.332241 -125.63192) (xy 175.420535 -125.660455) (xy 175.4632 -125.678692)
			(xy 175.473142 -125.682498) (xy 175.494406 -125.682498) (xy 175.504348 -125.678692) (xy 175.547014 -125.660456)
			(xy 175.635305 -125.63191) (xy 175.726089 -125.612714) (xy 175.818378 -125.603078) (xy 175.864774 -125.602492)
			(xy 175.907124 -125.602979) (xy 175.991441 -125.611028) (xy 176.074611 -125.627055) (xy 176.15588 -125.650916)
			(xy 176.234514 -125.682394) (xy 176.309799 -125.721204) (xy 176.381054 -125.766995) (xy 176.447634 -125.819352)
			(xy 176.508935 -125.877801) (xy 176.564402 -125.941813) (xy 176.613534 -126.010807) (xy 176.655885 -126.084159)
			(xy 176.691071 -126.161204) (xy 176.718774 -126.241246) (xy 176.738743 -126.323558) (xy 176.750798 -126.407396)
			(xy 176.754828 -126.492) (xy 186.404787 -126.492) (xy 186.408817 -126.407401) (xy 186.420871 -126.323567)
			(xy 186.440838 -126.241259) (xy 186.468539 -126.161222) (xy 186.503722 -126.08418) (xy 186.546069 -126.010831)
			(xy 186.595196 -125.941839) (xy 186.650659 -125.87783) (xy 186.711955 -125.819383) (xy 186.778529 -125.767026)
			(xy 186.849779 -125.721235) (xy 186.925058 -125.682424) (xy 187.003686 -125.650944) (xy 187.08495 -125.627081)
			(xy 187.168115 -125.61105) (xy 187.252426 -125.602997) (xy 187.294774 -125.602492) (xy 187.341169 -125.603084)
			(xy 187.433457 -125.612726) (xy 187.524241 -125.63192) (xy 187.612535 -125.660455) (xy 187.6552 -125.678692)
			(xy 187.665142 -125.682498) (xy 187.686406 -125.682498) (xy 187.696348 -125.678692) (xy 187.739014 -125.660456)
			(xy 187.827305 -125.63191) (xy 187.918089 -125.612714) (xy 188.010378 -125.603078) (xy 188.056774 -125.602492)
			(xy 188.099124 -125.602979) (xy 188.183441 -125.611028) (xy 188.266611 -125.627055) (xy 188.34788 -125.650916)
			(xy 188.426514 -125.682394) (xy 188.501799 -125.721204) (xy 188.573054 -125.766995) (xy 188.639634 -125.819352)
			(xy 188.700935 -125.877801) (xy 188.756402 -125.941813) (xy 188.805534 -126.010807) (xy 188.847885 -126.084159)
			(xy 188.883071 -126.161204) (xy 188.910774 -126.241246) (xy 188.930743 -126.323558) (xy 188.942798 -126.407396)
			(xy 188.946828 -126.492) (xy 188.942798 -126.576604) (xy 188.930743 -126.660442) (xy 188.910774 -126.742754)
			(xy 188.883071 -126.822796) (xy 188.847885 -126.899841) (xy 188.805534 -126.973193) (xy 188.756402 -127.042187)
			(xy 188.700935 -127.106199) (xy 188.639634 -127.164648) (xy 188.573054 -127.217005) (xy 188.501799 -127.262796)
			(xy 188.426514 -127.301606) (xy 188.34788 -127.333084) (xy 188.266611 -127.356945) (xy 188.183441 -127.372972)
			(xy 188.099124 -127.381021) (xy 188.056774 -127.381508) (xy 188.010379 -127.380899) (xy 187.918091 -127.371262)
			(xy 187.827308 -127.352073) (xy 187.739013 -127.323542) (xy 187.696348 -127.305308) (xy 187.686406 -127.301502)
			(xy 187.665142 -127.301502) (xy 187.6552 -127.305308) (xy 187.612541 -127.323561) (xy 187.524248 -127.352103)
			(xy 187.433462 -127.371294) (xy 187.34117 -127.380924) (xy 187.294774 -127.381508) (xy 187.252426 -127.381003)
			(xy 187.168115 -127.37295) (xy 187.08495 -127.356919) (xy 187.003686 -127.333056) (xy 186.925058 -127.301576)
			(xy 186.849779 -127.262765) (xy 186.778529 -127.216974) (xy 186.711955 -127.164617) (xy 186.650659 -127.10617)
			(xy 186.595196 -127.042161) (xy 186.546069 -126.973169) (xy 186.503722 -126.89982) (xy 186.468539 -126.822778)
			(xy 186.440838 -126.742741) (xy 186.420871 -126.660433) (xy 186.408817 -126.576599) (xy 186.404787 -126.492)
			(xy 176.754828 -126.492) (xy 176.750798 -126.576604) (xy 176.738743 -126.660442) (xy 176.718774 -126.742754)
			(xy 176.691071 -126.822796) (xy 176.655885 -126.899841) (xy 176.613534 -126.973193) (xy 176.564402 -127.042187)
			(xy 176.508935 -127.106199) (xy 176.447634 -127.164648) (xy 176.381054 -127.217005) (xy 176.309799 -127.262796)
			(xy 176.234514 -127.301606) (xy 176.15588 -127.333084) (xy 176.074611 -127.356945) (xy 175.991441 -127.372972)
			(xy 175.907124 -127.381021) (xy 175.864774 -127.381508) (xy 175.818379 -127.380899) (xy 175.726091 -127.371262)
			(xy 175.635308 -127.352073) (xy 175.547013 -127.323542) (xy 175.504348 -127.305308) (xy 175.494406 -127.301502)
			(xy 175.473142 -127.301502) (xy 175.4632 -127.305308) (xy 175.420541 -127.323561) (xy 175.332248 -127.352103)
			(xy 175.241462 -127.371294) (xy 175.14917 -127.380924) (xy 175.102774 -127.381508) (xy 175.060426 -127.381003)
			(xy 174.976115 -127.37295) (xy 174.89295 -127.356919) (xy 174.811686 -127.333056) (xy 174.733058 -127.301576)
			(xy 174.657779 -127.262765) (xy 174.586529 -127.216974) (xy 174.519955 -127.164617) (xy 174.458659 -127.10617)
			(xy 174.403196 -127.042161) (xy 174.354069 -126.973169) (xy 174.311722 -126.89982) (xy 174.276539 -126.822778)
			(xy 174.248838 -126.742741) (xy 174.228871 -126.660433) (xy 174.216817 -126.576599) (xy 174.212787 -126.492)
			(xy 164.562828 -126.492) (xy 164.558798 -126.576604) (xy 164.546743 -126.660442) (xy 164.526774 -126.742754)
			(xy 164.499071 -126.822796) (xy 164.463885 -126.899841) (xy 164.421534 -126.973193) (xy 164.372402 -127.042187)
			(xy 164.316935 -127.106199) (xy 164.255634 -127.164648) (xy 164.189054 -127.217005) (xy 164.117799 -127.262796)
			(xy 164.042514 -127.301606) (xy 163.96388 -127.333084) (xy 163.882611 -127.356945) (xy 163.799441 -127.372972)
			(xy 163.715124 -127.381021) (xy 163.672774 -127.381508) (xy 163.626379 -127.380899) (xy 163.534091 -127.371262)
			(xy 163.443308 -127.352073) (xy 163.355013 -127.323542) (xy 163.312348 -127.305308) (xy 163.302406 -127.301502)
			(xy 163.281142 -127.301502) (xy 163.2712 -127.305308) (xy 163.228541 -127.323561) (xy 163.140248 -127.352103)
			(xy 163.049462 -127.371294) (xy 162.95717 -127.380924) (xy 162.910774 -127.381508) (xy 162.868426 -127.381003)
			(xy 162.784115 -127.37295) (xy 162.70095 -127.356919) (xy 162.619686 -127.333056) (xy 162.541058 -127.301576)
			(xy 162.465779 -127.262765) (xy 162.394529 -127.216974) (xy 162.327955 -127.164617) (xy 162.266659 -127.10617)
			(xy 162.211196 -127.042161) (xy 162.162069 -126.973169) (xy 162.119722 -126.89982) (xy 162.084539 -126.822778)
			(xy 162.056838 -126.742741) (xy 162.036871 -126.660433) (xy 162.024817 -126.576599) (xy 162.020787 -126.492)
			(xy 148.946613 -126.492) (xy 148.942582 -126.576601) (xy 148.930529 -126.660436) (xy 148.910561 -126.742745)
			(xy 148.882859 -126.822784) (xy 148.847675 -126.899827) (xy 148.805326 -126.973177) (xy 148.756197 -127.042169)
			(xy 148.700732 -127.106179) (xy 148.639434 -127.164627) (xy 148.572858 -127.216983) (xy 148.501606 -127.262773)
			(xy 148.426325 -127.301584) (xy 148.347695 -127.333063) (xy 148.266428 -127.356924) (xy 148.183262 -127.372953)
			(xy 148.098948 -127.381004) (xy 148.0566 -127.381508) (xy 148.010204 -127.380925) (xy 147.917916 -127.37128)
			(xy 147.827132 -127.352084) (xy 147.738839 -127.323546) (xy 147.696174 -127.305308) (xy 147.686232 -127.301502)
			(xy 147.664968 -127.301502) (xy 147.655026 -127.305308) (xy 147.612364 -127.323553) (xy 147.524071 -127.352097)
			(xy 147.433286 -127.37129) (xy 147.340996 -127.380923) (xy 147.2946 -127.381508) (xy 147.252252 -127.381004)
			(xy 147.167938 -127.372953) (xy 147.084772 -127.356924) (xy 147.003505 -127.333063) (xy 146.924875 -127.301584)
			(xy 146.849594 -127.262773) (xy 146.778342 -127.216983) (xy 146.711766 -127.164627) (xy 146.650468 -127.106179)
			(xy 146.595003 -127.042169) (xy 146.545874 -126.973177) (xy 146.503525 -126.899827) (xy 146.468341 -126.822784)
			(xy 146.440639 -126.742745) (xy 146.420671 -126.660436) (xy 146.408618 -126.576601) (xy 146.404588 -126.492)
			(xy 136.754613 -126.492) (xy 136.750582 -126.576601) (xy 136.738529 -126.660436) (xy 136.718561 -126.742745)
			(xy 136.690859 -126.822784) (xy 136.655675 -126.899827) (xy 136.613326 -126.973177) (xy 136.564197 -127.042169)
			(xy 136.508732 -127.106179) (xy 136.447434 -127.164627) (xy 136.380858 -127.216983) (xy 136.309606 -127.262773)
			(xy 136.234325 -127.301584) (xy 136.155695 -127.333063) (xy 136.074428 -127.356924) (xy 135.991262 -127.372953)
			(xy 135.906948 -127.381004) (xy 135.8646 -127.381508) (xy 135.818204 -127.380925) (xy 135.725916 -127.37128)
			(xy 135.635132 -127.352084) (xy 135.546839 -127.323546) (xy 135.504174 -127.305308) (xy 135.494232 -127.301502)
			(xy 135.472968 -127.301502) (xy 135.463026 -127.305308) (xy 135.420364 -127.323553) (xy 135.332071 -127.352097)
			(xy 135.241286 -127.37129) (xy 135.148996 -127.380923) (xy 135.1026 -127.381508) (xy 135.060252 -127.381004)
			(xy 134.975938 -127.372953) (xy 134.892772 -127.356924) (xy 134.811505 -127.333063) (xy 134.732875 -127.301584)
			(xy 134.657594 -127.262773) (xy 134.586342 -127.216983) (xy 134.519766 -127.164627) (xy 134.458468 -127.106179)
			(xy 134.403003 -127.042169) (xy 134.353874 -126.973177) (xy 134.311525 -126.899827) (xy 134.276341 -126.822784)
			(xy 134.248639 -126.742745) (xy 134.228671 -126.660436) (xy 134.216618 -126.576601) (xy 134.212588 -126.492)
			(xy 124.562613 -126.492) (xy 124.558582 -126.576601) (xy 124.546529 -126.660436) (xy 124.526561 -126.742745)
			(xy 124.498859 -126.822784) (xy 124.463675 -126.899827) (xy 124.421326 -126.973177) (xy 124.372197 -127.042169)
			(xy 124.316732 -127.106179) (xy 124.255434 -127.164627) (xy 124.188858 -127.216983) (xy 124.117606 -127.262773)
			(xy 124.042325 -127.301584) (xy 123.963695 -127.333063) (xy 123.882428 -127.356924) (xy 123.799262 -127.372953)
			(xy 123.714948 -127.381004) (xy 123.6726 -127.381508) (xy 123.626204 -127.380925) (xy 123.533916 -127.37128)
			(xy 123.443132 -127.352084) (xy 123.354839 -127.323546) (xy 123.312174 -127.305308) (xy 123.302232 -127.301502)
			(xy 123.280968 -127.301502) (xy 123.271026 -127.305308) (xy 123.228364 -127.323553) (xy 123.140071 -127.352097)
			(xy 123.049286 -127.37129) (xy 122.956996 -127.380923) (xy 122.9106 -127.381508) (xy 122.868252 -127.381004)
			(xy 122.783938 -127.372953) (xy 122.700772 -127.356924) (xy 122.619505 -127.333063) (xy 122.540875 -127.301584)
			(xy 122.465594 -127.262773) (xy 122.394342 -127.216983) (xy 122.327766 -127.164627) (xy 122.266468 -127.106179)
			(xy 122.211003 -127.042169) (xy 122.161874 -126.973177) (xy 122.119525 -126.899827) (xy 122.084341 -126.822784)
			(xy 122.056639 -126.742745) (xy 122.036671 -126.660436) (xy 122.024618 -126.576601) (xy 122.020588 -126.492)
			(xy 108.946413 -126.492) (xy 108.942383 -126.576599) (xy 108.930329 -126.660433) (xy 108.910362 -126.742741)
			(xy 108.882661 -126.822778) (xy 108.847478 -126.89982) (xy 108.805131 -126.973169) (xy 108.756004 -127.042161)
			(xy 108.700541 -127.10617) (xy 108.639245 -127.164617) (xy 108.572671 -127.216974) (xy 108.501421 -127.262765)
			(xy 108.426142 -127.301576) (xy 108.347514 -127.333056) (xy 108.26625 -127.356919) (xy 108.183085 -127.37295)
			(xy 108.098774 -127.381003) (xy 108.056426 -127.381508) (xy 108.010031 -127.380916) (xy 107.917743 -127.371274)
			(xy 107.826959 -127.35208) (xy 107.738665 -127.323545) (xy 107.696 -127.305308) (xy 107.686058 -127.301502)
			(xy 107.664794 -127.301502) (xy 107.654852 -127.305308) (xy 107.612186 -127.323544) (xy 107.523895 -127.35209)
			(xy 107.433111 -127.371286) (xy 107.340822 -127.380922) (xy 107.294426 -127.381508) (xy 107.252076 -127.381021)
			(xy 107.167759 -127.372972) (xy 107.084589 -127.356945) (xy 107.00332 -127.333084) (xy 106.924686 -127.301606)
			(xy 106.849401 -127.262796) (xy 106.778146 -127.217005) (xy 106.711566 -127.164648) (xy 106.650265 -127.106199)
			(xy 106.594798 -127.042187) (xy 106.545666 -126.973193) (xy 106.503315 -126.899841) (xy 106.468129 -126.822796)
			(xy 106.440426 -126.742754) (xy 106.420457 -126.660442) (xy 106.408402 -126.576604) (xy 106.404372 -126.492)
			(xy 96.754413 -126.492) (xy 96.750383 -126.576599) (xy 96.738329 -126.660433) (xy 96.718362 -126.742741)
			(xy 96.690661 -126.822778) (xy 96.655478 -126.89982) (xy 96.613131 -126.973169) (xy 96.564004 -127.042161)
			(xy 96.508541 -127.10617) (xy 96.447245 -127.164617) (xy 96.380671 -127.216974) (xy 96.309421 -127.262765)
			(xy 96.234142 -127.301576) (xy 96.155514 -127.333056) (xy 96.07425 -127.356919) (xy 95.991085 -127.37295)
			(xy 95.906774 -127.381003) (xy 95.864426 -127.381508) (xy 95.818031 -127.380916) (xy 95.725743 -127.371274)
			(xy 95.634959 -127.35208) (xy 95.546665 -127.323545) (xy 95.504 -127.305308) (xy 95.494058 -127.301502)
			(xy 95.472794 -127.301502) (xy 95.462852 -127.305308) (xy 95.420186 -127.323544) (xy 95.331895 -127.35209)
			(xy 95.241111 -127.371286) (xy 95.148822 -127.380922) (xy 95.102426 -127.381508) (xy 95.060076 -127.381021)
			(xy 94.975759 -127.372972) (xy 94.892589 -127.356945) (xy 94.81132 -127.333084) (xy 94.732686 -127.301606)
			(xy 94.657401 -127.262796) (xy 94.586146 -127.217005) (xy 94.519566 -127.164648) (xy 94.458265 -127.106199)
			(xy 94.402798 -127.042187) (xy 94.353666 -126.973193) (xy 94.311315 -126.899841) (xy 94.276129 -126.822796)
			(xy 94.248426 -126.742754) (xy 94.228457 -126.660442) (xy 94.216402 -126.576604) (xy 94.212372 -126.492)
			(xy 84.562413 -126.492) (xy 84.558383 -126.576599) (xy 84.546329 -126.660433) (xy 84.526362 -126.742741)
			(xy 84.498661 -126.822778) (xy 84.463478 -126.89982) (xy 84.421131 -126.973169) (xy 84.372004 -127.042161)
			(xy 84.316541 -127.10617) (xy 84.255245 -127.164617) (xy 84.188671 -127.216974) (xy 84.117421 -127.262765)
			(xy 84.042142 -127.301576) (xy 83.963514 -127.333056) (xy 83.88225 -127.356919) (xy 83.799085 -127.37295)
			(xy 83.714774 -127.381003) (xy 83.672426 -127.381508) (xy 83.626031 -127.380916) (xy 83.533743 -127.371274)
			(xy 83.442959 -127.35208) (xy 83.354665 -127.323545) (xy 83.312 -127.305308) (xy 83.302058 -127.301502)
			(xy 83.280794 -127.301502) (xy 83.270852 -127.305308) (xy 83.228186 -127.323544) (xy 83.139895 -127.35209)
			(xy 83.049111 -127.371286) (xy 82.956822 -127.380922) (xy 82.910426 -127.381508) (xy 82.868076 -127.381021)
			(xy 82.783759 -127.372972) (xy 82.700589 -127.356945) (xy 82.61932 -127.333084) (xy 82.540686 -127.301606)
			(xy 82.465401 -127.262796) (xy 82.394146 -127.217005) (xy 82.327566 -127.164648) (xy 82.266265 -127.106199)
			(xy 82.210798 -127.042187) (xy 82.161666 -126.973193) (xy 82.119315 -126.899841) (xy 82.084129 -126.822796)
			(xy 82.056426 -126.742754) (xy 82.036457 -126.660442) (xy 82.024402 -126.576604) (xy 82.020372 -126.492)
			(xy 68.946513 -126.492) (xy 68.942482 -126.576601) (xy 68.930429 -126.660435) (xy 68.910461 -126.742744)
			(xy 68.88276 -126.822783) (xy 68.847575 -126.899826) (xy 68.805227 -126.973175) (xy 68.756099 -127.042167)
			(xy 68.700634 -127.106177) (xy 68.639337 -127.164624) (xy 68.572761 -127.216981) (xy 68.50151 -127.262771)
			(xy 68.426229 -127.301582) (xy 68.347599 -127.333061) (xy 68.266333 -127.356923) (xy 68.183167 -127.372953)
			(xy 68.098854 -127.381004) (xy 68.056506 -127.381508) (xy 68.01011 -127.380923) (xy 67.917822 -127.371279)
			(xy 67.827038 -127.352083) (xy 67.738745 -127.323546) (xy 67.69608 -127.305308) (xy 67.686138 -127.301502)
			(xy 67.664874 -127.301502) (xy 67.654932 -127.305308) (xy 67.612269 -127.323551) (xy 67.523977 -127.352095)
			(xy 67.433192 -127.371289) (xy 67.340902 -127.380923) (xy 67.294506 -127.381508) (xy 67.252157 -127.38102)
			(xy 67.167841 -127.37297) (xy 67.084673 -127.356941) (xy 67.003405 -127.333079) (xy 66.924773 -127.3016)
			(xy 66.849489 -127.262789) (xy 66.778236 -127.216998) (xy 66.711658 -127.16464) (xy 66.650358 -127.106192)
			(xy 66.594892 -127.042181) (xy 66.545762 -126.973187) (xy 66.503412 -126.899836) (xy 66.468227 -126.822791)
			(xy 66.440525 -126.742751) (xy 66.420556 -126.66044) (xy 66.408502 -126.576603) (xy 66.404472 -126.492)
			(xy 56.754513 -126.492) (xy 56.750482 -126.576601) (xy 56.738429 -126.660435) (xy 56.718461 -126.742744)
			(xy 56.69076 -126.822783) (xy 56.655575 -126.899826) (xy 56.613227 -126.973175) (xy 56.564099 -127.042167)
			(xy 56.508634 -127.106177) (xy 56.447337 -127.164624) (xy 56.380761 -127.216981) (xy 56.30951 -127.262771)
			(xy 56.234229 -127.301582) (xy 56.155599 -127.333061) (xy 56.074333 -127.356923) (xy 55.991167 -127.372953)
			(xy 55.906854 -127.381004) (xy 55.864506 -127.381508) (xy 55.81811 -127.380923) (xy 55.725822 -127.371279)
			(xy 55.635038 -127.352083) (xy 55.546745 -127.323546) (xy 55.50408 -127.305308) (xy 55.494138 -127.301502)
			(xy 55.472874 -127.301502) (xy 55.462932 -127.305308) (xy 55.420269 -127.323551) (xy 55.331977 -127.352095)
			(xy 55.241192 -127.371289) (xy 55.148902 -127.380923) (xy 55.102506 -127.381508) (xy 55.060157 -127.38102)
			(xy 54.975841 -127.37297) (xy 54.892673 -127.356941) (xy 54.811405 -127.333079) (xy 54.732773 -127.3016)
			(xy 54.657489 -127.262789) (xy 54.586236 -127.216998) (xy 54.519658 -127.16464) (xy 54.458358 -127.106192)
			(xy 54.402892 -127.042181) (xy 54.353762 -126.973187) (xy 54.311412 -126.899836) (xy 54.276227 -126.822791)
			(xy 54.248525 -126.742751) (xy 54.228556 -126.66044) (xy 54.216502 -126.576603) (xy 54.212472 -126.492)
			(xy 44.562513 -126.492) (xy 44.558482 -126.576601) (xy 44.546429 -126.660435) (xy 44.526461 -126.742744)
			(xy 44.49876 -126.822783) (xy 44.463575 -126.899826) (xy 44.421227 -126.973175) (xy 44.372099 -127.042167)
			(xy 44.316634 -127.106177) (xy 44.255337 -127.164624) (xy 44.188761 -127.216981) (xy 44.11751 -127.262771)
			(xy 44.042229 -127.301582) (xy 43.963599 -127.333061) (xy 43.882333 -127.356923) (xy 43.799167 -127.372953)
			(xy 43.714854 -127.381004) (xy 43.672506 -127.381508) (xy 43.62611 -127.380923) (xy 43.533822 -127.371279)
			(xy 43.443038 -127.352083) (xy 43.354745 -127.323546) (xy 43.31208 -127.305308) (xy 43.302138 -127.301502)
			(xy 43.280874 -127.301502) (xy 43.270932 -127.305308) (xy 43.228269 -127.323551) (xy 43.139977 -127.352095)
			(xy 43.049192 -127.371289) (xy 42.956902 -127.380923) (xy 42.910506 -127.381508) (xy 42.868157 -127.38102)
			(xy 42.783841 -127.37297) (xy 42.700673 -127.356941) (xy 42.619405 -127.333079) (xy 42.540773 -127.3016)
			(xy 42.465489 -127.262789) (xy 42.394236 -127.216998) (xy 42.327658 -127.16464) (xy 42.266358 -127.106192)
			(xy 42.210892 -127.042181) (xy 42.161762 -126.973187) (xy 42.119412 -126.899836) (xy 42.084227 -126.822791)
			(xy 42.056525 -126.742751) (xy 42.036556 -126.66044) (xy 42.024502 -126.576603) (xy 42.020472 -126.492)
			(xy 21.154006 -126.492) (xy 21.120007 -126.493527) (xy 21.02993 -126.494032) (xy 20.93918 -126.493524)
			(xy 20.757865 -126.48532) (xy 20.577106 -126.468929) (xy 20.397272 -126.444384) (xy 20.218732 -126.411736)
			(xy 20.04185 -126.371051) (xy 19.866988 -126.322413) (xy 19.694503 -126.265921) (xy 19.524747 -126.20169)
			(xy 19.358069 -126.129852) (xy 19.194807 -126.050553) (xy 19.035297 -125.963956) (xy 18.879864 -125.870238)
			(xy 18.728826 -125.76959) (xy 18.582492 -125.662218) (xy 18.44116 -125.548342) (xy 18.30512 -125.428193)
			(xy 18.17465 -125.302019) (xy 18.050016 -125.170076) (xy 17.931473 -125.032635) (xy 17.819264 -124.889976)
			(xy 17.713618 -124.742391) (xy 17.61475 -124.590181) (xy 17.522864 -124.433659) (xy 17.438146 -124.273143)
			(xy 17.399 -124.191268) (xy 17.393666 -124.179584) (xy 17.3736 -124.164598) (xy 17.264888 -124.148088)
			(xy 17.241266 -124.156216) (xy 17.232376 -124.165868) (xy 17.184455 -124.217229) (xy 17.083658 -124.315088)
			(xy 16.977503 -124.407108) (xy 16.866328 -124.492995) (xy 16.750487 -124.572477) (xy 16.630349 -124.6453)
			(xy 16.506295 -124.711232) (xy 16.37872 -124.770064) (xy 16.248031 -124.821609) (xy 16.114643 -124.865702)
			(xy 15.978981 -124.902204) (xy 15.841477 -124.930997) (xy 15.702568 -124.951991) (xy 15.562696 -124.965118)
			(xy 15.422307 -124.970337) (xy 15.281846 -124.967632) (xy 15.141762 -124.95701) (xy 15.002499 -124.938506)
			(xy 14.864501 -124.912178) (xy 14.728208 -124.87811) (xy 14.594052 -124.836411) (xy 14.462462 -124.787214)
			(xy 14.333855 -124.730674) (xy 14.208641 -124.666973) (xy 14.087218 -124.596312) (xy 13.969973 -124.518916)
			(xy 13.857279 -124.435032) (xy 13.749494 -124.344927) (xy 13.646962 -124.248887) (xy 13.550008 -124.147219)
			(xy 13.458942 -124.040245) (xy 13.374053 -123.928306) (xy 13.295611 -123.811758) (xy 13.223867 -123.690972)
			(xy 13.159047 -123.566333) (xy 13.101359 -123.438237) (xy 13.050986 -123.307092) (xy 13.008088 -123.173315)
			(xy 12.972802 -123.037332) (xy 12.94524 -122.899576) (xy 12.92549 -122.760485) (xy 12.913615 -122.620501)
			(xy 12.909653 -122.48007) (xy 10.609072 -122.48007) (xy 10.609072 -128.230122) (xy 10.608605 -128.27415)
			(xy 10.60093 -128.361872) (xy 10.585639 -128.448591) (xy 10.562848 -128.533648) (xy 10.532731 -128.616394)
			(xy 10.495516 -128.696201) (xy 10.451487 -128.77246) (xy 10.40098 -128.844592) (xy 10.344377 -128.912047)
			(xy 10.282112 -128.974313) (xy 10.214656 -129.030914) (xy 10.142523 -129.081422) (xy 10.066264 -129.12545)
			(xy 9.986457 -129.162664) (xy 9.90371 -129.192781) (xy 9.818654 -129.215571) (xy 9.731934 -129.230861)
			(xy 9.644212 -129.238536) (xy 9.600184 -129.23901) (xy 2.999994 -129.23901) (xy 2.930118 -129.2395)
			(xy 2.790585 -129.247336) (xy 2.651711 -129.262984) (xy 2.513933 -129.286393) (xy 2.377684 -129.317491)
			(xy 2.243393 -129.35618) (xy 2.111483 -129.402337) (xy 1.982368 -129.455818) (xy 1.856456 -129.516454)
			(xy 1.734141 -129.584055) (xy 1.615809 -129.658408) (xy 1.501832 -129.739279) (xy 1.392569 -129.826414)
			(xy 1.288363 -129.919537) (xy 1.189543 -130.018357) (xy 1.09642 -130.122563) (xy 1.009285 -130.231826)
			(xy 0.928414 -130.345803) (xy 0.854061 -130.464135) (xy 0.78646 -130.58645) (xy 0.725824 -130.712362)
			(xy 0.672343 -130.841477) (xy 0.626186 -130.973387) (xy 0.587497 -131.107678) (xy 0.556399 -131.243927)
			(xy 0.53299 -131.381705) (xy 0.517342 -131.520579) (xy 0.514454 -131.572) (xy 42.020472 -131.572)
			(xy 42.024502 -131.487397) (xy 42.036556 -131.40356) (xy 42.056525 -131.321249) (xy 42.084227 -131.241209)
			(xy 42.119412 -131.164164) (xy 42.161762 -131.090813) (xy 42.210892 -131.021819) (xy 42.266358 -130.957808)
			(xy 42.327658 -130.89936) (xy 42.394236 -130.847002) (xy 42.465489 -130.801211) (xy 42.540773 -130.7624)
			(xy 42.619405 -130.730921) (xy 42.700673 -130.707059) (xy 42.783841 -130.69103) (xy 42.868157 -130.68298)
			(xy 42.910506 -130.682492) (xy 42.956902 -130.683073) (xy 43.04919 -130.692718) (xy 43.139974 -130.711915)
			(xy 43.228267 -130.740454) (xy 43.270932 -130.758692) (xy 43.280874 -130.762498) (xy 43.302138 -130.762498)
			(xy 43.31208 -130.758692) (xy 43.354741 -130.740445) (xy 43.443034 -130.711902) (xy 43.533819 -130.692709)
			(xy 43.62611 -130.683077) (xy 43.672506 -130.682492) (xy 43.714854 -130.682996) (xy 43.799167 -130.691047)
			(xy 43.882333 -130.707077) (xy 43.963599 -130.730939) (xy 44.042229 -130.762418) (xy 44.11751 -130.801229)
			(xy 44.188761 -130.847019) (xy 44.255337 -130.899376) (xy 44.316634 -130.957823) (xy 44.372099 -131.021833)
			(xy 44.421227 -131.090825) (xy 44.463575 -131.164174) (xy 44.49876 -131.241217) (xy 44.526461 -131.321256)
			(xy 44.546429 -131.403565) (xy 44.558482 -131.487399) (xy 44.562513 -131.572) (xy 54.212472 -131.572)
			(xy 54.216502 -131.487397) (xy 54.228556 -131.40356) (xy 54.248525 -131.321249) (xy 54.276227 -131.241209)
			(xy 54.311412 -131.164164) (xy 54.353762 -131.090813) (xy 54.402892 -131.021819) (xy 54.458358 -130.957808)
			(xy 54.519658 -130.89936) (xy 54.586236 -130.847002) (xy 54.657489 -130.801211) (xy 54.732773 -130.7624)
			(xy 54.811405 -130.730921) (xy 54.892673 -130.707059) (xy 54.975841 -130.69103) (xy 55.060157 -130.68298)
			(xy 55.102506 -130.682492) (xy 55.148902 -130.683073) (xy 55.24119 -130.692718) (xy 55.331974 -130.711915)
			(xy 55.420267 -130.740454) (xy 55.462932 -130.758692) (xy 55.472874 -130.762498) (xy 55.494138 -130.762498)
			(xy 55.50408 -130.758692) (xy 55.546741 -130.740445) (xy 55.635034 -130.711902) (xy 55.725819 -130.692709)
			(xy 55.81811 -130.683077) (xy 55.864506 -130.682492) (xy 55.906854 -130.682996) (xy 55.991167 -130.691047)
			(xy 56.074333 -130.707077) (xy 56.155599 -130.730939) (xy 56.234229 -130.762418) (xy 56.30951 -130.801229)
			(xy 56.380761 -130.847019) (xy 56.447337 -130.899376) (xy 56.508634 -130.957823) (xy 56.564099 -131.021833)
			(xy 56.613227 -131.090825) (xy 56.655575 -131.164174) (xy 56.69076 -131.241217) (xy 56.718461 -131.321256)
			(xy 56.738429 -131.403565) (xy 56.750482 -131.487399) (xy 56.754513 -131.572) (xy 66.404472 -131.572)
			(xy 66.408502 -131.487397) (xy 66.420556 -131.40356) (xy 66.440525 -131.321249) (xy 66.468227 -131.241209)
			(xy 66.503412 -131.164164) (xy 66.545762 -131.090813) (xy 66.594892 -131.021819) (xy 66.650358 -130.957808)
			(xy 66.711658 -130.89936) (xy 66.778236 -130.847002) (xy 66.849489 -130.801211) (xy 66.924773 -130.7624)
			(xy 67.003405 -130.730921) (xy 67.084673 -130.707059) (xy 67.167841 -130.69103) (xy 67.252157 -130.68298)
			(xy 67.294506 -130.682492) (xy 67.340902 -130.683073) (xy 67.43319 -130.692718) (xy 67.523974 -130.711915)
			(xy 67.612267 -130.740454) (xy 67.654932 -130.758692) (xy 67.664874 -130.762498) (xy 67.686138 -130.762498)
			(xy 67.69608 -130.758692) (xy 67.738741 -130.740445) (xy 67.827034 -130.711902) (xy 67.917819 -130.692709)
			(xy 68.01011 -130.683077) (xy 68.056506 -130.682492) (xy 68.098854 -130.682996) (xy 68.183167 -130.691047)
			(xy 68.266333 -130.707077) (xy 68.347599 -130.730939) (xy 68.426229 -130.762418) (xy 68.50151 -130.801229)
			(xy 68.572761 -130.847019) (xy 68.639337 -130.899376) (xy 68.700634 -130.957823) (xy 68.756099 -131.021833)
			(xy 68.805227 -131.090825) (xy 68.847575 -131.164174) (xy 68.88276 -131.241217) (xy 68.910461 -131.321256)
			(xy 68.930429 -131.403565) (xy 68.942482 -131.487399) (xy 68.946513 -131.572) (xy 82.020372 -131.572)
			(xy 82.024402 -131.487396) (xy 82.036457 -131.403558) (xy 82.056426 -131.321246) (xy 82.084129 -131.241204)
			(xy 82.119315 -131.164159) (xy 82.161666 -131.090807) (xy 82.210798 -131.021813) (xy 82.266265 -130.957801)
			(xy 82.327566 -130.899352) (xy 82.394146 -130.846995) (xy 82.465401 -130.801204) (xy 82.540686 -130.762394)
			(xy 82.61932 -130.730916) (xy 82.700589 -130.707055) (xy 82.783759 -130.691028) (xy 82.868076 -130.682979)
			(xy 82.910426 -130.682492) (xy 82.956821 -130.683101) (xy 83.049109 -130.692738) (xy 83.139892 -130.711927)
			(xy 83.228187 -130.740458) (xy 83.270852 -130.758692) (xy 83.280794 -130.762498) (xy 83.302058 -130.762498)
			(xy 83.312 -130.758692) (xy 83.354659 -130.740439) (xy 83.442952 -130.711897) (xy 83.533738 -130.692706)
			(xy 83.62603 -130.683076) (xy 83.672426 -130.682492) (xy 83.714774 -130.682997) (xy 83.799085 -130.69105)
			(xy 83.88225 -130.707081) (xy 83.963514 -130.730944) (xy 84.042142 -130.762424) (xy 84.117421 -130.801235)
			(xy 84.188671 -130.847026) (xy 84.255245 -130.899383) (xy 84.316541 -130.95783) (xy 84.372004 -131.021839)
			(xy 84.421131 -131.090831) (xy 84.463478 -131.16418) (xy 84.498661 -131.241222) (xy 84.526362 -131.321259)
			(xy 84.546329 -131.403567) (xy 84.558383 -131.487401) (xy 84.562413 -131.572) (xy 94.212372 -131.572)
			(xy 94.216402 -131.487396) (xy 94.228457 -131.403558) (xy 94.248426 -131.321246) (xy 94.276129 -131.241204)
			(xy 94.311315 -131.164159) (xy 94.353666 -131.090807) (xy 94.402798 -131.021813) (xy 94.458265 -130.957801)
			(xy 94.519566 -130.899352) (xy 94.586146 -130.846995) (xy 94.657401 -130.801204) (xy 94.732686 -130.762394)
			(xy 94.81132 -130.730916) (xy 94.892589 -130.707055) (xy 94.975759 -130.691028) (xy 95.060076 -130.682979)
			(xy 95.102426 -130.682492) (xy 95.148821 -130.683101) (xy 95.241109 -130.692738) (xy 95.331892 -130.711927)
			(xy 95.420187 -130.740458) (xy 95.462852 -130.758692) (xy 95.472794 -130.762498) (xy 95.494058 -130.762498)
			(xy 95.504 -130.758692) (xy 95.546659 -130.740439) (xy 95.634952 -130.711897) (xy 95.725738 -130.692706)
			(xy 95.81803 -130.683076) (xy 95.864426 -130.682492) (xy 95.906774 -130.682997) (xy 95.991085 -130.69105)
			(xy 96.07425 -130.707081) (xy 96.155514 -130.730944) (xy 96.234142 -130.762424) (xy 96.309421 -130.801235)
			(xy 96.380671 -130.847026) (xy 96.447245 -130.899383) (xy 96.508541 -130.95783) (xy 96.564004 -131.021839)
			(xy 96.613131 -131.090831) (xy 96.655478 -131.16418) (xy 96.690661 -131.241222) (xy 96.718362 -131.321259)
			(xy 96.738329 -131.403567) (xy 96.750383 -131.487401) (xy 96.754413 -131.572) (xy 106.404372 -131.572)
			(xy 106.408402 -131.487396) (xy 106.420457 -131.403558) (xy 106.440426 -131.321246) (xy 106.468129 -131.241204)
			(xy 106.503315 -131.164159) (xy 106.545666 -131.090807) (xy 106.594798 -131.021813) (xy 106.650265 -130.957801)
			(xy 106.711566 -130.899352) (xy 106.778146 -130.846995) (xy 106.849401 -130.801204) (xy 106.924686 -130.762394)
			(xy 107.00332 -130.730916) (xy 107.084589 -130.707055) (xy 107.167759 -130.691028) (xy 107.252076 -130.682979)
			(xy 107.294426 -130.682492) (xy 107.340821 -130.683101) (xy 107.433109 -130.692738) (xy 107.523892 -130.711927)
			(xy 107.612187 -130.740458) (xy 107.654852 -130.758692) (xy 107.664794 -130.762498) (xy 107.686058 -130.762498)
			(xy 107.696 -130.758692) (xy 107.738659 -130.740439) (xy 107.826952 -130.711897) (xy 107.917738 -130.692706)
			(xy 108.01003 -130.683076) (xy 108.056426 -130.682492) (xy 108.098774 -130.682997) (xy 108.183085 -130.69105)
			(xy 108.26625 -130.707081) (xy 108.347514 -130.730944) (xy 108.426142 -130.762424) (xy 108.501421 -130.801235)
			(xy 108.572671 -130.847026) (xy 108.639245 -130.899383) (xy 108.700541 -130.95783) (xy 108.756004 -131.021839)
			(xy 108.805131 -131.090831) (xy 108.847478 -131.16418) (xy 108.882661 -131.241222) (xy 108.910362 -131.321259)
			(xy 108.930329 -131.403567) (xy 108.942383 -131.487401) (xy 108.946413 -131.572) (xy 122.020588 -131.572)
			(xy 122.024618 -131.487399) (xy 122.036671 -131.403564) (xy 122.056639 -131.321255) (xy 122.084341 -131.241216)
			(xy 122.119525 -131.164173) (xy 122.161874 -131.090823) (xy 122.211003 -131.021831) (xy 122.266468 -130.957821)
			(xy 122.327766 -130.899373) (xy 122.394342 -130.847017) (xy 122.465594 -130.801227) (xy 122.540875 -130.762416)
			(xy 122.619505 -130.730937) (xy 122.700772 -130.707076) (xy 122.783938 -130.691047) (xy 122.868252 -130.682996)
			(xy 122.9106 -130.682492) (xy 122.956996 -130.683075) (xy 123.049284 -130.69272) (xy 123.140068 -130.711916)
			(xy 123.228361 -130.740454) (xy 123.271026 -130.758692) (xy 123.280968 -130.762498) (xy 123.302232 -130.762498)
			(xy 123.312174 -130.758692) (xy 123.354836 -130.740447) (xy 123.443129 -130.711903) (xy 123.533914 -130.69271)
			(xy 123.626204 -130.683077) (xy 123.6726 -130.682492) (xy 123.714948 -130.682996) (xy 123.799262 -130.691047)
			(xy 123.882428 -130.707076) (xy 123.963695 -130.730937) (xy 124.042325 -130.762416) (xy 124.117606 -130.801227)
			(xy 124.188858 -130.847017) (xy 124.255434 -130.899373) (xy 124.316732 -130.957821) (xy 124.372197 -131.021831)
			(xy 124.421326 -131.090823) (xy 124.463675 -131.164173) (xy 124.498859 -131.241216) (xy 124.526561 -131.321255)
			(xy 124.546529 -131.403564) (xy 124.558582 -131.487399) (xy 124.562613 -131.572) (xy 134.212588 -131.572)
			(xy 134.216618 -131.487399) (xy 134.228671 -131.403564) (xy 134.248639 -131.321255) (xy 134.276341 -131.241216)
			(xy 134.311525 -131.164173) (xy 134.353874 -131.090823) (xy 134.403003 -131.021831) (xy 134.458468 -130.957821)
			(xy 134.519766 -130.899373) (xy 134.586342 -130.847017) (xy 134.657594 -130.801227) (xy 134.732875 -130.762416)
			(xy 134.811505 -130.730937) (xy 134.892772 -130.707076) (xy 134.975938 -130.691047) (xy 135.060252 -130.682996)
			(xy 135.1026 -130.682492) (xy 135.148996 -130.683075) (xy 135.241284 -130.69272) (xy 135.332068 -130.711916)
			(xy 135.420361 -130.740454) (xy 135.463026 -130.758692) (xy 135.472968 -130.762498) (xy 135.494232 -130.762498)
			(xy 135.504174 -130.758692) (xy 135.546836 -130.740447) (xy 135.635129 -130.711903) (xy 135.725914 -130.69271)
			(xy 135.818204 -130.683077) (xy 135.8646 -130.682492) (xy 135.906948 -130.682996) (xy 135.991262 -130.691047)
			(xy 136.074428 -130.707076) (xy 136.155695 -130.730937) (xy 136.234325 -130.762416) (xy 136.309606 -130.801227)
			(xy 136.380858 -130.847017) (xy 136.447434 -130.899373) (xy 136.508732 -130.957821) (xy 136.564197 -131.021831)
			(xy 136.613326 -131.090823) (xy 136.655675 -131.164173) (xy 136.690859 -131.241216) (xy 136.718561 -131.321255)
			(xy 136.738529 -131.403564) (xy 136.750582 -131.487399) (xy 136.754613 -131.572) (xy 146.404588 -131.572)
			(xy 146.408618 -131.487399) (xy 146.420671 -131.403564) (xy 146.440639 -131.321255) (xy 146.468341 -131.241216)
			(xy 146.503525 -131.164173) (xy 146.545874 -131.090823) (xy 146.595003 -131.021831) (xy 146.650468 -130.957821)
			(xy 146.711766 -130.899373) (xy 146.778342 -130.847017) (xy 146.849594 -130.801227) (xy 146.924875 -130.762416)
			(xy 147.003505 -130.730937) (xy 147.084772 -130.707076) (xy 147.167938 -130.691047) (xy 147.252252 -130.682996)
			(xy 147.2946 -130.682492) (xy 147.340996 -130.683075) (xy 147.433284 -130.69272) (xy 147.524068 -130.711916)
			(xy 147.612361 -130.740454) (xy 147.655026 -130.758692) (xy 147.664968 -130.762498) (xy 147.686232 -130.762498)
			(xy 147.696174 -130.758692) (xy 147.738836 -130.740447) (xy 147.827129 -130.711903) (xy 147.917914 -130.69271)
			(xy 148.010204 -130.683077) (xy 148.0566 -130.682492) (xy 148.098948 -130.682996) (xy 148.183262 -130.691047)
			(xy 148.266428 -130.707076) (xy 148.347695 -130.730937) (xy 148.426325 -130.762416) (xy 148.501606 -130.801227)
			(xy 148.572858 -130.847017) (xy 148.639434 -130.899373) (xy 148.700732 -130.957821) (xy 148.756197 -131.021831)
			(xy 148.805326 -131.090823) (xy 148.847675 -131.164173) (xy 148.882859 -131.241216) (xy 148.910561 -131.321255)
			(xy 148.930529 -131.403564) (xy 148.942582 -131.487399) (xy 148.946613 -131.572) (xy 162.020787 -131.572)
			(xy 162.024817 -131.487401) (xy 162.036871 -131.403567) (xy 162.056838 -131.321259) (xy 162.084539 -131.241222)
			(xy 162.119722 -131.16418) (xy 162.162069 -131.090831) (xy 162.211196 -131.021839) (xy 162.266659 -130.95783)
			(xy 162.327955 -130.899383) (xy 162.394529 -130.847026) (xy 162.465779 -130.801235) (xy 162.541058 -130.762424)
			(xy 162.619686 -130.730944) (xy 162.70095 -130.707081) (xy 162.784115 -130.69105) (xy 162.868426 -130.682997)
			(xy 162.910774 -130.682492) (xy 162.957169 -130.683084) (xy 163.049457 -130.692726) (xy 163.140241 -130.71192)
			(xy 163.228535 -130.740455) (xy 163.2712 -130.758692) (xy 163.281142 -130.762498) (xy 163.302406 -130.762498)
			(xy 163.312348 -130.758692) (xy 163.355014 -130.740456) (xy 163.443305 -130.71191) (xy 163.534089 -130.692714)
			(xy 163.626378 -130.683078) (xy 163.672774 -130.682492) (xy 163.715124 -130.682979) (xy 163.799441 -130.691028)
			(xy 163.882611 -130.707055) (xy 163.96388 -130.730916) (xy 164.042514 -130.762394) (xy 164.117799 -130.801204)
			(xy 164.189054 -130.846995) (xy 164.255634 -130.899352) (xy 164.316935 -130.957801) (xy 164.372402 -131.021813)
			(xy 164.421534 -131.090807) (xy 164.463885 -131.164159) (xy 164.499071 -131.241204) (xy 164.526774 -131.321246)
			(xy 164.546743 -131.403558) (xy 164.558798 -131.487396) (xy 164.562828 -131.572) (xy 174.212787 -131.572)
			(xy 174.216817 -131.487401) (xy 174.228871 -131.403567) (xy 174.248838 -131.321259) (xy 174.276539 -131.241222)
			(xy 174.311722 -131.16418) (xy 174.354069 -131.090831) (xy 174.403196 -131.021839) (xy 174.458659 -130.95783)
			(xy 174.519955 -130.899383) (xy 174.586529 -130.847026) (xy 174.657779 -130.801235) (xy 174.733058 -130.762424)
			(xy 174.811686 -130.730944) (xy 174.89295 -130.707081) (xy 174.976115 -130.69105) (xy 175.060426 -130.682997)
			(xy 175.102774 -130.682492) (xy 175.149169 -130.683084) (xy 175.241457 -130.692726) (xy 175.332241 -130.71192)
			(xy 175.420535 -130.740455) (xy 175.4632 -130.758692) (xy 175.473142 -130.762498) (xy 175.494406 -130.762498)
			(xy 175.504348 -130.758692) (xy 175.547014 -130.740456) (xy 175.635305 -130.71191) (xy 175.726089 -130.692714)
			(xy 175.818378 -130.683078) (xy 175.864774 -130.682492) (xy 175.907124 -130.682979) (xy 175.991441 -130.691028)
			(xy 176.074611 -130.707055) (xy 176.15588 -130.730916) (xy 176.234514 -130.762394) (xy 176.309799 -130.801204)
			(xy 176.381054 -130.846995) (xy 176.447634 -130.899352) (xy 176.508935 -130.957801) (xy 176.564402 -131.021813)
			(xy 176.613534 -131.090807) (xy 176.655885 -131.164159) (xy 176.691071 -131.241204) (xy 176.718774 -131.321246)
			(xy 176.738743 -131.403558) (xy 176.750798 -131.487396) (xy 176.754828 -131.572) (xy 186.404787 -131.572)
			(xy 186.408817 -131.487401) (xy 186.420871 -131.403567) (xy 186.440838 -131.321259) (xy 186.468539 -131.241222)
			(xy 186.503722 -131.16418) (xy 186.546069 -131.090831) (xy 186.595196 -131.021839) (xy 186.650659 -130.95783)
			(xy 186.711955 -130.899383) (xy 186.778529 -130.847026) (xy 186.849779 -130.801235) (xy 186.925058 -130.762424)
			(xy 187.003686 -130.730944) (xy 187.08495 -130.707081) (xy 187.168115 -130.69105) (xy 187.252426 -130.682997)
			(xy 187.294774 -130.682492) (xy 187.341169 -130.683084) (xy 187.433457 -130.692726) (xy 187.524241 -130.71192)
			(xy 187.612535 -130.740455) (xy 187.6552 -130.758692) (xy 187.665142 -130.762498) (xy 187.686406 -130.762498)
			(xy 187.696348 -130.758692) (xy 187.739014 -130.740456) (xy 187.827305 -130.71191) (xy 187.918089 -130.692714)
			(xy 188.010378 -130.683078) (xy 188.056774 -130.682492) (xy 188.099124 -130.682979) (xy 188.183441 -130.691028)
			(xy 188.266611 -130.707055) (xy 188.34788 -130.730916) (xy 188.426514 -130.762394) (xy 188.501799 -130.801204)
			(xy 188.573054 -130.846995) (xy 188.639634 -130.899352) (xy 188.700935 -130.957801) (xy 188.756402 -131.021813)
			(xy 188.805534 -131.090807) (xy 188.847885 -131.164159) (xy 188.883071 -131.241204) (xy 188.910774 -131.321246)
			(xy 188.930743 -131.403558) (xy 188.942798 -131.487396) (xy 188.946828 -131.572) (xy 188.942798 -131.656604)
			(xy 188.930743 -131.740442) (xy 188.910774 -131.822754) (xy 188.883071 -131.902796) (xy 188.847885 -131.979841)
			(xy 188.805534 -132.053193) (xy 188.756402 -132.122187) (xy 188.700935 -132.186199) (xy 188.639634 -132.244648)
			(xy 188.573054 -132.297005) (xy 188.501799 -132.342796) (xy 188.426514 -132.381606) (xy 188.34788 -132.413084)
			(xy 188.266611 -132.436945) (xy 188.183441 -132.452972) (xy 188.099124 -132.461021) (xy 188.056774 -132.461508)
			(xy 188.010379 -132.460899) (xy 187.918091 -132.451262) (xy 187.827308 -132.432073) (xy 187.739013 -132.403542)
			(xy 187.696348 -132.385308) (xy 187.686406 -132.381502) (xy 187.665142 -132.381502) (xy 187.6552 -132.385308)
			(xy 187.612541 -132.403561) (xy 187.524248 -132.432103) (xy 187.433462 -132.451294) (xy 187.34117 -132.460924)
			(xy 187.294774 -132.461508) (xy 187.252426 -132.461003) (xy 187.168115 -132.45295) (xy 187.08495 -132.436919)
			(xy 187.003686 -132.413056) (xy 186.925058 -132.381576) (xy 186.849779 -132.342765) (xy 186.778529 -132.296974)
			(xy 186.711955 -132.244617) (xy 186.650659 -132.18617) (xy 186.595196 -132.122161) (xy 186.546069 -132.053169)
			(xy 186.503722 -131.97982) (xy 186.468539 -131.902778) (xy 186.440838 -131.822741) (xy 186.420871 -131.740433)
			(xy 186.408817 -131.656599) (xy 186.404787 -131.572) (xy 176.754828 -131.572) (xy 176.750798 -131.656604)
			(xy 176.738743 -131.740442) (xy 176.718774 -131.822754) (xy 176.691071 -131.902796) (xy 176.655885 -131.979841)
			(xy 176.613534 -132.053193) (xy 176.564402 -132.122187) (xy 176.508935 -132.186199) (xy 176.447634 -132.244648)
			(xy 176.381054 -132.297005) (xy 176.309799 -132.342796) (xy 176.234514 -132.381606) (xy 176.15588 -132.413084)
			(xy 176.074611 -132.436945) (xy 175.991441 -132.452972) (xy 175.907124 -132.461021) (xy 175.864774 -132.461508)
			(xy 175.818379 -132.460899) (xy 175.726091 -132.451262) (xy 175.635308 -132.432073) (xy 175.547013 -132.403542)
			(xy 175.504348 -132.385308) (xy 175.494406 -132.381502) (xy 175.473142 -132.381502) (xy 175.4632 -132.385308)
			(xy 175.420541 -132.403561) (xy 175.332248 -132.432103) (xy 175.241462 -132.451294) (xy 175.14917 -132.460924)
			(xy 175.102774 -132.461508) (xy 175.060426 -132.461003) (xy 174.976115 -132.45295) (xy 174.89295 -132.436919)
			(xy 174.811686 -132.413056) (xy 174.733058 -132.381576) (xy 174.657779 -132.342765) (xy 174.586529 -132.296974)
			(xy 174.519955 -132.244617) (xy 174.458659 -132.18617) (xy 174.403196 -132.122161) (xy 174.354069 -132.053169)
			(xy 174.311722 -131.97982) (xy 174.276539 -131.902778) (xy 174.248838 -131.822741) (xy 174.228871 -131.740433)
			(xy 174.216817 -131.656599) (xy 174.212787 -131.572) (xy 164.562828 -131.572) (xy 164.558798 -131.656604)
			(xy 164.546743 -131.740442) (xy 164.526774 -131.822754) (xy 164.499071 -131.902796) (xy 164.463885 -131.979841)
			(xy 164.421534 -132.053193) (xy 164.372402 -132.122187) (xy 164.316935 -132.186199) (xy 164.255634 -132.244648)
			(xy 164.189054 -132.297005) (xy 164.117799 -132.342796) (xy 164.042514 -132.381606) (xy 163.96388 -132.413084)
			(xy 163.882611 -132.436945) (xy 163.799441 -132.452972) (xy 163.715124 -132.461021) (xy 163.672774 -132.461508)
			(xy 163.626379 -132.460899) (xy 163.534091 -132.451262) (xy 163.443308 -132.432073) (xy 163.355013 -132.403542)
			(xy 163.312348 -132.385308) (xy 163.302406 -132.381502) (xy 163.281142 -132.381502) (xy 163.2712 -132.385308)
			(xy 163.228541 -132.403561) (xy 163.140248 -132.432103) (xy 163.049462 -132.451294) (xy 162.95717 -132.460924)
			(xy 162.910774 -132.461508) (xy 162.868426 -132.461003) (xy 162.784115 -132.45295) (xy 162.70095 -132.436919)
			(xy 162.619686 -132.413056) (xy 162.541058 -132.381576) (xy 162.465779 -132.342765) (xy 162.394529 -132.296974)
			(xy 162.327955 -132.244617) (xy 162.266659 -132.18617) (xy 162.211196 -132.122161) (xy 162.162069 -132.053169)
			(xy 162.119722 -131.97982) (xy 162.084539 -131.902778) (xy 162.056838 -131.822741) (xy 162.036871 -131.740433)
			(xy 162.024817 -131.656599) (xy 162.020787 -131.572) (xy 148.946613 -131.572) (xy 148.942582 -131.656601)
			(xy 148.930529 -131.740436) (xy 148.910561 -131.822745) (xy 148.882859 -131.902784) (xy 148.847675 -131.979827)
			(xy 148.805326 -132.053177) (xy 148.756197 -132.122169) (xy 148.700732 -132.186179) (xy 148.639434 -132.244627)
			(xy 148.572858 -132.296983) (xy 148.501606 -132.342773) (xy 148.426325 -132.381584) (xy 148.347695 -132.413063)
			(xy 148.266428 -132.436924) (xy 148.183262 -132.452953) (xy 148.098948 -132.461004) (xy 148.0566 -132.461508)
			(xy 148.010204 -132.460925) (xy 147.917916 -132.45128) (xy 147.827132 -132.432084) (xy 147.738839 -132.403546)
			(xy 147.696174 -132.385308) (xy 147.686232 -132.381502) (xy 147.664968 -132.381502) (xy 147.655026 -132.385308)
			(xy 147.612364 -132.403553) (xy 147.524071 -132.432097) (xy 147.433286 -132.45129) (xy 147.340996 -132.460923)
			(xy 147.2946 -132.461508) (xy 147.252252 -132.461004) (xy 147.167938 -132.452953) (xy 147.084772 -132.436924)
			(xy 147.003505 -132.413063) (xy 146.924875 -132.381584) (xy 146.849594 -132.342773) (xy 146.778342 -132.296983)
			(xy 146.711766 -132.244627) (xy 146.650468 -132.186179) (xy 146.595003 -132.122169) (xy 146.545874 -132.053177)
			(xy 146.503525 -131.979827) (xy 146.468341 -131.902784) (xy 146.440639 -131.822745) (xy 146.420671 -131.740436)
			(xy 146.408618 -131.656601) (xy 146.404588 -131.572) (xy 136.754613 -131.572) (xy 136.750582 -131.656601)
			(xy 136.738529 -131.740436) (xy 136.718561 -131.822745) (xy 136.690859 -131.902784) (xy 136.655675 -131.979827)
			(xy 136.613326 -132.053177) (xy 136.564197 -132.122169) (xy 136.508732 -132.186179) (xy 136.447434 -132.244627)
			(xy 136.380858 -132.296983) (xy 136.309606 -132.342773) (xy 136.234325 -132.381584) (xy 136.155695 -132.413063)
			(xy 136.074428 -132.436924) (xy 135.991262 -132.452953) (xy 135.906948 -132.461004) (xy 135.8646 -132.461508)
			(xy 135.818204 -132.460925) (xy 135.725916 -132.45128) (xy 135.635132 -132.432084) (xy 135.546839 -132.403546)
			(xy 135.504174 -132.385308) (xy 135.494232 -132.381502) (xy 135.472968 -132.381502) (xy 135.463026 -132.385308)
			(xy 135.420364 -132.403553) (xy 135.332071 -132.432097) (xy 135.241286 -132.45129) (xy 135.148996 -132.460923)
			(xy 135.1026 -132.461508) (xy 135.060252 -132.461004) (xy 134.975938 -132.452953) (xy 134.892772 -132.436924)
			(xy 134.811505 -132.413063) (xy 134.732875 -132.381584) (xy 134.657594 -132.342773) (xy 134.586342 -132.296983)
			(xy 134.519766 -132.244627) (xy 134.458468 -132.186179) (xy 134.403003 -132.122169) (xy 134.353874 -132.053177)
			(xy 134.311525 -131.979827) (xy 134.276341 -131.902784) (xy 134.248639 -131.822745) (xy 134.228671 -131.740436)
			(xy 134.216618 -131.656601) (xy 134.212588 -131.572) (xy 124.562613 -131.572) (xy 124.558582 -131.656601)
			(xy 124.546529 -131.740436) (xy 124.526561 -131.822745) (xy 124.498859 -131.902784) (xy 124.463675 -131.979827)
			(xy 124.421326 -132.053177) (xy 124.372197 -132.122169) (xy 124.316732 -132.186179) (xy 124.255434 -132.244627)
			(xy 124.188858 -132.296983) (xy 124.117606 -132.342773) (xy 124.042325 -132.381584) (xy 123.963695 -132.413063)
			(xy 123.882428 -132.436924) (xy 123.799262 -132.452953) (xy 123.714948 -132.461004) (xy 123.6726 -132.461508)
			(xy 123.626204 -132.460925) (xy 123.533916 -132.45128) (xy 123.443132 -132.432084) (xy 123.354839 -132.403546)
			(xy 123.312174 -132.385308) (xy 123.302232 -132.381502) (xy 123.280968 -132.381502) (xy 123.271026 -132.385308)
			(xy 123.228364 -132.403553) (xy 123.140071 -132.432097) (xy 123.049286 -132.45129) (xy 122.956996 -132.460923)
			(xy 122.9106 -132.461508) (xy 122.868252 -132.461004) (xy 122.783938 -132.452953) (xy 122.700772 -132.436924)
			(xy 122.619505 -132.413063) (xy 122.540875 -132.381584) (xy 122.465594 -132.342773) (xy 122.394342 -132.296983)
			(xy 122.327766 -132.244627) (xy 122.266468 -132.186179) (xy 122.211003 -132.122169) (xy 122.161874 -132.053177)
			(xy 122.119525 -131.979827) (xy 122.084341 -131.902784) (xy 122.056639 -131.822745) (xy 122.036671 -131.740436)
			(xy 122.024618 -131.656601) (xy 122.020588 -131.572) (xy 108.946413 -131.572) (xy 108.942383 -131.656599)
			(xy 108.930329 -131.740433) (xy 108.910362 -131.822741) (xy 108.882661 -131.902778) (xy 108.847478 -131.97982)
			(xy 108.805131 -132.053169) (xy 108.756004 -132.122161) (xy 108.700541 -132.18617) (xy 108.639245 -132.244617)
			(xy 108.572671 -132.296974) (xy 108.501421 -132.342765) (xy 108.426142 -132.381576) (xy 108.347514 -132.413056)
			(xy 108.26625 -132.436919) (xy 108.183085 -132.45295) (xy 108.098774 -132.461003) (xy 108.056426 -132.461508)
			(xy 108.010031 -132.460916) (xy 107.917743 -132.451274) (xy 107.826959 -132.43208) (xy 107.738665 -132.403545)
			(xy 107.696 -132.385308) (xy 107.686058 -132.381502) (xy 107.664794 -132.381502) (xy 107.654852 -132.385308)
			(xy 107.612186 -132.403544) (xy 107.523895 -132.43209) (xy 107.433111 -132.451286) (xy 107.340822 -132.460922)
			(xy 107.294426 -132.461508) (xy 107.252076 -132.461021) (xy 107.167759 -132.452972) (xy 107.084589 -132.436945)
			(xy 107.00332 -132.413084) (xy 106.924686 -132.381606) (xy 106.849401 -132.342796) (xy 106.778146 -132.297005)
			(xy 106.711566 -132.244648) (xy 106.650265 -132.186199) (xy 106.594798 -132.122187) (xy 106.545666 -132.053193)
			(xy 106.503315 -131.979841) (xy 106.468129 -131.902796) (xy 106.440426 -131.822754) (xy 106.420457 -131.740442)
			(xy 106.408402 -131.656604) (xy 106.404372 -131.572) (xy 96.754413 -131.572) (xy 96.750383 -131.656599)
			(xy 96.738329 -131.740433) (xy 96.718362 -131.822741) (xy 96.690661 -131.902778) (xy 96.655478 -131.97982)
			(xy 96.613131 -132.053169) (xy 96.564004 -132.122161) (xy 96.508541 -132.18617) (xy 96.447245 -132.244617)
			(xy 96.380671 -132.296974) (xy 96.309421 -132.342765) (xy 96.234142 -132.381576) (xy 96.155514 -132.413056)
			(xy 96.07425 -132.436919) (xy 95.991085 -132.45295) (xy 95.906774 -132.461003) (xy 95.864426 -132.461508)
			(xy 95.818031 -132.460916) (xy 95.725743 -132.451274) (xy 95.634959 -132.43208) (xy 95.546665 -132.403545)
			(xy 95.504 -132.385308) (xy 95.494058 -132.381502) (xy 95.472794 -132.381502) (xy 95.462852 -132.385308)
			(xy 95.420186 -132.403544) (xy 95.331895 -132.43209) (xy 95.241111 -132.451286) (xy 95.148822 -132.460922)
			(xy 95.102426 -132.461508) (xy 95.060076 -132.461021) (xy 94.975759 -132.452972) (xy 94.892589 -132.436945)
			(xy 94.81132 -132.413084) (xy 94.732686 -132.381606) (xy 94.657401 -132.342796) (xy 94.586146 -132.297005)
			(xy 94.519566 -132.244648) (xy 94.458265 -132.186199) (xy 94.402798 -132.122187) (xy 94.353666 -132.053193)
			(xy 94.311315 -131.979841) (xy 94.276129 -131.902796) (xy 94.248426 -131.822754) (xy 94.228457 -131.740442)
			(xy 94.216402 -131.656604) (xy 94.212372 -131.572) (xy 84.562413 -131.572) (xy 84.558383 -131.656599)
			(xy 84.546329 -131.740433) (xy 84.526362 -131.822741) (xy 84.498661 -131.902778) (xy 84.463478 -131.97982)
			(xy 84.421131 -132.053169) (xy 84.372004 -132.122161) (xy 84.316541 -132.18617) (xy 84.255245 -132.244617)
			(xy 84.188671 -132.296974) (xy 84.117421 -132.342765) (xy 84.042142 -132.381576) (xy 83.963514 -132.413056)
			(xy 83.88225 -132.436919) (xy 83.799085 -132.45295) (xy 83.714774 -132.461003) (xy 83.672426 -132.461508)
			(xy 83.626031 -132.460916) (xy 83.533743 -132.451274) (xy 83.442959 -132.43208) (xy 83.354665 -132.403545)
			(xy 83.312 -132.385308) (xy 83.302058 -132.381502) (xy 83.280794 -132.381502) (xy 83.270852 -132.385308)
			(xy 83.228186 -132.403544) (xy 83.139895 -132.43209) (xy 83.049111 -132.451286) (xy 82.956822 -132.460922)
			(xy 82.910426 -132.461508) (xy 82.868076 -132.461021) (xy 82.783759 -132.452972) (xy 82.700589 -132.436945)
			(xy 82.61932 -132.413084) (xy 82.540686 -132.381606) (xy 82.465401 -132.342796) (xy 82.394146 -132.297005)
			(xy 82.327566 -132.244648) (xy 82.266265 -132.186199) (xy 82.210798 -132.122187) (xy 82.161666 -132.053193)
			(xy 82.119315 -131.979841) (xy 82.084129 -131.902796) (xy 82.056426 -131.822754) (xy 82.036457 -131.740442)
			(xy 82.024402 -131.656604) (xy 82.020372 -131.572) (xy 68.946513 -131.572) (xy 68.942482 -131.656601)
			(xy 68.930429 -131.740435) (xy 68.910461 -131.822744) (xy 68.88276 -131.902783) (xy 68.847575 -131.979826)
			(xy 68.805227 -132.053175) (xy 68.756099 -132.122167) (xy 68.700634 -132.186177) (xy 68.639337 -132.244624)
			(xy 68.572761 -132.296981) (xy 68.50151 -132.342771) (xy 68.426229 -132.381582) (xy 68.347599 -132.413061)
			(xy 68.266333 -132.436923) (xy 68.183167 -132.452953) (xy 68.098854 -132.461004) (xy 68.056506 -132.461508)
			(xy 68.01011 -132.460923) (xy 67.917822 -132.451279) (xy 67.827038 -132.432083) (xy 67.738745 -132.403546)
			(xy 67.69608 -132.385308) (xy 67.686138 -132.381502) (xy 67.664874 -132.381502) (xy 67.654932 -132.385308)
			(xy 67.612269 -132.403551) (xy 67.523977 -132.432095) (xy 67.433192 -132.451289) (xy 67.340902 -132.460923)
			(xy 67.294506 -132.461508) (xy 67.252157 -132.46102) (xy 67.167841 -132.45297) (xy 67.084673 -132.436941)
			(xy 67.003405 -132.413079) (xy 66.924773 -132.3816) (xy 66.849489 -132.342789) (xy 66.778236 -132.296998)
			(xy 66.711658 -132.24464) (xy 66.650358 -132.186192) (xy 66.594892 -132.122181) (xy 66.545762 -132.053187)
			(xy 66.503412 -131.979836) (xy 66.468227 -131.902791) (xy 66.440525 -131.822751) (xy 66.420556 -131.74044)
			(xy 66.408502 -131.656603) (xy 66.404472 -131.572) (xy 56.754513 -131.572) (xy 56.750482 -131.656601)
			(xy 56.738429 -131.740435) (xy 56.718461 -131.822744) (xy 56.69076 -131.902783) (xy 56.655575 -131.979826)
			(xy 56.613227 -132.053175) (xy 56.564099 -132.122167) (xy 56.508634 -132.186177) (xy 56.447337 -132.244624)
			(xy 56.380761 -132.296981) (xy 56.30951 -132.342771) (xy 56.234229 -132.381582) (xy 56.155599 -132.413061)
			(xy 56.074333 -132.436923) (xy 55.991167 -132.452953) (xy 55.906854 -132.461004) (xy 55.864506 -132.461508)
			(xy 55.81811 -132.460923) (xy 55.725822 -132.451279) (xy 55.635038 -132.432083) (xy 55.546745 -132.403546)
			(xy 55.50408 -132.385308) (xy 55.494138 -132.381502) (xy 55.472874 -132.381502) (xy 55.462932 -132.385308)
			(xy 55.420269 -132.403551) (xy 55.331977 -132.432095) (xy 55.241192 -132.451289) (xy 55.148902 -132.460923)
			(xy 55.102506 -132.461508) (xy 55.060157 -132.46102) (xy 54.975841 -132.45297) (xy 54.892673 -132.436941)
			(xy 54.811405 -132.413079) (xy 54.732773 -132.3816) (xy 54.657489 -132.342789) (xy 54.586236 -132.296998)
			(xy 54.519658 -132.24464) (xy 54.458358 -132.186192) (xy 54.402892 -132.122181) (xy 54.353762 -132.053187)
			(xy 54.311412 -131.979836) (xy 54.276227 -131.902791) (xy 54.248525 -131.822751) (xy 54.228556 -131.74044)
			(xy 54.216502 -131.656603) (xy 54.212472 -131.572) (xy 44.562513 -131.572) (xy 44.558482 -131.656601)
			(xy 44.546429 -131.740435) (xy 44.526461 -131.822744) (xy 44.49876 -131.902783) (xy 44.463575 -131.979826)
			(xy 44.421227 -132.053175) (xy 44.372099 -132.122167) (xy 44.316634 -132.186177) (xy 44.255337 -132.244624)
			(xy 44.188761 -132.296981) (xy 44.11751 -132.342771) (xy 44.042229 -132.381582) (xy 43.963599 -132.413061)
			(xy 43.882333 -132.436923) (xy 43.799167 -132.452953) (xy 43.714854 -132.461004) (xy 43.672506 -132.461508)
			(xy 43.62611 -132.460923) (xy 43.533822 -132.451279) (xy 43.443038 -132.432083) (xy 43.354745 -132.403546)
			(xy 43.31208 -132.385308) (xy 43.302138 -132.381502) (xy 43.280874 -132.381502) (xy 43.270932 -132.385308)
			(xy 43.228269 -132.403551) (xy 43.139977 -132.432095) (xy 43.049192 -132.451289) (xy 42.956902 -132.460923)
			(xy 42.910506 -132.461508) (xy 42.868157 -132.46102) (xy 42.783841 -132.45297) (xy 42.700673 -132.436941)
			(xy 42.619405 -132.413079) (xy 42.540773 -132.3816) (xy 42.465489 -132.342789) (xy 42.394236 -132.296998)
			(xy 42.327658 -132.24464) (xy 42.266358 -132.186192) (xy 42.210892 -132.122181) (xy 42.161762 -132.053187)
			(xy 42.119412 -131.979836) (xy 42.084227 -131.902791) (xy 42.056525 -131.822751) (xy 42.036556 -131.74044)
			(xy 42.024502 -131.656603) (xy 42.020472 -131.572) (xy 0.514454 -131.572) (xy 0.509506 -131.660112)
			(xy 0.509016 -131.729988) (xy 0.509016 -132.959856) (xy 213.088728 -132.959856) (xy 213.089328 -132.913461)
			(xy 213.098967 -132.821173) (xy 213.118158 -132.730389) (xy 213.146692 -132.642095) (xy 213.164928 -132.59943)
			(xy 213.168758 -132.589495) (xy 213.168741 -132.568225) (xy 213.164928 -132.558282) (xy 213.146671 -132.515625)
			(xy 213.11813 -132.427331) (xy 213.09894 -132.336544) (xy 213.089311 -132.244253) (xy 213.088728 -132.197856)
			(xy 213.089328 -132.151461) (xy 213.098967 -132.059173) (xy 213.118158 -131.968389) (xy 213.146692 -131.880095)
			(xy 213.164928 -131.83743) (xy 213.168758 -131.827495) (xy 213.168741 -131.806225) (xy 213.164928 -131.796282)
			(xy 213.146671 -131.753625) (xy 213.11813 -131.665331) (xy 213.09894 -131.574544) (xy 213.089311 -131.482253)
			(xy 213.088728 -131.435856) (xy 213.089328 -131.389461) (xy 213.098967 -131.297173) (xy 213.118158 -131.206389)
			(xy 213.146692 -131.118095) (xy 213.164928 -131.07543) (xy 213.168758 -131.065495) (xy 213.168741 -131.044225)
			(xy 213.164928 -131.034282) (xy 213.146671 -130.991625) (xy 213.11813 -130.903331) (xy 213.09894 -130.812544)
			(xy 213.089311 -130.720253) (xy 213.088728 -130.673856) (xy 213.089328 -130.627461) (xy 213.098967 -130.535173)
			(xy 213.118158 -130.444389) (xy 213.146692 -130.356095) (xy 213.164928 -130.31343) (xy 213.168758 -130.303495)
			(xy 213.168741 -130.282225) (xy 213.164928 -130.272282) (xy 213.146671 -130.229625) (xy 213.11813 -130.141331)
			(xy 213.09894 -130.050544) (xy 213.089311 -129.958253) (xy 213.088728 -129.911856) (xy 213.089328 -129.865461)
			(xy 213.098967 -129.773173) (xy 213.118158 -129.682389) (xy 213.146692 -129.594095) (xy 213.164928 -129.55143)
			(xy 213.168758 -129.541495) (xy 213.168741 -129.520225) (xy 213.164928 -129.510282) (xy 213.146671 -129.467625)
			(xy 213.11813 -129.379331) (xy 213.09894 -129.288544) (xy 213.089311 -129.196253) (xy 213.088728 -129.149856)
			(xy 213.089328 -129.103461) (xy 213.098967 -129.011173) (xy 213.118158 -128.920389) (xy 213.146692 -128.832095)
			(xy 213.164928 -128.78943) (xy 213.168758 -128.779495) (xy 213.168741 -128.758225) (xy 213.164928 -128.748282)
			(xy 213.146671 -128.705625) (xy 213.11813 -128.617331) (xy 213.09894 -128.526544) (xy 213.089311 -128.434253)
			(xy 213.088728 -128.387856) (xy 213.089328 -128.341461) (xy 213.098967 -128.249173) (xy 213.118158 -128.158389)
			(xy 213.146692 -128.070095) (xy 213.164928 -128.02743) (xy 213.168758 -128.017495) (xy 213.168741 -127.996225)
			(xy 213.164928 -127.986282) (xy 213.146671 -127.943625) (xy 213.11813 -127.855331) (xy 213.09894 -127.764544)
			(xy 213.089311 -127.672253) (xy 213.088728 -127.625856) (xy 213.089125 -127.584752) (xy 213.096714 -127.502894)
			(xy 213.111824 -127.422086) (xy 213.134325 -127.343017) (xy 213.164026 -127.266361) (xy 213.200673 -127.192773)
			(xy 213.243953 -127.12288) (xy 213.293498 -127.057278) (xy 213.348884 -126.996528) (xy 213.40964 -126.941147)
			(xy 213.475246 -126.891608) (xy 213.545143 -126.848334) (xy 213.618734 -126.811693) (xy 213.695393 -126.781999)
			(xy 213.774464 -126.759505) (xy 213.855273 -126.744403) (xy 213.937132 -126.736821) (xy 213.978236 -126.736348)
			(xy 214.019707 -126.736821) (xy 214.102292 -126.744496) (xy 214.183804 -126.759823) (xy 214.263536 -126.782669)
			(xy 214.30234 -126.797308) (xy 214.311828 -126.800522) (xy 214.331839 -126.800112) (xy 214.341202 -126.796546)
			(xy 214.383373 -126.778847) (xy 214.47054 -126.751148) (xy 214.560087 -126.732532) (xy 214.651071 -126.723195)
			(xy 214.696802 -126.722632) (xy 214.743198 -126.723211) (xy 214.835486 -126.732857) (xy 214.92627 -126.752054)
			(xy 215.014563 -126.780593) (xy 215.057228 -126.798832) (xy 215.06717 -126.802638) (xy 215.088434 -126.802638)
			(xy 215.098376 -126.798832) (xy 215.141039 -126.780589) (xy 215.229331 -126.752044) (xy 215.320116 -126.73285)
			(xy 215.412406 -126.723217) (xy 215.458802 -126.722632) (xy 215.502226 -126.723118) (xy 215.588665 -126.731536)
			(xy 215.673869 -126.748349) (xy 215.757026 -126.773398) (xy 215.797384 -126.789434) (xy 215.806818 -126.792777)
			(xy 215.826812 -126.792777) (xy 215.836246 -126.789434) (xy 215.87661 -126.77342) (xy 215.959771 -126.748397)
			(xy 216.044973 -126.731586) (xy 216.131406 -126.723147) (xy 216.174828 -126.722632) (xy 216.221223 -126.723237)
			(xy 216.313511 -126.732875) (xy 216.404295 -126.752064) (xy 216.492589 -126.780597) (xy 216.535254 -126.798832)
			(xy 216.545196 -126.802638) (xy 216.56646 -126.802638) (xy 216.576402 -126.798832) (xy 216.619061 -126.78058)
			(xy 216.707355 -126.752038) (xy 216.798141 -126.732846) (xy 216.890432 -126.723215) (xy 216.936828 -126.722632)
			(xy 216.977933 -126.723025) (xy 217.059791 -126.730613) (xy 217.140601 -126.745722) (xy 217.219671 -126.768223)
			(xy 217.296329 -126.797923) (xy 217.369918 -126.834569) (xy 217.439813 -126.87785) (xy 217.505416 -126.927394)
			(xy 217.566167 -126.982781) (xy 217.621549 -127.043537) (xy 217.671089 -127.109143) (xy 217.714364 -127.179041)
			(xy 217.751005 -127.252634) (xy 217.780699 -127.329293) (xy 217.803193 -127.408365) (xy 217.818296 -127.489176)
			(xy 217.825878 -127.571035) (xy 217.826336 -127.61214) (xy 217.82573 -127.658535) (xy 217.816091 -127.750823)
			(xy 217.796902 -127.841606) (xy 217.76837 -127.929901) (xy 217.750136 -127.972566) (xy 217.746305 -127.982501)
			(xy 217.746321 -128.003772) (xy 217.750136 -128.013714) (xy 217.768396 -128.05637) (xy 217.796935 -128.144665)
			(xy 217.816124 -128.235452) (xy 217.825753 -128.327743) (xy 217.826336 -128.37414) (xy 217.82573 -128.420535)
			(xy 217.816091 -128.512823) (xy 217.796902 -128.603606) (xy 217.76837 -128.691901) (xy 217.750136 -128.734566)
			(xy 217.746305 -128.744501) (xy 217.746321 -128.765772) (xy 217.750136 -128.775714) (xy 217.768396 -128.81837)
			(xy 217.796935 -128.906665) (xy 217.816124 -128.997452) (xy 217.825753 -129.089743) (xy 217.826336 -129.13614)
			(xy 217.82573 -129.182535) (xy 217.816091 -129.274823) (xy 217.796902 -129.365606) (xy 217.76837 -129.453901)
			(xy 217.750136 -129.496566) (xy 217.746305 -129.506501) (xy 217.746321 -129.527772) (xy 217.750136 -129.537714)
			(xy 217.768396 -129.58037) (xy 217.796935 -129.668665) (xy 217.816124 -129.759452) (xy 217.825753 -129.851743)
			(xy 217.826336 -129.89814) (xy 217.82573 -129.944535) (xy 217.816091 -130.036823) (xy 217.796902 -130.127606)
			(xy 217.76837 -130.215901) (xy 217.750136 -130.258566) (xy 217.746305 -130.268501) (xy 217.746321 -130.289772)
			(xy 217.750136 -130.299714) (xy 217.768396 -130.34237) (xy 217.796935 -130.430665) (xy 217.816124 -130.521452)
			(xy 217.825753 -130.613743) (xy 217.826336 -130.66014) (xy 217.82573 -130.706535) (xy 217.816091 -130.798823)
			(xy 217.796902 -130.889606) (xy 217.76837 -130.977901) (xy 217.750136 -131.020566) (xy 217.746305 -131.030501)
			(xy 217.746321 -131.051772) (xy 217.750136 -131.061714) (xy 217.768396 -131.10437) (xy 217.770454 -131.110736)
			(xy 230.701596 -131.110736) (xy 230.702191 -131.064341) (xy 230.711833 -130.972053) (xy 230.731025 -130.881269)
			(xy 230.75956 -130.792975) (xy 230.777796 -130.75031) (xy 230.78158 -130.740361) (xy 230.781594 -130.719104)
			(xy 230.777796 -130.709162) (xy 230.759563 -130.666495) (xy 230.731016 -130.578204) (xy 230.71182 -130.487421)
			(xy 230.702183 -130.395132) (xy 230.701596 -130.348736) (xy 230.702191 -130.302341) (xy 230.711833 -130.210053)
			(xy 230.731025 -130.119269) (xy 230.75956 -130.030975) (xy 230.777796 -129.98831) (xy 230.78158 -129.978361)
			(xy 230.781594 -129.957104) (xy 230.777796 -129.947162) (xy 230.759563 -129.904495) (xy 230.731016 -129.816204)
			(xy 230.71182 -129.725421) (xy 230.702183 -129.633132) (xy 230.701596 -129.586736) (xy 230.702191 -129.540341)
			(xy 230.711833 -129.448053) (xy 230.731025 -129.357269) (xy 230.75956 -129.268975) (xy 230.777796 -129.22631)
			(xy 230.78158 -129.216361) (xy 230.781594 -129.195104) (xy 230.777796 -129.185162) (xy 230.759563 -129.142495)
			(xy 230.731016 -129.054204) (xy 230.71182 -128.963421) (xy 230.702183 -128.871132) (xy 230.701596 -128.824736)
			(xy 230.702191 -128.778341) (xy 230.711833 -128.686053) (xy 230.731025 -128.595269) (xy 230.75956 -128.506975)
			(xy 230.777796 -128.46431) (xy 230.78158 -128.454361) (xy 230.781594 -128.433104) (xy 230.777796 -128.423162)
			(xy 230.759563 -128.380495) (xy 230.731016 -128.292204) (xy 230.71182 -128.201421) (xy 230.702183 -128.109132)
			(xy 230.701596 -128.062736) (xy 230.702191 -128.016341) (xy 230.711833 -127.924053) (xy 230.731025 -127.833269)
			(xy 230.75956 -127.744975) (xy 230.777796 -127.70231) (xy 230.78158 -127.692361) (xy 230.781594 -127.671104)
			(xy 230.777796 -127.661162) (xy 230.759563 -127.618495) (xy 230.731016 -127.530204) (xy 230.71182 -127.439421)
			(xy 230.702183 -127.347132) (xy 230.701596 -127.300736) (xy 230.702147 -127.256691) (xy 230.710849 -127.169033)
			(xy 230.72817 -127.082663) (xy 230.753941 -126.998427) (xy 230.77043 -126.957582) (xy 230.773801 -126.948582)
			(xy 230.774177 -126.92938) (xy 230.771192 -126.920244) (xy 230.757686 -126.882861) (xy 230.736583 -126.806223)
			(xy 230.722406 -126.728008) (xy 230.715266 -126.648839) (xy 230.714804 -126.609094) (xy 230.715307 -126.567981)
			(xy 230.722894 -126.486105) (xy 230.738004 -126.405278) (xy 230.760506 -126.326191) (xy 230.790209 -126.249516)
			(xy 230.82686 -126.17591) (xy 230.870147 -126.105999) (xy 230.919698 -126.04038) (xy 230.975093 -125.979613)
			(xy 231.035859 -125.924216) (xy 231.101476 -125.874662) (xy 231.171385 -125.831374) (xy 231.244991 -125.794721)
			(xy 231.321664 -125.765015) (xy 231.400751 -125.74251) (xy 231.481577 -125.727398) (xy 231.563453 -125.719808)
			(xy 231.604566 -125.719332) (xy 231.650969 -125.719939) (xy 231.743266 -125.729636) (xy 231.834052 -125.748895)
			(xy 231.922336 -125.777508) (xy 231.964992 -125.795786) (xy 231.974934 -125.799592) (xy 231.996198 -125.799592)
			(xy 232.00614 -125.795786) (xy 232.048804 -125.777532) (xy 232.137091 -125.748938) (xy 232.227873 -125.729678)
			(xy 232.320165 -125.719963) (xy 232.366566 -125.719332) (xy 232.409139 -125.719856) (xy 232.493893 -125.728015)
			(xy 232.577478 -125.744243) (xy 232.659128 -125.768389) (xy 232.698798 -125.783848) (xy 232.70805 -125.787101)
			(xy 232.727646 -125.787101) (xy 232.736898 -125.783848) (xy 232.776567 -125.768388) (xy 232.858222 -125.74426)
			(xy 232.941806 -125.728033) (xy 233.026558 -125.719855) (xy 233.06913 -125.719332) (xy 233.115532 -125.719952)
			(xy 233.20783 -125.729645) (xy 233.298615 -125.7489) (xy 233.3869 -125.77751) (xy 233.429556 -125.795786)
			(xy 233.439498 -125.799592) (xy 233.460762 -125.799592) (xy 233.470704 -125.795786) (xy 233.51336 -125.777511)
			(xy 233.60165 -125.748922) (xy 233.692434 -125.729668) (xy 233.784729 -125.719959) (xy 233.83113 -125.719332)
			(xy 233.877532 -125.719952) (xy 233.96983 -125.729645) (xy 234.060615 -125.7489) (xy 234.1489 -125.77751)
			(xy 234.191556 -125.795786) (xy 234.201498 -125.799592) (xy 234.222762 -125.799592) (xy 234.232704 -125.795786)
			(xy 234.27536 -125.777511) (xy 234.36365 -125.748922) (xy 234.454434 -125.729668) (xy 234.546729 -125.719959)
			(xy 234.59313 -125.719332) (xy 234.634245 -125.719784) (xy 234.716123 -125.727374) (xy 234.796951 -125.742486)
			(xy 234.876041 -125.764991) (xy 234.952716 -125.794697) (xy 235.026324 -125.831352) (xy 235.067746 -125.857)
			(xy 268.350492 -125.857) (xy 268.351075 -125.810604) (xy 268.36072 -125.718316) (xy 268.379916 -125.627532)
			(xy 268.408454 -125.539239) (xy 268.426692 -125.496574) (xy 268.430498 -125.486632) (xy 268.430498 -125.465368)
			(xy 268.426692 -125.455426) (xy 268.408447 -125.412764) (xy 268.379903 -125.324471) (xy 268.36071 -125.233686)
			(xy 268.351077 -125.141396) (xy 268.350492 -125.095) (xy 268.351075 -125.048604) (xy 268.36072 -124.956316)
			(xy 268.379916 -124.865532) (xy 268.408454 -124.777239) (xy 268.426692 -124.734574) (xy 268.430498 -124.724632)
			(xy 268.430498 -124.703368) (xy 268.426692 -124.693426) (xy 268.408447 -124.650764) (xy 268.379903 -124.562471)
			(xy 268.36071 -124.471686) (xy 268.351077 -124.379396) (xy 268.350492 -124.333) (xy 268.351075 -124.286604)
			(xy 268.36072 -124.194316) (xy 268.379916 -124.103532) (xy 268.408454 -124.015239) (xy 268.426692 -123.972574)
			(xy 268.430498 -123.962632) (xy 268.430498 -123.941368) (xy 268.426692 -123.931426) (xy 268.408447 -123.888764)
			(xy 268.379903 -123.800471) (xy 268.36071 -123.709686) (xy 268.351077 -123.617396) (xy 268.350492 -123.571)
			(xy 268.351075 -123.524604) (xy 268.36072 -123.432316) (xy 268.379916 -123.341532) (xy 268.408454 -123.253239)
			(xy 268.426692 -123.210574) (xy 268.430498 -123.200632) (xy 268.430498 -123.179368) (xy 268.426692 -123.169426)
			(xy 268.408447 -123.126764) (xy 268.379903 -123.038471) (xy 268.36071 -122.947686) (xy 268.351077 -122.855396)
			(xy 268.350492 -122.809) (xy 268.351075 -122.762604) (xy 268.36072 -122.670316) (xy 268.379916 -122.579532)
			(xy 268.408454 -122.491239) (xy 268.426692 -122.448574) (xy 268.430498 -122.438632) (xy 268.430498 -122.417368)
			(xy 268.426692 -122.407426) (xy 268.408447 -122.364764) (xy 268.379903 -122.276471) (xy 268.36071 -122.185686)
			(xy 268.351077 -122.093396) (xy 268.350492 -122.047) (xy 268.350967 -122.005898) (xy 268.358552 -121.924043)
			(xy 268.373657 -121.843238) (xy 268.396153 -121.764171) (xy 268.425849 -121.687517) (xy 268.462491 -121.61393)
			(xy 268.505766 -121.544038) (xy 268.555306 -121.478437) (xy 268.610687 -121.417687) (xy 268.671437 -121.362306)
			(xy 268.737038 -121.312766) (xy 268.80693 -121.269491) (xy 268.880517 -121.232849) (xy 268.957171 -121.203153)
			(xy 269.036238 -121.180657) (xy 269.117043 -121.165552) (xy 269.198898 -121.157967) (xy 269.24 -121.157492)
			(xy 269.286396 -121.158075) (xy 269.378684 -121.16772) (xy 269.469468 -121.186916) (xy 269.557761 -121.215454)
			(xy 269.600426 -121.233692) (xy 269.610368 -121.237498) (xy 269.631632 -121.237498) (xy 269.641574 -121.233692)
			(xy 269.684236 -121.215447) (xy 269.772529 -121.186903) (xy 269.863314 -121.16771) (xy 269.955604 -121.158077)
			(xy 270.002 -121.157492) (xy 270.048396 -121.158075) (xy 270.140684 -121.16772) (xy 270.231468 -121.186916)
			(xy 270.319761 -121.215454) (xy 270.362426 -121.233692) (xy 270.372368 -121.237498) (xy 270.393632 -121.237498)
			(xy 270.403574 -121.233692) (xy 270.446236 -121.215447) (xy 270.534529 -121.186903) (xy 270.625314 -121.16771)
			(xy 270.717604 -121.158077) (xy 270.764 -121.157492) (xy 270.810396 -121.158075) (xy 270.902684 -121.16772)
			(xy 270.993468 -121.186916) (xy 271.081761 -121.215454) (xy 271.124426 -121.233692) (xy 271.134368 -121.237498)
			(xy 271.155632 -121.237498) (xy 271.165574 -121.233692) (xy 271.208236 -121.215447) (xy 271.296529 -121.186903)
			(xy 271.387314 -121.16771) (xy 271.479604 -121.158077) (xy 271.526 -121.157492) (xy 271.572396 -121.158075)
			(xy 271.664684 -121.16772) (xy 271.755468 -121.186916) (xy 271.843761 -121.215454) (xy 271.886426 -121.233692)
			(xy 271.896368 -121.237498) (xy 271.917632 -121.237498) (xy 271.927574 -121.233692) (xy 271.970236 -121.215447)
			(xy 272.058529 -121.186903) (xy 272.149314 -121.16771) (xy 272.241604 -121.158077) (xy 272.288 -121.157492)
			(xy 272.329102 -121.157967) (xy 272.410957 -121.165552) (xy 272.491762 -121.180657) (xy 272.570829 -121.203153)
			(xy 272.647483 -121.232849) (xy 272.72107 -121.269491) (xy 272.790962 -121.312766) (xy 272.856563 -121.362306)
			(xy 272.917313 -121.417687) (xy 272.972694 -121.478437) (xy 273.022234 -121.544038) (xy 273.065509 -121.61393)
			(xy 273.102151 -121.687517) (xy 273.131847 -121.764171) (xy 273.154343 -121.843238) (xy 273.169448 -121.924043)
			(xy 273.177033 -122.005898) (xy 273.177508 -122.047) (xy 273.176925 -122.093396) (xy 273.16728 -122.185684)
			(xy 273.148084 -122.276468) (xy 273.119546 -122.364761) (xy 273.101308 -122.407426) (xy 273.097502 -122.417368)
			(xy 273.097502 -122.438632) (xy 273.101308 -122.448574) (xy 273.119553 -122.491236) (xy 273.148097 -122.579529)
			(xy 273.16729 -122.670314) (xy 273.176923 -122.762604) (xy 273.177508 -122.809) (xy 273.177033 -122.850102)
			(xy 273.169448 -122.931957) (xy 273.154343 -123.012762) (xy 273.131847 -123.091829) (xy 273.102151 -123.168483)
			(xy 273.065509 -123.24207) (xy 273.022234 -123.311962) (xy 272.972694 -123.377563) (xy 272.917313 -123.438313)
			(xy 272.856563 -123.493694) (xy 272.790962 -123.543234) (xy 272.72107 -123.586509) (xy 272.647483 -123.623151)
			(xy 272.570829 -123.652847) (xy 272.491762 -123.675343) (xy 272.410957 -123.690448) (xy 272.329102 -123.698033)
			(xy 272.288 -123.698508) (xy 272.241604 -123.697925) (xy 272.149316 -123.68828) (xy 272.058532 -123.669084)
			(xy 271.970239 -123.640546) (xy 271.927574 -123.622308) (xy 271.917632 -123.618502) (xy 271.896368 -123.618502)
			(xy 271.886426 -123.622308) (xy 271.853507 -123.636537) (xy 271.785822 -123.660257) (xy 271.716442 -123.678437)
			(xy 271.681194 -123.685046) (xy 271.67107 -123.687344) (xy 271.653749 -123.698749) (xy 271.642344 -123.71607)
			(xy 271.640046 -123.726194) (xy 271.633416 -123.761437) (xy 271.61522 -123.83081) (xy 271.591513 -123.898498)
			(xy 271.577308 -123.931426) (xy 271.573502 -123.941368) (xy 271.573502 -123.962632) (xy 271.577308 -123.972574)
			(xy 271.591537 -124.005493) (xy 271.615257 -124.073178) (xy 271.633437 -124.142558) (xy 271.640046 -124.177806)
			(xy 271.642344 -124.18793) (xy 271.653749 -124.205251) (xy 271.67107 -124.216656) (xy 271.681194 -124.218954)
			(xy 271.716437 -124.225584) (xy 271.78581 -124.24378) (xy 271.853498 -124.267487) (xy 271.886426 -124.281692)
			(xy 271.896368 -124.285498) (xy 271.917632 -124.285498) (xy 271.927574 -124.281692) (xy 271.970236 -124.263447)
			(xy 272.058529 -124.234903) (xy 272.149314 -124.21571) (xy 272.241604 -124.206077) (xy 272.288 -124.205492)
			(xy 272.329102 -124.205967) (xy 272.410957 -124.213552) (xy 272.491762 -124.228657) (xy 272.570829 -124.251153)
			(xy 272.647483 -124.280849) (xy 272.72107 -124.317491) (xy 272.790962 -124.360766) (xy 272.856563 -124.410306)
			(xy 272.917313 -124.465687) (xy 272.972694 -124.526437) (xy 273.022234 -124.592038) (xy 273.065509 -124.66193)
			(xy 273.102151 -124.735517) (xy 273.131847 -124.812171) (xy 273.154343 -124.891238) (xy 273.169448 -124.972043)
			(xy 273.177033 -125.053898) (xy 273.177508 -125.095) (xy 273.176925 -125.141396) (xy 273.16728 -125.233684)
			(xy 273.148084 -125.324468) (xy 273.119546 -125.412761) (xy 273.101308 -125.455426) (xy 273.097502 -125.465368)
			(xy 273.097502 -125.486632) (xy 273.101308 -125.496574) (xy 273.119553 -125.539236) (xy 273.148097 -125.627529)
			(xy 273.16729 -125.718314) (xy 273.176923 -125.810604) (xy 273.177508 -125.857) (xy 273.177033 -125.898102)
			(xy 273.169448 -125.979957) (xy 273.154343 -126.060762) (xy 273.131847 -126.139829) (xy 273.102151 -126.216483)
			(xy 273.065509 -126.29007) (xy 273.022234 -126.359962) (xy 272.972694 -126.425563) (xy 272.917313 -126.486313)
			(xy 272.856563 -126.541694) (xy 272.790962 -126.591234) (xy 272.72107 -126.634509) (xy 272.647483 -126.671151)
			(xy 272.570829 -126.700847) (xy 272.491762 -126.723343) (xy 272.410957 -126.738448) (xy 272.329102 -126.746033)
			(xy 272.288 -126.746508) (xy 272.241604 -126.745925) (xy 272.149316 -126.73628) (xy 272.058532 -126.717084)
			(xy 271.970239 -126.688546) (xy 271.927574 -126.670308) (xy 271.917632 -126.666502) (xy 271.896368 -126.666502)
			(xy 271.886426 -126.670308) (xy 271.843764 -126.688553) (xy 271.755471 -126.717097) (xy 271.664686 -126.73629)
			(xy 271.572396 -126.745923) (xy 271.526 -126.746508) (xy 271.479604 -126.745925) (xy 271.387316 -126.73628)
			(xy 271.296532 -126.717084) (xy 271.208239 -126.688546) (xy 271.165574 -126.670308) (xy 271.155632 -126.666502)
			(xy 271.134368 -126.666502) (xy 271.124426 -126.670308) (xy 271.081764 -126.688553) (xy 270.993471 -126.717097)
			(xy 270.902686 -126.73629) (xy 270.810396 -126.745923) (xy 270.764 -126.746508) (xy 270.717604 -126.745925)
			(xy 270.625316 -126.73628) (xy 270.534532 -126.717084) (xy 270.446239 -126.688546) (xy 270.403574 -126.670308)
			(xy 270.393632 -126.666502) (xy 270.372368 -126.666502) (xy 270.362426 -126.670308) (xy 270.319764 -126.688553)
			(xy 270.231471 -126.717097) (xy 270.140686 -126.73629) (xy 270.048396 -126.745923) (xy 270.002 -126.746508)
			(xy 269.955604 -126.745925) (xy 269.863316 -126.73628) (xy 269.772532 -126.717084) (xy 269.684239 -126.688546)
			(xy 269.641574 -126.670308) (xy 269.631632 -126.666502) (xy 269.610368 -126.666502) (xy 269.600426 -126.670308)
			(xy 269.557764 -126.688553) (xy 269.469471 -126.717097) (xy 269.378686 -126.73629) (xy 269.286396 -126.745923)
			(xy 269.24 -126.746508) (xy 269.198898 -126.746033) (xy 269.117043 -126.738448) (xy 269.036238 -126.723343)
			(xy 268.957171 -126.700847) (xy 268.880517 -126.671151) (xy 268.80693 -126.634509) (xy 268.737038 -126.591234)
			(xy 268.671437 -126.541694) (xy 268.610687 -126.486313) (xy 268.555306 -126.425563) (xy 268.505766 -126.359962)
			(xy 268.462491 -126.29007) (xy 268.425849 -126.216483) (xy 268.396153 -126.139829) (xy 268.373657 -126.060762)
			(xy 268.358552 -125.979957) (xy 268.350967 -125.898102) (xy 268.350492 -125.857) (xy 235.067746 -125.857)
			(xy 235.096236 -125.874641) (xy 235.161855 -125.924196) (xy 235.222622 -125.979595) (xy 235.278019 -126.040363)
			(xy 235.327572 -126.105984) (xy 235.37086 -126.175897) (xy 235.407512 -126.249506) (xy 235.437217 -126.326182)
			(xy 235.45972 -126.405272) (xy 235.474829 -126.486101) (xy 235.482417 -126.567979) (xy 235.482892 -126.609094)
			(xy 235.482318 -126.653145) (xy 235.473542 -126.740808) (xy 235.456153 -126.827177) (xy 235.430321 -126.911407)
			(xy 235.413804 -126.952248) (xy 235.410474 -126.961259) (xy 235.410073 -126.98045) (xy 235.413042 -126.989586)
			(xy 235.426531 -127.026969) (xy 235.447571 -127.103614) (xy 235.461682 -127.181831) (xy 235.46875 -127.260996)
			(xy 235.469176 -127.300736) (xy 235.468573 -127.347131) (xy 235.458934 -127.439419) (xy 235.439744 -127.530203)
			(xy 235.411211 -127.618497) (xy 235.392976 -127.661162) (xy 235.389151 -127.671098) (xy 235.389165 -127.692367)
			(xy 235.392976 -127.70231) (xy 235.411231 -127.744968) (xy 235.439773 -127.833262) (xy 235.458963 -127.924048)
			(xy 235.468593 -128.01634) (xy 235.469176 -128.062736) (xy 235.468573 -128.109131) (xy 235.458934 -128.201419)
			(xy 235.439744 -128.292203) (xy 235.411211 -128.380497) (xy 235.392976 -128.423162) (xy 235.389151 -128.433098)
			(xy 235.389165 -128.454367) (xy 235.392976 -128.46431) (xy 235.411231 -128.506968) (xy 235.439773 -128.595262)
			(xy 235.458963 -128.686048) (xy 235.468593 -128.77834) (xy 235.469176 -128.824736) (xy 235.468573 -128.871131)
			(xy 235.458934 -128.963419) (xy 235.455402 -128.980127) (xy 270.348706 -128.980127) (xy 270.348706 -128.895405)
			(xy 270.356759 -128.811068) (xy 270.372793 -128.727878) (xy 270.396661 -128.646588) (xy 270.428149 -128.567936)
			(xy 270.466971 -128.492633) (xy 270.512774 -128.421361) (xy 270.565145 -128.354765) (xy 270.62361 -128.29345)
			(xy 270.687638 -128.237969) (xy 270.75665 -128.188826) (xy 270.83002 -128.146466) (xy 270.907085 -128.111271)
			(xy 270.987147 -128.083562) (xy 271.06948 -128.063588) (xy 271.153339 -128.051531) (xy 271.237964 -128.0475)
			(xy 271.322589 -128.051531) (xy 271.406448 -128.063588) (xy 271.488781 -128.083562) (xy 271.568843 -128.111271)
			(xy 271.645908 -128.146466) (xy 271.719278 -128.188826) (xy 271.78829 -128.237969) (xy 271.852318 -128.29345)
			(xy 271.910783 -128.354765) (xy 271.963154 -128.421361) (xy 272.008957 -128.492633) (xy 272.047779 -128.567936)
			(xy 272.079267 -128.646588) (xy 272.103135 -128.727878) (xy 272.119169 -128.811068) (xy 272.127222 -128.895405)
			(xy 272.127726 -128.937766) (xy 272.127222 -128.980127) (xy 272.119169 -129.064464) (xy 272.103135 -129.147654)
			(xy 272.079267 -129.228944) (xy 272.047779 -129.307596) (xy 272.008957 -129.382899) (xy 271.963154 -129.454171)
			(xy 271.910783 -129.520767) (xy 271.852318 -129.582082) (xy 271.78829 -129.637563) (xy 271.719278 -129.686706)
			(xy 271.645908 -129.729066) (xy 271.568843 -129.764261) (xy 271.488781 -129.79197) (xy 271.406448 -129.811944)
			(xy 271.322589 -129.824001) (xy 271.237964 -129.828033) (xy 271.153339 -129.824001) (xy 271.06948 -129.811944)
			(xy 270.987147 -129.79197) (xy 270.907085 -129.764261) (xy 270.83002 -129.729066) (xy 270.75665 -129.686706)
			(xy 270.687638 -129.637563) (xy 270.62361 -129.582082) (xy 270.565145 -129.520767) (xy 270.512774 -129.454171)
			(xy 270.466971 -129.382899) (xy 270.428149 -129.307596) (xy 270.396661 -129.228944) (xy 270.372793 -129.147654)
			(xy 270.356759 -129.064464) (xy 270.348706 -128.980127) (xy 235.455402 -128.980127) (xy 235.439744 -129.054203)
			(xy 235.411211 -129.142497) (xy 235.392976 -129.185162) (xy 235.389151 -129.195098) (xy 235.389165 -129.216367)
			(xy 235.392976 -129.22631) (xy 235.411231 -129.268968) (xy 235.439773 -129.357262) (xy 235.458963 -129.448048)
			(xy 235.468593 -129.54034) (xy 235.469176 -129.586736) (xy 235.468573 -129.633131) (xy 235.458934 -129.725419)
			(xy 235.439744 -129.816203) (xy 235.411211 -129.904497) (xy 235.392976 -129.947162) (xy 235.389151 -129.957098)
			(xy 235.389165 -129.978367) (xy 235.392976 -129.98831) (xy 235.411231 -130.030968) (xy 235.439773 -130.119262)
			(xy 235.458963 -130.210048) (xy 235.468593 -130.30234) (xy 235.469176 -130.348736) (xy 235.468573 -130.395131)
			(xy 235.458934 -130.487419) (xy 235.449335 -130.532829) (xy 268.757142 -130.532829) (xy 268.757142 -130.448107)
			(xy 268.765195 -130.36377) (xy 268.781229 -130.28058) (xy 268.805097 -130.19929) (xy 268.836585 -130.120638)
			(xy 268.875407 -130.045335) (xy 268.92121 -129.974063) (xy 268.973581 -129.907467) (xy 269.032046 -129.846152)
			(xy 269.096074 -129.790671) (xy 269.165086 -129.741528) (xy 269.238456 -129.699168) (xy 269.315521 -129.663973)
			(xy 269.395583 -129.636264) (xy 269.477916 -129.61629) (xy 269.561775 -129.604233) (xy 269.6464 -129.600202)
			(xy 269.731025 -129.604233) (xy 269.814884 -129.61629) (xy 269.897217 -129.636264) (xy 269.977279 -129.663973)
			(xy 270.054344 -129.699168) (xy 270.127714 -129.741528) (xy 270.196726 -129.790671) (xy 270.260754 -129.846152)
			(xy 270.319219 -129.907467) (xy 270.37159 -129.974063) (xy 270.417393 -130.045335) (xy 270.456215 -130.120638)
			(xy 270.487703 -130.19929) (xy 270.511571 -130.28058) (xy 270.527605 -130.36377) (xy 270.535658 -130.448107)
			(xy 270.536162 -130.490468) (xy 270.535658 -130.532829) (xy 270.527605 -130.617166) (xy 270.511571 -130.700356)
			(xy 270.487703 -130.781646) (xy 270.456215 -130.860298) (xy 270.417393 -130.935601) (xy 270.37159 -131.006873)
			(xy 270.319219 -131.073469) (xy 270.260754 -131.134784) (xy 270.196726 -131.190265) (xy 270.127714 -131.239408)
			(xy 270.054344 -131.281768) (xy 269.977279 -131.316963) (xy 269.897217 -131.344672) (xy 269.814884 -131.364646)
			(xy 269.731025 -131.376703) (xy 269.6464 -131.380735) (xy 269.561775 -131.376703) (xy 269.477916 -131.364646)
			(xy 269.395583 -131.344672) (xy 269.315521 -131.316963) (xy 269.238456 -131.281768) (xy 269.165086 -131.239408)
			(xy 269.096074 -131.190265) (xy 269.032046 -131.134784) (xy 268.973581 -131.073469) (xy 268.92121 -131.006873)
			(xy 268.875407 -130.935601) (xy 268.836585 -130.860298) (xy 268.805097 -130.781646) (xy 268.781229 -130.700356)
			(xy 268.765195 -130.617166) (xy 268.757142 -130.532829) (xy 235.449335 -130.532829) (xy 235.439744 -130.578203)
			(xy 235.411211 -130.666497) (xy 235.392976 -130.709162) (xy 235.389151 -130.719098) (xy 235.389165 -130.740367)
			(xy 235.392976 -130.75031) (xy 235.411231 -130.792968) (xy 235.439773 -130.881262) (xy 235.458963 -130.972048)
			(xy 235.468593 -131.06434) (xy 235.469176 -131.110736) (xy 235.4687 -131.152245) (xy 235.460981 -131.234903)
			(xy 235.445588 -131.316482) (xy 235.422653 -131.396269) (xy 235.407962 -131.435094) (xy 235.404787 -131.444591)
			(xy 235.405179 -131.464591) (xy 235.408724 -131.473956) (xy 235.42646 -131.51612) (xy 235.451388 -131.594352)
			(xy 277.69185 -131.594352) (xy 277.69185 -61.165994) (xy 277.692371 -61.132734) (xy 277.701058 -61.066783)
			(xy 277.718283 -61.002531) (xy 277.743751 -60.941079) (xy 277.777025 -60.883479) (xy 277.817536 -60.830717)
			(xy 277.840694 -60.806838) (xy 279.28951 -59.358022) (xy 279.313407 -59.334883) (xy 279.366164 -59.294369)
			(xy 279.423761 -59.261092) (xy 279.48521 -59.235621) (xy 279.549458 -59.218392) (xy 279.615407 -59.209702)
			(xy 279.648666 -59.209178) (xy 298.525184 -59.209178) (xy 298.558444 -59.209705) (xy 298.624395 -59.21839)
			(xy 298.688647 -59.235613) (xy 298.750099 -59.261079) (xy 298.807699 -59.294353) (xy 298.860461 -59.334864)
			(xy 298.88434 -59.358022) (xy 300.12259 -60.596272) (xy 300.145761 -60.620139) (xy 300.186271 -60.672903)
			(xy 300.219544 -60.730506) (xy 300.245009 -60.791961) (xy 300.262231 -60.856215) (xy 300.270914 -60.922167)
			(xy 300.271434 -60.955428) (xy 300.271434 -72.65289) (xy 300.271856 -72.66296) (xy 300.279578 -72.681558)
			(xy 300.28642 -72.688958) (xy 300.477428 -72.879966) (xy 310.009801 -72.879966) (xy 310.013811 -72.774063)
			(xy 310.025819 -72.668767) (xy 310.045756 -72.564681) (xy 310.073508 -72.462401) (xy 310.108916 -72.362512)
			(xy 310.151777 -72.265588) (xy 310.201845 -72.172182) (xy 310.258835 -72.082831) (xy 310.322418 -71.998045)
			(xy 310.392232 -71.918311) (xy 310.467876 -71.844086) (xy 310.548916 -71.775793) (xy 310.63489 -71.713826)
			(xy 310.725304 -71.658538) (xy 310.81964 -71.610246) (xy 310.917359 -71.569227) (xy 311.017899 -71.535716)
			(xy 311.120687 -71.509904) (xy 311.225131 -71.49194) (xy 311.330636 -71.481927) (xy 311.436595 -71.479921)
			(xy 311.542403 -71.485935) (xy 311.647453 -71.499934) (xy 311.751143 -71.521837) (xy 311.85288 -71.55152)
			(xy 311.952081 -71.588811) (xy 312.048177 -71.633499) (xy 312.140618 -71.685326) (xy 312.228875 -71.743996)
			(xy 312.312442 -71.809173) (xy 312.390841 -71.880483) (xy 312.463622 -71.957517) (xy 312.530368 -72.039836)
			(xy 312.590698 -72.126967) (xy 312.644265 -72.218411) (xy 312.690763 -72.313644) (xy 312.729925 -72.412121)
			(xy 312.761528 -72.513278) (xy 312.785389 -72.616536) (xy 312.801374 -72.721302) (xy 312.809389 -72.826977)
			(xy 312.80989 -72.879966) (xy 312.809389 -72.932955) (xy 312.801374 -73.03863) (xy 312.785389 -73.143396)
			(xy 312.761528 -73.246654) (xy 312.729925 -73.347811) (xy 312.690763 -73.446288) (xy 312.644265 -73.541521)
			(xy 312.590698 -73.632965) (xy 312.530368 -73.720096) (xy 312.463622 -73.802415) (xy 312.390841 -73.879449)
			(xy 312.312442 -73.950759) (xy 312.228875 -74.015936) (xy 312.140618 -74.074606) (xy 312.048177 -74.126433)
			(xy 311.952081 -74.171121) (xy 311.85288 -74.208412) (xy 311.751143 -74.238095) (xy 311.647453 -74.259998)
			(xy 311.542403 -74.273997) (xy 311.436595 -74.280011) (xy 311.330636 -74.278005) (xy 311.225131 -74.267992)
			(xy 311.120687 -74.250028) (xy 311.017899 -74.224216) (xy 310.917359 -74.190705) (xy 310.81964 -74.149686)
			(xy 310.725304 -74.101394) (xy 310.63489 -74.046106) (xy 310.548916 -73.984139) (xy 310.467876 -73.915846)
			(xy 310.392232 -73.841621) (xy 310.322418 -73.761887) (xy 310.258835 -73.677101) (xy 310.201845 -73.58775)
			(xy 310.151777 -73.494344) (xy 310.108916 -73.39742) (xy 310.073508 -73.297531) (xy 310.045756 -73.195251)
			(xy 310.025819 -73.091165) (xy 310.013811 -72.985869) (xy 310.009801 -72.879966) (xy 300.477428 -72.879966)
			(xy 300.613826 -73.016364) (xy 300.621227 -73.023203) (xy 300.639825 -73.030924) (xy 300.649894 -73.03135)
			(xy 306.38115 -73.03135) (xy 306.414411 -73.031843) (xy 306.480363 -73.040536) (xy 306.544615 -73.057766)
			(xy 306.606067 -73.083239) (xy 306.663667 -73.116518) (xy 306.716428 -73.157033) (xy 306.740306 -73.180194)
			(xy 308.856126 -75.296014) (xy 308.863521 -75.30286) (xy 308.882124 -75.310576) (xy 308.892194 -75.311)
			(xy 319.8876 -75.311) (xy 319.920859 -75.311539) (xy 319.986809 -75.320225) (xy 320.05106 -75.337447)
			(xy 320.112511 -75.362911) (xy 320.170112 -75.396182) (xy 320.222876 -75.436688) (xy 320.246756 -75.459844)
			(xy 321.288156 -76.501244) (xy 321.311308 -76.525129) (xy 321.351821 -76.577889) (xy 321.385097 -76.635488)
			(xy 321.410566 -76.696939) (xy 321.427791 -76.76119) (xy 321.436479 -76.82714) (xy 321.437 -76.8604)
			(xy 321.437 -120.904) (xy 321.436461 -120.937259) (xy 321.427775 -121.003209) (xy 321.410553 -121.06746)
			(xy 321.385089 -121.128911) (xy 321.351818 -121.186512) (xy 321.311312 -121.239276) (xy 321.288156 -121.263156)
			(xy 319.992756 -122.558556) (xy 319.968871 -122.581708) (xy 319.916111 -122.622221) (xy 319.858512 -122.655497)
			(xy 319.797061 -122.680966) (xy 319.73281 -122.698191) (xy 319.66686 -122.706879) (xy 319.6336 -122.7074)
			(xy 304.015394 -122.7074) (xy 304.005321 -122.707796) (xy 303.986722 -122.715534) (xy 303.979326 -122.722386)
			(xy 300.28642 -126.415292) (xy 300.279594 -126.422703) (xy 300.271865 -126.441294) (xy 300.271434 -126.45136)
			(xy 300.271434 -131.730496) (xy 300.270911 -131.763756) (xy 300.262225 -131.829707) (xy 300.245001 -131.893959)
			(xy 300.219534 -131.955411) (xy 300.18626 -132.013011) (xy 300.145749 -132.065773) (xy 300.12259 -132.089652)
			(xy 298.892722 -133.31952) (xy 298.868863 -133.3427) (xy 298.816096 -133.383208) (xy 298.758492 -133.416478)
			(xy 298.697036 -133.441942) (xy 298.632781 -133.459163) (xy 298.566827 -133.467845) (xy 298.533566 -133.468364)
			(xy 279.565862 -133.468364) (xy 279.532601 -133.46786) (xy 279.46665 -133.459168) (xy 279.402398 -133.44194)
			(xy 279.340946 -133.416469) (xy 279.283346 -133.383193) (xy 279.230585 -133.342679) (xy 279.206706 -133.31952)
			(xy 277.840694 -131.953508) (xy 277.81751 -131.929653) (xy 277.777002 -131.876886) (xy 277.743731 -131.81928)
			(xy 277.718269 -131.757823) (xy 277.701049 -131.693568) (xy 277.692368 -131.627614) (xy 277.69185 -131.594352)
			(xy 235.451388 -131.594352) (xy 235.454232 -131.603278) (xy 235.472912 -131.692826) (xy 235.482304 -131.783818)
			(xy 235.482892 -131.829556) (xy 235.482406 -131.870659) (xy 235.474825 -131.952514) (xy 235.459723 -132.033321)
			(xy 235.437229 -132.11239) (xy 235.407535 -132.189045) (xy 235.370895 -132.262634) (xy 235.327621 -132.332528)
			(xy 235.278083 -132.39813) (xy 235.222702 -132.458882) (xy 235.161952 -132.514265) (xy 235.096351 -132.563805)
			(xy 235.026458 -132.607082) (xy 234.952871 -132.643724) (xy 234.876216 -132.67342) (xy 234.797148 -132.695916)
			(xy 234.716342 -132.711021) (xy 234.634487 -132.718605) (xy 234.593384 -132.719064) (xy 234.546988 -132.718491)
			(xy 234.454699 -132.708843) (xy 234.363916 -132.689645) (xy 234.275622 -132.661103) (xy 234.232958 -132.642864)
			(xy 234.223016 -132.639058) (xy 234.201752 -132.639058) (xy 234.19181 -132.642864) (xy 234.149149 -132.661111)
			(xy 234.060856 -132.689655) (xy 233.970071 -132.708848) (xy 233.87778 -132.71848) (xy 233.831384 -132.719064)
			(xy 233.784988 -132.718491) (xy 233.692699 -132.708843) (xy 233.601916 -132.689645) (xy 233.513622 -132.661103)
			(xy 233.470958 -132.642864) (xy 233.461016 -132.639058) (xy 233.439752 -132.639058) (xy 233.42981 -132.642864)
			(xy 233.387149 -132.661111) (xy 233.298856 -132.689655) (xy 233.208071 -132.708848) (xy 233.11578 -132.71848)
			(xy 233.069384 -132.719064) (xy 233.026817 -132.718594) (xy 232.942069 -132.710485) (xy 232.858485 -132.694314)
			(xy 232.776829 -132.670229) (xy 232.737152 -132.654802) (xy 232.7279 -132.651549) (xy 232.708304 -132.651549)
			(xy 232.699052 -132.654802) (xy 232.65938 -132.670239) (xy 232.57772 -132.694311) (xy 232.494134 -132.710474)
			(xy 232.409387 -132.718579) (xy 232.36682 -132.719064) (xy 232.320424 -132.718478) (xy 232.228136 -132.708834)
			(xy 232.137352 -132.689639) (xy 232.049059 -132.661102) (xy 232.006394 -132.642864) (xy 231.996452 -132.639058)
			(xy 231.975188 -132.639058) (xy 231.965246 -132.642864) (xy 231.92258 -132.661099) (xy 231.834289 -132.689647)
			(xy 231.743505 -132.708842) (xy 231.651216 -132.718478) (xy 231.60482 -132.719064) (xy 231.563716 -132.718629)
			(xy 231.481858 -132.711045) (xy 231.401049 -132.69594) (xy 231.321979 -132.673444) (xy 231.245322 -132.643747)
			(xy 231.171732 -132.607104) (xy 231.101838 -132.563827) (xy 231.036234 -132.514285) (xy 230.975482 -132.458901)
			(xy 230.9201 -132.398147) (xy 230.87056 -132.332543) (xy 230.827284 -132.262647) (xy 230.790643 -132.189056)
			(xy 230.760949 -132.112398) (xy 230.738454 -132.033327) (xy 230.723352 -131.952518) (xy 230.71577 -131.87066)
			(xy 230.715312 -131.829556) (xy 230.715787 -131.788047) (xy 230.723505 -131.705388) (xy 230.7389 -131.62381)
			(xy 230.761835 -131.544023) (xy 230.776526 -131.505198) (xy 230.779706 -131.495702) (xy 230.779312 -131.475701)
			(xy 230.775764 -131.466336) (xy 230.758025 -131.424174) (xy 230.730254 -131.337015) (xy 230.711574 -131.247467)
			(xy 230.702183 -131.156474) (xy 230.701596 -131.110736) (xy 217.770454 -131.110736) (xy 217.796935 -131.192665)
			(xy 217.816124 -131.283452) (xy 217.825753 -131.375743) (xy 217.826336 -131.42214) (xy 217.82573 -131.468535)
			(xy 217.816091 -131.560823) (xy 217.796902 -131.651606) (xy 217.76837 -131.739901) (xy 217.750136 -131.782566)
			(xy 217.746305 -131.792501) (xy 217.746321 -131.813772) (xy 217.750136 -131.823714) (xy 217.768396 -131.86637)
			(xy 217.796935 -131.954665) (xy 217.816124 -132.045452) (xy 217.825753 -132.137743) (xy 217.826336 -132.18414)
			(xy 217.82573 -132.230535) (xy 217.816091 -132.322823) (xy 217.796902 -132.413606) (xy 217.76837 -132.501901)
			(xy 217.750136 -132.544566) (xy 217.746305 -132.554501) (xy 217.746321 -132.575772) (xy 217.750136 -132.585714)
			(xy 217.768396 -132.62837) (xy 217.796935 -132.716665) (xy 217.816124 -132.807452) (xy 217.825753 -132.899743)
			(xy 217.826336 -132.94614) (xy 217.825872 -132.987242) (xy 217.818283 -133.069096) (xy 217.803175 -133.1499)
			(xy 217.780677 -133.228966) (xy 217.750979 -133.305619) (xy 217.714335 -133.379205) (xy 217.671059 -133.449096)
			(xy 217.621519 -133.514696) (xy 217.566137 -133.575446) (xy 217.505387 -133.630826) (xy 217.439786 -133.680366)
			(xy 217.369894 -133.723641) (xy 217.296308 -133.760284) (xy 217.219655 -133.78998) (xy 217.140589 -133.812478)
			(xy 217.059784 -133.827585) (xy 216.97793 -133.835172) (xy 216.936828 -133.835648) (xy 216.890433 -133.83506)
			(xy 216.798144 -133.825417) (xy 216.70736 -133.806223) (xy 216.619067 -133.777686) (xy 216.576402 -133.759448)
			(xy 216.56646 -133.755642) (xy 216.545196 -133.755642) (xy 216.535254 -133.759448) (xy 216.492589 -133.777686)
			(xy 216.404298 -133.806231) (xy 216.313513 -133.825426) (xy 216.221224 -133.835062) (xy 216.174828 -133.835648)
			(xy 216.131404 -133.835154) (xy 216.044966 -133.826739) (xy 215.959761 -133.809928) (xy 215.876604 -133.784881)
			(xy 215.836246 -133.768846) (xy 215.826836 -133.765374) (xy 215.806794 -133.765374) (xy 215.797384 -133.768846)
			(xy 215.757016 -133.78485) (xy 215.673856 -133.809876) (xy 215.588656 -133.826689) (xy 215.502224 -133.835131)
			(xy 215.458802 -133.835648) (xy 215.412406 -133.835069) (xy 215.320118 -133.825424) (xy 215.229334 -133.806227)
			(xy 215.141041 -133.777687) (xy 215.098376 -133.759448) (xy 215.088434 -133.755642) (xy 215.06717 -133.755642)
			(xy 215.057228 -133.759448) (xy 215.014567 -133.777695) (xy 214.926274 -133.806238) (xy 214.835489 -133.82543)
			(xy 214.743198 -133.835063) (xy 214.696802 -133.835648) (xy 214.655331 -133.835195) (xy 214.572745 -133.827514)
			(xy 214.491233 -133.812181) (xy 214.411501 -133.78933) (xy 214.372698 -133.774688) (xy 214.363204 -133.771495)
			(xy 214.343199 -133.771892) (xy 214.333836 -133.77545) (xy 214.291673 -133.793169) (xy 214.204503 -133.820863)
			(xy 214.114954 -133.839474) (xy 214.023968 -133.848804) (xy 213.978236 -133.849364) (xy 213.937132 -133.848913)
			(xy 213.855275 -133.841331) (xy 213.774466 -133.826228) (xy 213.695396 -133.803733) (xy 213.618739 -133.774037)
			(xy 213.54515 -133.737395) (xy 213.475255 -133.694119) (xy 213.409651 -133.644578) (xy 213.348899 -133.589195)
			(xy 213.293517 -133.528442) (xy 213.243976 -133.462839) (xy 213.200701 -133.392943) (xy 213.164059 -133.319353)
			(xy 213.134365 -133.242696) (xy 213.11187 -133.163626) (xy 213.096768 -133.082817) (xy 213.089186 -133.00096)
			(xy 213.088728 -132.959856) (xy 0.509016 -132.959856) (xy 0.509016 -136.959232) (xy 40.624242 -136.959232)
			(xy 40.624242 -136.852768) (xy 40.632198 -136.746601) (xy 40.648065 -136.641325) (xy 40.671756 -136.53753)
			(xy 40.703137 -136.435795) (xy 40.742033 -136.33669) (xy 40.788226 -136.240768) (xy 40.841459 -136.148567)
			(xy 40.901432 -136.060602) (xy 40.967812 -135.977365) (xy 41.040226 -135.89932) (xy 41.118271 -135.826906)
			(xy 41.201508 -135.760526) (xy 41.289473 -135.700553) (xy 41.381674 -135.64732) (xy 41.477596 -135.601127)
			(xy 41.576701 -135.562231) (xy 41.678436 -135.53085) (xy 41.782231 -135.507159) (xy 41.887507 -135.491292)
			(xy 41.993674 -135.483336) (xy 42.100138 -135.483336) (xy 42.206305 -135.491292) (xy 42.311581 -135.507159)
			(xy 42.415376 -135.53085) (xy 42.517111 -135.562231) (xy 42.616216 -135.601127) (xy 42.712138 -135.64732)
			(xy 42.804339 -135.700553) (xy 42.892304 -135.760526) (xy 42.975541 -135.826906) (xy 43.053586 -135.89932)
			(xy 43.126 -135.977365) (xy 43.19238 -136.060602) (xy 43.252353 -136.148567) (xy 43.305586 -136.240768)
			(xy 43.351779 -136.33669) (xy 43.390675 -136.435795) (xy 43.422056 -136.53753) (xy 43.445747 -136.641325)
			(xy 43.461614 -136.746601) (xy 43.46957 -136.852768) (xy 43.470068 -136.906) (xy 43.46957 -136.959232)
			(xy 52.816242 -136.959232) (xy 52.816242 -136.852768) (xy 52.824198 -136.746601) (xy 52.840065 -136.641325)
			(xy 52.863756 -136.53753) (xy 52.895137 -136.435795) (xy 52.934033 -136.33669) (xy 52.980226 -136.240768)
			(xy 53.033459 -136.148567) (xy 53.093432 -136.060602) (xy 53.159812 -135.977365) (xy 53.232226 -135.89932)
			(xy 53.310271 -135.826906) (xy 53.393508 -135.760526) (xy 53.481473 -135.700553) (xy 53.573674 -135.64732)
			(xy 53.669596 -135.601127) (xy 53.768701 -135.562231) (xy 53.870436 -135.53085) (xy 53.974231 -135.507159)
			(xy 54.079507 -135.491292) (xy 54.185674 -135.483336) (xy 54.292138 -135.483336) (xy 54.398305 -135.491292)
			(xy 54.503581 -135.507159) (xy 54.607376 -135.53085) (xy 54.709111 -135.562231) (xy 54.808216 -135.601127)
			(xy 54.904138 -135.64732) (xy 54.996339 -135.700553) (xy 55.084304 -135.760526) (xy 55.167541 -135.826906)
			(xy 55.245586 -135.89932) (xy 55.318 -135.977365) (xy 55.38438 -136.060602) (xy 55.444353 -136.148567)
			(xy 55.497586 -136.240768) (xy 55.543779 -136.33669) (xy 55.582675 -136.435795) (xy 55.614056 -136.53753)
			(xy 55.637747 -136.641325) (xy 55.653614 -136.746601) (xy 55.66157 -136.852768) (xy 55.662068 -136.906)
			(xy 55.66157 -136.959232) (xy 65.008242 -136.959232) (xy 65.008242 -136.852768) (xy 65.016198 -136.746601)
			(xy 65.032065 -136.641325) (xy 65.055756 -136.53753) (xy 65.087137 -136.435795) (xy 65.126033 -136.33669)
			(xy 65.172226 -136.240768) (xy 65.225459 -136.148567) (xy 65.285432 -136.060602) (xy 65.351812 -135.977365)
			(xy 65.424226 -135.89932) (xy 65.502271 -135.826906) (xy 65.585508 -135.760526) (xy 65.673473 -135.700553)
			(xy 65.765674 -135.64732) (xy 65.861596 -135.601127) (xy 65.960701 -135.562231) (xy 66.062436 -135.53085)
			(xy 66.166231 -135.507159) (xy 66.271507 -135.491292) (xy 66.377674 -135.483336) (xy 66.484138 -135.483336)
			(xy 66.590305 -135.491292) (xy 66.695581 -135.507159) (xy 66.799376 -135.53085) (xy 66.901111 -135.562231)
			(xy 67.000216 -135.601127) (xy 67.096138 -135.64732) (xy 67.188339 -135.700553) (xy 67.276304 -135.760526)
			(xy 67.359541 -135.826906) (xy 67.437586 -135.89932) (xy 67.51 -135.977365) (xy 67.57638 -136.060602)
			(xy 67.636353 -136.148567) (xy 67.689586 -136.240768) (xy 67.735779 -136.33669) (xy 67.774675 -136.435795)
			(xy 67.806056 -136.53753) (xy 67.829747 -136.641325) (xy 67.845614 -136.746601) (xy 67.85357 -136.852768)
			(xy 67.854068 -136.906) (xy 67.85357 -136.959232) (xy 80.624162 -136.959232) (xy 80.624162 -136.852768)
			(xy 80.632118 -136.746601) (xy 80.647985 -136.641325) (xy 80.671676 -136.53753) (xy 80.703057 -136.435795)
			(xy 80.741953 -136.33669) (xy 80.788146 -136.240768) (xy 80.841379 -136.148567) (xy 80.901352 -136.060602)
			(xy 80.967732 -135.977365) (xy 81.040146 -135.89932) (xy 81.118191 -135.826906) (xy 81.201428 -135.760526)
			(xy 81.289393 -135.700553) (xy 81.381594 -135.64732) (xy 81.477516 -135.601127) (xy 81.576621 -135.562231)
			(xy 81.678356 -135.53085) (xy 81.782151 -135.507159) (xy 81.887427 -135.491292) (xy 81.993594 -135.483336)
			(xy 82.100058 -135.483336) (xy 82.206225 -135.491292) (xy 82.311501 -135.507159) (xy 82.415296 -135.53085)
			(xy 82.517031 -135.562231) (xy 82.616136 -135.601127) (xy 82.712058 -135.64732) (xy 82.804259 -135.700553)
			(xy 82.892224 -135.760526) (xy 82.975461 -135.826906) (xy 83.053506 -135.89932) (xy 83.12592 -135.977365)
			(xy 83.1923 -136.060602) (xy 83.252273 -136.148567) (xy 83.305506 -136.240768) (xy 83.351699 -136.33669)
			(xy 83.390595 -136.435795) (xy 83.421976 -136.53753) (xy 83.445667 -136.641325) (xy 83.461534 -136.746601)
			(xy 83.46949 -136.852768) (xy 83.469988 -136.906) (xy 83.46949 -136.959232) (xy 92.816162 -136.959232)
			(xy 92.816162 -136.852768) (xy 92.824118 -136.746601) (xy 92.839985 -136.641325) (xy 92.863676 -136.53753)
			(xy 92.895057 -136.435795) (xy 92.933953 -136.33669) (xy 92.980146 -136.240768) (xy 93.033379 -136.148567)
			(xy 93.093352 -136.060602) (xy 93.159732 -135.977365) (xy 93.232146 -135.89932) (xy 93.310191 -135.826906)
			(xy 93.393428 -135.760526) (xy 93.481393 -135.700553) (xy 93.573594 -135.64732) (xy 93.669516 -135.601127)
			(xy 93.768621 -135.562231) (xy 93.870356 -135.53085) (xy 93.974151 -135.507159) (xy 94.079427 -135.491292)
			(xy 94.185594 -135.483336) (xy 94.292058 -135.483336) (xy 94.398225 -135.491292) (xy 94.503501 -135.507159)
			(xy 94.607296 -135.53085) (xy 94.709031 -135.562231) (xy 94.808136 -135.601127) (xy 94.904058 -135.64732)
			(xy 94.996259 -135.700553) (xy 95.084224 -135.760526) (xy 95.167461 -135.826906) (xy 95.245506 -135.89932)
			(xy 95.31792 -135.977365) (xy 95.3843 -136.060602) (xy 95.444273 -136.148567) (xy 95.497506 -136.240768)
			(xy 95.543699 -136.33669) (xy 95.582595 -136.435795) (xy 95.613976 -136.53753) (xy 95.637667 -136.641325)
			(xy 95.653534 -136.746601) (xy 95.66149 -136.852768) (xy 95.661988 -136.906) (xy 95.66149 -136.959232)
			(xy 105.008162 -136.959232) (xy 105.008162 -136.852768) (xy 105.016118 -136.746601) (xy 105.031985 -136.641325)
			(xy 105.055676 -136.53753) (xy 105.087057 -136.435795) (xy 105.125953 -136.33669) (xy 105.172146 -136.240768)
			(xy 105.225379 -136.148567) (xy 105.285352 -136.060602) (xy 105.351732 -135.977365) (xy 105.424146 -135.89932)
			(xy 105.502191 -135.826906) (xy 105.585428 -135.760526) (xy 105.673393 -135.700553) (xy 105.765594 -135.64732)
			(xy 105.861516 -135.601127) (xy 105.960621 -135.562231) (xy 106.062356 -135.53085) (xy 106.166151 -135.507159)
			(xy 106.271427 -135.491292) (xy 106.377594 -135.483336) (xy 106.484058 -135.483336) (xy 106.590225 -135.491292)
			(xy 106.695501 -135.507159) (xy 106.799296 -135.53085) (xy 106.901031 -135.562231) (xy 107.000136 -135.601127)
			(xy 107.096058 -135.64732) (xy 107.188259 -135.700553) (xy 107.276224 -135.760526) (xy 107.359461 -135.826906)
			(xy 107.437506 -135.89932) (xy 107.50992 -135.977365) (xy 107.5763 -136.060602) (xy 107.636273 -136.148567)
			(xy 107.689506 -136.240768) (xy 107.735699 -136.33669) (xy 107.774595 -136.435795) (xy 107.805976 -136.53753)
			(xy 107.829667 -136.641325) (xy 107.845534 -136.746601) (xy 107.85349 -136.852768) (xy 107.853988 -136.906)
			(xy 107.85349 -136.959232) (xy 120.624336 -136.959232) (xy 120.624336 -136.852768) (xy 120.632292 -136.746601)
			(xy 120.648159 -136.641325) (xy 120.67185 -136.53753) (xy 120.703231 -136.435795) (xy 120.742127 -136.33669)
			(xy 120.78832 -136.240768) (xy 120.841553 -136.148567) (xy 120.901526 -136.060602) (xy 120.967906 -135.977365)
			(xy 121.04032 -135.89932) (xy 121.118365 -135.826906) (xy 121.201602 -135.760526) (xy 121.289567 -135.700553)
			(xy 121.381768 -135.64732) (xy 121.47769 -135.601127) (xy 121.576795 -135.562231) (xy 121.67853 -135.53085)
			(xy 121.782325 -135.507159) (xy 121.887601 -135.491292) (xy 121.993768 -135.483336) (xy 122.100232 -135.483336)
			(xy 122.206399 -135.491292) (xy 122.311675 -135.507159) (xy 122.41547 -135.53085) (xy 122.517205 -135.562231)
			(xy 122.61631 -135.601127) (xy 122.712232 -135.64732) (xy 122.804433 -135.700553) (xy 122.892398 -135.760526)
			(xy 122.975635 -135.826906) (xy 123.05368 -135.89932) (xy 123.126094 -135.977365) (xy 123.192474 -136.060602)
			(xy 123.252447 -136.148567) (xy 123.30568 -136.240768) (xy 123.351873 -136.33669) (xy 123.390769 -136.435795)
			(xy 123.42215 -136.53753) (xy 123.445841 -136.641325) (xy 123.461708 -136.746601) (xy 123.469664 -136.852768)
			(xy 123.470162 -136.906) (xy 123.469664 -136.959232) (xy 132.816336 -136.959232) (xy 132.816336 -136.852768)
			(xy 132.824292 -136.746601) (xy 132.840159 -136.641325) (xy 132.86385 -136.53753) (xy 132.895231 -136.435795)
			(xy 132.934127 -136.33669) (xy 132.98032 -136.240768) (xy 133.033553 -136.148567) (xy 133.093526 -136.060602)
			(xy 133.159906 -135.977365) (xy 133.23232 -135.89932) (xy 133.310365 -135.826906) (xy 133.393602 -135.760526)
			(xy 133.481567 -135.700553) (xy 133.573768 -135.64732) (xy 133.66969 -135.601127) (xy 133.768795 -135.562231)
			(xy 133.87053 -135.53085) (xy 133.974325 -135.507159) (xy 134.079601 -135.491292) (xy 134.185768 -135.483336)
			(xy 134.292232 -135.483336) (xy 134.398399 -135.491292) (xy 134.503675 -135.507159) (xy 134.60747 -135.53085)
			(xy 134.709205 -135.562231) (xy 134.80831 -135.601127) (xy 134.904232 -135.64732) (xy 134.996433 -135.700553)
			(xy 135.084398 -135.760526) (xy 135.167635 -135.826906) (xy 135.24568 -135.89932) (xy 135.318094 -135.977365)
			(xy 135.384474 -136.060602) (xy 135.444447 -136.148567) (xy 135.49768 -136.240768) (xy 135.543873 -136.33669)
			(xy 135.582769 -136.435795) (xy 135.61415 -136.53753) (xy 135.637841 -136.641325) (xy 135.653708 -136.746601)
			(xy 135.661664 -136.852768) (xy 135.662162 -136.906) (xy 135.661664 -136.959232) (xy 145.008336 -136.959232)
			(xy 145.008336 -136.852768) (xy 145.016292 -136.746601) (xy 145.032159 -136.641325) (xy 145.05585 -136.53753)
			(xy 145.087231 -136.435795) (xy 145.126127 -136.33669) (xy 145.17232 -136.240768) (xy 145.225553 -136.148567)
			(xy 145.285526 -136.060602) (xy 145.351906 -135.977365) (xy 145.42432 -135.89932) (xy 145.502365 -135.826906)
			(xy 145.585602 -135.760526) (xy 145.673567 -135.700553) (xy 145.765768 -135.64732) (xy 145.86169 -135.601127)
			(xy 145.960795 -135.562231) (xy 146.06253 -135.53085) (xy 146.166325 -135.507159) (xy 146.271601 -135.491292)
			(xy 146.377768 -135.483336) (xy 146.484232 -135.483336) (xy 146.590399 -135.491292) (xy 146.695675 -135.507159)
			(xy 146.79947 -135.53085) (xy 146.901205 -135.562231) (xy 147.00031 -135.601127) (xy 147.096232 -135.64732)
			(xy 147.188433 -135.700553) (xy 147.276398 -135.760526) (xy 147.359635 -135.826906) (xy 147.43768 -135.89932)
			(xy 147.510094 -135.977365) (xy 147.576474 -136.060602) (xy 147.636447 -136.148567) (xy 147.68968 -136.240768)
			(xy 147.735873 -136.33669) (xy 147.774769 -136.435795) (xy 147.80615 -136.53753) (xy 147.829841 -136.641325)
			(xy 147.845708 -136.746601) (xy 147.853664 -136.852768) (xy 147.854162 -136.906) (xy 147.853664 -136.959232)
			(xy 160.62451 -136.959232) (xy 160.62451 -136.852768) (xy 160.632466 -136.746601) (xy 160.648333 -136.641325)
			(xy 160.672024 -136.53753) (xy 160.703405 -136.435795) (xy 160.742301 -136.33669) (xy 160.788494 -136.240768)
			(xy 160.841727 -136.148567) (xy 160.9017 -136.060602) (xy 160.96808 -135.977365) (xy 161.040494 -135.89932)
			(xy 161.118539 -135.826906) (xy 161.201776 -135.760526) (xy 161.289741 -135.700553) (xy 161.381942 -135.64732)
			(xy 161.477864 -135.601127) (xy 161.576969 -135.562231) (xy 161.678704 -135.53085) (xy 161.782499 -135.507159)
			(xy 161.887775 -135.491292) (xy 161.993942 -135.483336) (xy 162.100406 -135.483336) (xy 162.206573 -135.491292)
			(xy 162.311849 -135.507159) (xy 162.415644 -135.53085) (xy 162.517379 -135.562231) (xy 162.616484 -135.601127)
			(xy 162.712406 -135.64732) (xy 162.804607 -135.700553) (xy 162.892572 -135.760526) (xy 162.975809 -135.826906)
			(xy 163.053854 -135.89932) (xy 163.126268 -135.977365) (xy 163.192648 -136.060602) (xy 163.252621 -136.148567)
			(xy 163.305854 -136.240768) (xy 163.352047 -136.33669) (xy 163.390943 -136.435795) (xy 163.422324 -136.53753)
			(xy 163.446015 -136.641325) (xy 163.461882 -136.746601) (xy 163.469838 -136.852768) (xy 163.470336 -136.906)
			(xy 163.469838 -136.959232) (xy 172.81651 -136.959232) (xy 172.81651 -136.852768) (xy 172.824466 -136.746601)
			(xy 172.840333 -136.641325) (xy 172.864024 -136.53753) (xy 172.895405 -136.435795) (xy 172.934301 -136.33669)
			(xy 172.980494 -136.240768) (xy 173.033727 -136.148567) (xy 173.0937 -136.060602) (xy 173.16008 -135.977365)
			(xy 173.232494 -135.89932) (xy 173.310539 -135.826906) (xy 173.393776 -135.760526) (xy 173.481741 -135.700553)
			(xy 173.573942 -135.64732) (xy 173.669864 -135.601127) (xy 173.768969 -135.562231) (xy 173.870704 -135.53085)
			(xy 173.974499 -135.507159) (xy 174.079775 -135.491292) (xy 174.185942 -135.483336) (xy 174.292406 -135.483336)
			(xy 174.398573 -135.491292) (xy 174.503849 -135.507159) (xy 174.607644 -135.53085) (xy 174.709379 -135.562231)
			(xy 174.808484 -135.601127) (xy 174.904406 -135.64732) (xy 174.996607 -135.700553) (xy 175.084572 -135.760526)
			(xy 175.167809 -135.826906) (xy 175.245854 -135.89932) (xy 175.318268 -135.977365) (xy 175.384648 -136.060602)
			(xy 175.444621 -136.148567) (xy 175.497854 -136.240768) (xy 175.544047 -136.33669) (xy 175.582943 -136.435795)
			(xy 175.614324 -136.53753) (xy 175.638015 -136.641325) (xy 175.653882 -136.746601) (xy 175.661838 -136.852768)
			(xy 175.662336 -136.906) (xy 175.661838 -136.959232) (xy 185.00851 -136.959232) (xy 185.00851 -136.852768)
			(xy 185.016466 -136.746601) (xy 185.032333 -136.641325) (xy 185.056024 -136.53753) (xy 185.087405 -136.435795)
			(xy 185.126301 -136.33669) (xy 185.172494 -136.240768) (xy 185.225727 -136.148567) (xy 185.2857 -136.060602)
			(xy 185.35208 -135.977365) (xy 185.424494 -135.89932) (xy 185.502539 -135.826906) (xy 185.585776 -135.760526)
			(xy 185.673741 -135.700553) (xy 185.765942 -135.64732) (xy 185.861864 -135.601127) (xy 185.960969 -135.562231)
			(xy 186.062704 -135.53085) (xy 186.166499 -135.507159) (xy 186.271775 -135.491292) (xy 186.377942 -135.483336)
			(xy 186.484406 -135.483336) (xy 186.590573 -135.491292) (xy 186.695849 -135.507159) (xy 186.799644 -135.53085)
			(xy 186.901379 -135.562231) (xy 187.000484 -135.601127) (xy 187.096406 -135.64732) (xy 187.188607 -135.700553)
			(xy 187.276572 -135.760526) (xy 187.359809 -135.826906) (xy 187.437854 -135.89932) (xy 187.510268 -135.977365)
			(xy 187.576648 -136.060602) (xy 187.636621 -136.148567) (xy 187.689854 -136.240768) (xy 187.736047 -136.33669)
			(xy 187.774943 -136.435795) (xy 187.806324 -136.53753) (xy 187.830015 -136.641325) (xy 187.845882 -136.746601)
			(xy 187.853838 -136.852768) (xy 187.854336 -136.906) (xy 187.853838 -136.959232) (xy 187.845882 -137.065399)
			(xy 187.830015 -137.170675) (xy 187.806324 -137.27447) (xy 187.774943 -137.376205) (xy 187.736047 -137.47531)
			(xy 187.689854 -137.571232) (xy 187.636621 -137.663433) (xy 187.576648 -137.751398) (xy 187.510268 -137.834635)
			(xy 187.437854 -137.91268) (xy 187.359809 -137.985094) (xy 187.276572 -138.051474) (xy 187.188607 -138.111447)
			(xy 187.096406 -138.16468) (xy 187.000484 -138.210873) (xy 186.901379 -138.249769) (xy 186.799644 -138.28115)
			(xy 186.695849 -138.304841) (xy 186.590573 -138.320708) (xy 186.484406 -138.328664) (xy 186.377942 -138.328664)
			(xy 186.271775 -138.320708) (xy 186.166499 -138.304841) (xy 186.062704 -138.28115) (xy 185.960969 -138.249769)
			(xy 185.861864 -138.210873) (xy 185.765942 -138.16468) (xy 185.673741 -138.111447) (xy 185.585776 -138.051474)
			(xy 185.502539 -137.985094) (xy 185.424494 -137.91268) (xy 185.35208 -137.834635) (xy 185.2857 -137.751398)
			(xy 185.225727 -137.663433) (xy 185.172494 -137.571232) (xy 185.126301 -137.47531) (xy 185.087405 -137.376205)
			(xy 185.056024 -137.27447) (xy 185.032333 -137.170675) (xy 185.016466 -137.065399) (xy 185.00851 -136.959232)
			(xy 175.661838 -136.959232) (xy 175.653882 -137.065399) (xy 175.638015 -137.170675) (xy 175.614324 -137.27447)
			(xy 175.582943 -137.376205) (xy 175.544047 -137.47531) (xy 175.497854 -137.571232) (xy 175.444621 -137.663433)
			(xy 175.384648 -137.751398) (xy 175.318268 -137.834635) (xy 175.245854 -137.91268) (xy 175.167809 -137.985094)
			(xy 175.084572 -138.051474) (xy 174.996607 -138.111447) (xy 174.904406 -138.16468) (xy 174.808484 -138.210873)
			(xy 174.709379 -138.249769) (xy 174.607644 -138.28115) (xy 174.503849 -138.304841) (xy 174.398573 -138.320708)
			(xy 174.292406 -138.328664) (xy 174.185942 -138.328664) (xy 174.079775 -138.320708) (xy 173.974499 -138.304841)
			(xy 173.870704 -138.28115) (xy 173.768969 -138.249769) (xy 173.669864 -138.210873) (xy 173.573942 -138.16468)
			(xy 173.481741 -138.111447) (xy 173.393776 -138.051474) (xy 173.310539 -137.985094) (xy 173.232494 -137.91268)
			(xy 173.16008 -137.834635) (xy 173.0937 -137.751398) (xy 173.033727 -137.663433) (xy 172.980494 -137.571232)
			(xy 172.934301 -137.47531) (xy 172.895405 -137.376205) (xy 172.864024 -137.27447) (xy 172.840333 -137.170675)
			(xy 172.824466 -137.065399) (xy 172.81651 -136.959232) (xy 163.469838 -136.959232) (xy 163.461882 -137.065399)
			(xy 163.446015 -137.170675) (xy 163.422324 -137.27447) (xy 163.390943 -137.376205) (xy 163.352047 -137.47531)
			(xy 163.305854 -137.571232) (xy 163.252621 -137.663433) (xy 163.192648 -137.751398) (xy 163.126268 -137.834635)
			(xy 163.053854 -137.91268) (xy 162.975809 -137.985094) (xy 162.892572 -138.051474) (xy 162.804607 -138.111447)
			(xy 162.712406 -138.16468) (xy 162.616484 -138.210873) (xy 162.517379 -138.249769) (xy 162.415644 -138.28115)
			(xy 162.311849 -138.304841) (xy 162.206573 -138.320708) (xy 162.100406 -138.328664) (xy 161.993942 -138.328664)
			(xy 161.887775 -138.320708) (xy 161.782499 -138.304841) (xy 161.678704 -138.28115) (xy 161.576969 -138.249769)
			(xy 161.477864 -138.210873) (xy 161.381942 -138.16468) (xy 161.289741 -138.111447) (xy 161.201776 -138.051474)
			(xy 161.118539 -137.985094) (xy 161.040494 -137.91268) (xy 160.96808 -137.834635) (xy 160.9017 -137.751398)
			(xy 160.841727 -137.663433) (xy 160.788494 -137.571232) (xy 160.742301 -137.47531) (xy 160.703405 -137.376205)
			(xy 160.672024 -137.27447) (xy 160.648333 -137.170675) (xy 160.632466 -137.065399) (xy 160.62451 -136.959232)
			(xy 147.853664 -136.959232) (xy 147.845708 -137.065399) (xy 147.829841 -137.170675) (xy 147.80615 -137.27447)
			(xy 147.774769 -137.376205) (xy 147.735873 -137.47531) (xy 147.68968 -137.571232) (xy 147.636447 -137.663433)
			(xy 147.576474 -137.751398) (xy 147.510094 -137.834635) (xy 147.43768 -137.91268) (xy 147.359635 -137.985094)
			(xy 147.276398 -138.051474) (xy 147.188433 -138.111447) (xy 147.096232 -138.16468) (xy 147.00031 -138.210873)
			(xy 146.901205 -138.249769) (xy 146.79947 -138.28115) (xy 146.695675 -138.304841) (xy 146.590399 -138.320708)
			(xy 146.484232 -138.328664) (xy 146.377768 -138.328664) (xy 146.271601 -138.320708) (xy 146.166325 -138.304841)
			(xy 146.06253 -138.28115) (xy 145.960795 -138.249769) (xy 145.86169 -138.210873) (xy 145.765768 -138.16468)
			(xy 145.673567 -138.111447) (xy 145.585602 -138.051474) (xy 145.502365 -137.985094) (xy 145.42432 -137.91268)
			(xy 145.351906 -137.834635) (xy 145.285526 -137.751398) (xy 145.225553 -137.663433) (xy 145.17232 -137.571232)
			(xy 145.126127 -137.47531) (xy 145.087231 -137.376205) (xy 145.05585 -137.27447) (xy 145.032159 -137.170675)
			(xy 145.016292 -137.065399) (xy 145.008336 -136.959232) (xy 135.661664 -136.959232) (xy 135.653708 -137.065399)
			(xy 135.637841 -137.170675) (xy 135.61415 -137.27447) (xy 135.582769 -137.376205) (xy 135.543873 -137.47531)
			(xy 135.49768 -137.571232) (xy 135.444447 -137.663433) (xy 135.384474 -137.751398) (xy 135.318094 -137.834635)
			(xy 135.24568 -137.91268) (xy 135.167635 -137.985094) (xy 135.084398 -138.051474) (xy 134.996433 -138.111447)
			(xy 134.904232 -138.16468) (xy 134.80831 -138.210873) (xy 134.709205 -138.249769) (xy 134.60747 -138.28115)
			(xy 134.503675 -138.304841) (xy 134.398399 -138.320708) (xy 134.292232 -138.328664) (xy 134.185768 -138.328664)
			(xy 134.079601 -138.320708) (xy 133.974325 -138.304841) (xy 133.87053 -138.28115) (xy 133.768795 -138.249769)
			(xy 133.66969 -138.210873) (xy 133.573768 -138.16468) (xy 133.481567 -138.111447) (xy 133.393602 -138.051474)
			(xy 133.310365 -137.985094) (xy 133.23232 -137.91268) (xy 133.159906 -137.834635) (xy 133.093526 -137.751398)
			(xy 133.033553 -137.663433) (xy 132.98032 -137.571232) (xy 132.934127 -137.47531) (xy 132.895231 -137.376205)
			(xy 132.86385 -137.27447) (xy 132.840159 -137.170675) (xy 132.824292 -137.065399) (xy 132.816336 -136.959232)
			(xy 123.469664 -136.959232) (xy 123.461708 -137.065399) (xy 123.445841 -137.170675) (xy 123.42215 -137.27447)
			(xy 123.390769 -137.376205) (xy 123.351873 -137.47531) (xy 123.30568 -137.571232) (xy 123.252447 -137.663433)
			(xy 123.192474 -137.751398) (xy 123.126094 -137.834635) (xy 123.05368 -137.91268) (xy 122.975635 -137.985094)
			(xy 122.892398 -138.051474) (xy 122.804433 -138.111447) (xy 122.712232 -138.16468) (xy 122.61631 -138.210873)
			(xy 122.517205 -138.249769) (xy 122.41547 -138.28115) (xy 122.311675 -138.304841) (xy 122.206399 -138.320708)
			(xy 122.100232 -138.328664) (xy 121.993768 -138.328664) (xy 121.887601 -138.320708) (xy 121.782325 -138.304841)
			(xy 121.67853 -138.28115) (xy 121.576795 -138.249769) (xy 121.47769 -138.210873) (xy 121.381768 -138.16468)
			(xy 121.289567 -138.111447) (xy 121.201602 -138.051474) (xy 121.118365 -137.985094) (xy 121.04032 -137.91268)
			(xy 120.967906 -137.834635) (xy 120.901526 -137.751398) (xy 120.841553 -137.663433) (xy 120.78832 -137.571232)
			(xy 120.742127 -137.47531) (xy 120.703231 -137.376205) (xy 120.67185 -137.27447) (xy 120.648159 -137.170675)
			(xy 120.632292 -137.065399) (xy 120.624336 -136.959232) (xy 107.85349 -136.959232) (xy 107.845534 -137.065399)
			(xy 107.829667 -137.170675) (xy 107.805976 -137.27447) (xy 107.774595 -137.376205) (xy 107.735699 -137.47531)
			(xy 107.689506 -137.571232) (xy 107.636273 -137.663433) (xy 107.5763 -137.751398) (xy 107.50992 -137.834635)
			(xy 107.437506 -137.91268) (xy 107.359461 -137.985094) (xy 107.276224 -138.051474) (xy 107.188259 -138.111447)
			(xy 107.096058 -138.16468) (xy 107.000136 -138.210873) (xy 106.901031 -138.249769) (xy 106.799296 -138.28115)
			(xy 106.695501 -138.304841) (xy 106.590225 -138.320708) (xy 106.484058 -138.328664) (xy 106.377594 -138.328664)
			(xy 106.271427 -138.320708) (xy 106.166151 -138.304841) (xy 106.062356 -138.28115) (xy 105.960621 -138.249769)
			(xy 105.861516 -138.210873) (xy 105.765594 -138.16468) (xy 105.673393 -138.111447) (xy 105.585428 -138.051474)
			(xy 105.502191 -137.985094) (xy 105.424146 -137.91268) (xy 105.351732 -137.834635) (xy 105.285352 -137.751398)
			(xy 105.225379 -137.663433) (xy 105.172146 -137.571232) (xy 105.125953 -137.47531) (xy 105.087057 -137.376205)
			(xy 105.055676 -137.27447) (xy 105.031985 -137.170675) (xy 105.016118 -137.065399) (xy 105.008162 -136.959232)
			(xy 95.66149 -136.959232) (xy 95.653534 -137.065399) (xy 95.637667 -137.170675) (xy 95.613976 -137.27447)
			(xy 95.582595 -137.376205) (xy 95.543699 -137.47531) (xy 95.497506 -137.571232) (xy 95.444273 -137.663433)
			(xy 95.3843 -137.751398) (xy 95.31792 -137.834635) (xy 95.245506 -137.91268) (xy 95.167461 -137.985094)
			(xy 95.084224 -138.051474) (xy 94.996259 -138.111447) (xy 94.904058 -138.16468) (xy 94.808136 -138.210873)
			(xy 94.709031 -138.249769) (xy 94.607296 -138.28115) (xy 94.503501 -138.304841) (xy 94.398225 -138.320708)
			(xy 94.292058 -138.328664) (xy 94.185594 -138.328664) (xy 94.079427 -138.320708) (xy 93.974151 -138.304841)
			(xy 93.870356 -138.28115) (xy 93.768621 -138.249769) (xy 93.669516 -138.210873) (xy 93.573594 -138.16468)
			(xy 93.481393 -138.111447) (xy 93.393428 -138.051474) (xy 93.310191 -137.985094) (xy 93.232146 -137.91268)
			(xy 93.159732 -137.834635) (xy 93.093352 -137.751398) (xy 93.033379 -137.663433) (xy 92.980146 -137.571232)
			(xy 92.933953 -137.47531) (xy 92.895057 -137.376205) (xy 92.863676 -137.27447) (xy 92.839985 -137.170675)
			(xy 92.824118 -137.065399) (xy 92.816162 -136.959232) (xy 83.46949 -136.959232) (xy 83.461534 -137.065399)
			(xy 83.445667 -137.170675) (xy 83.421976 -137.27447) (xy 83.390595 -137.376205) (xy 83.351699 -137.47531)
			(xy 83.305506 -137.571232) (xy 83.252273 -137.663433) (xy 83.1923 -137.751398) (xy 83.12592 -137.834635)
			(xy 83.053506 -137.91268) (xy 82.975461 -137.985094) (xy 82.892224 -138.051474) (xy 82.804259 -138.111447)
			(xy 82.712058 -138.16468) (xy 82.616136 -138.210873) (xy 82.517031 -138.249769) (xy 82.415296 -138.28115)
			(xy 82.311501 -138.304841) (xy 82.206225 -138.320708) (xy 82.100058 -138.328664) (xy 81.993594 -138.328664)
			(xy 81.887427 -138.320708) (xy 81.782151 -138.304841) (xy 81.678356 -138.28115) (xy 81.576621 -138.249769)
			(xy 81.477516 -138.210873) (xy 81.381594 -138.16468) (xy 81.289393 -138.111447) (xy 81.201428 -138.051474)
			(xy 81.118191 -137.985094) (xy 81.040146 -137.91268) (xy 80.967732 -137.834635) (xy 80.901352 -137.751398)
			(xy 80.841379 -137.663433) (xy 80.788146 -137.571232) (xy 80.741953 -137.47531) (xy 80.703057 -137.376205)
			(xy 80.671676 -137.27447) (xy 80.647985 -137.170675) (xy 80.632118 -137.065399) (xy 80.624162 -136.959232)
			(xy 67.85357 -136.959232) (xy 67.845614 -137.065399) (xy 67.829747 -137.170675) (xy 67.806056 -137.27447)
			(xy 67.774675 -137.376205) (xy 67.735779 -137.47531) (xy 67.689586 -137.571232) (xy 67.636353 -137.663433)
			(xy 67.57638 -137.751398) (xy 67.51 -137.834635) (xy 67.437586 -137.91268) (xy 67.359541 -137.985094)
			(xy 67.276304 -138.051474) (xy 67.188339 -138.111447) (xy 67.096138 -138.16468) (xy 67.000216 -138.210873)
			(xy 66.901111 -138.249769) (xy 66.799376 -138.28115) (xy 66.695581 -138.304841) (xy 66.590305 -138.320708)
			(xy 66.484138 -138.328664) (xy 66.377674 -138.328664) (xy 66.271507 -138.320708) (xy 66.166231 -138.304841)
			(xy 66.062436 -138.28115) (xy 65.960701 -138.249769) (xy 65.861596 -138.210873) (xy 65.765674 -138.16468)
			(xy 65.673473 -138.111447) (xy 65.585508 -138.051474) (xy 65.502271 -137.985094) (xy 65.424226 -137.91268)
			(xy 65.351812 -137.834635) (xy 65.285432 -137.751398) (xy 65.225459 -137.663433) (xy 65.172226 -137.571232)
			(xy 65.126033 -137.47531) (xy 65.087137 -137.376205) (xy 65.055756 -137.27447) (xy 65.032065 -137.170675)
			(xy 65.016198 -137.065399) (xy 65.008242 -136.959232) (xy 55.66157 -136.959232) (xy 55.653614 -137.065399)
			(xy 55.637747 -137.170675) (xy 55.614056 -137.27447) (xy 55.582675 -137.376205) (xy 55.543779 -137.47531)
			(xy 55.497586 -137.571232) (xy 55.444353 -137.663433) (xy 55.38438 -137.751398) (xy 55.318 -137.834635)
			(xy 55.245586 -137.91268) (xy 55.167541 -137.985094) (xy 55.084304 -138.051474) (xy 54.996339 -138.111447)
			(xy 54.904138 -138.16468) (xy 54.808216 -138.210873) (xy 54.709111 -138.249769) (xy 54.607376 -138.28115)
			(xy 54.503581 -138.304841) (xy 54.398305 -138.320708) (xy 54.292138 -138.328664) (xy 54.185674 -138.328664)
			(xy 54.079507 -138.320708) (xy 53.974231 -138.304841) (xy 53.870436 -138.28115) (xy 53.768701 -138.249769)
			(xy 53.669596 -138.210873) (xy 53.573674 -138.16468) (xy 53.481473 -138.111447) (xy 53.393508 -138.051474)
			(xy 53.310271 -137.985094) (xy 53.232226 -137.91268) (xy 53.159812 -137.834635) (xy 53.093432 -137.751398)
			(xy 53.033459 -137.663433) (xy 52.980226 -137.571232) (xy 52.934033 -137.47531) (xy 52.895137 -137.376205)
			(xy 52.863756 -137.27447) (xy 52.840065 -137.170675) (xy 52.824198 -137.065399) (xy 52.816242 -136.959232)
			(xy 43.46957 -136.959232) (xy 43.461614 -137.065399) (xy 43.445747 -137.170675) (xy 43.422056 -137.27447)
			(xy 43.390675 -137.376205) (xy 43.351779 -137.47531) (xy 43.305586 -137.571232) (xy 43.252353 -137.663433)
			(xy 43.19238 -137.751398) (xy 43.126 -137.834635) (xy 43.053586 -137.91268) (xy 42.975541 -137.985094)
			(xy 42.892304 -138.051474) (xy 42.804339 -138.111447) (xy 42.712138 -138.16468) (xy 42.616216 -138.210873)
			(xy 42.517111 -138.249769) (xy 42.415376 -138.28115) (xy 42.311581 -138.304841) (xy 42.206305 -138.320708)
			(xy 42.100138 -138.328664) (xy 41.993674 -138.328664) (xy 41.887507 -138.320708) (xy 41.782231 -138.304841)
			(xy 41.678436 -138.28115) (xy 41.576701 -138.249769) (xy 41.477596 -138.210873) (xy 41.381674 -138.16468)
			(xy 41.289473 -138.111447) (xy 41.201508 -138.051474) (xy 41.118271 -137.985094) (xy 41.040226 -137.91268)
			(xy 40.967812 -137.834635) (xy 40.901432 -137.751398) (xy 40.841459 -137.663433) (xy 40.788226 -137.571232)
			(xy 40.742033 -137.47531) (xy 40.703137 -137.376205) (xy 40.671756 -137.27447) (xy 40.648065 -137.170675)
			(xy 40.632198 -137.065399) (xy 40.624242 -136.959232) (xy 0.509016 -136.959232) (xy 0.509016 -141.95405)
			(xy 220.791775 -141.95405) (xy 220.791775 -141.82491) (xy 220.799725 -141.696015) (xy 220.815595 -141.567855)
			(xy 220.839324 -141.440914) (xy 220.870823 -141.315675) (xy 220.909972 -141.192612) (xy 220.956623 -141.072193)
			(xy 221.010598 -140.954874) (xy 221.071693 -140.8411) (xy 221.139676 -140.731303) (xy 221.21429 -140.6259)
			(xy 221.295251 -140.52529) (xy 221.382251 -140.429855) (xy 221.474962 -140.339956) (xy 221.573032 -140.255935)
			(xy 221.676087 -140.178111) (xy 221.783738 -140.106779) (xy 221.895577 -140.042209) (xy 222.011178 -139.984647)
			(xy 222.130103 -139.93431) (xy 222.251902 -139.89139) (xy 222.376112 -139.856049) (xy 222.502261 -139.828422)
			(xy 222.629873 -139.808613) (xy 222.758462 -139.796697) (xy 222.88754 -139.792721) (xy 223.016618 -139.796697)
			(xy 223.145207 -139.808613) (xy 223.272819 -139.828422) (xy 223.398968 -139.856049) (xy 223.523178 -139.89139)
			(xy 223.644977 -139.93431) (xy 223.763902 -139.984647) (xy 223.879503 -140.042209) (xy 223.991342 -140.106779)
			(xy 224.098993 -140.178111) (xy 224.202048 -140.255935) (xy 224.300118 -140.339956) (xy 224.392829 -140.429855)
			(xy 224.422133 -140.462) (xy 270.001492 -140.462) (xy 270.002075 -140.415604) (xy 270.01172 -140.323316)
			(xy 270.030916 -140.232532) (xy 270.059454 -140.144239) (xy 270.077692 -140.101574) (xy 270.081498 -140.091632)
			(xy 270.081498 -140.070368) (xy 270.077692 -140.060426) (xy 270.059447 -140.017764) (xy 270.030903 -139.929471)
			(xy 270.01171 -139.838686) (xy 270.002077 -139.746396) (xy 270.001492 -139.7) (xy 270.002075 -139.653604)
			(xy 270.01172 -139.561316) (xy 270.030916 -139.470532) (xy 270.059454 -139.382239) (xy 270.077692 -139.339574)
			(xy 270.081498 -139.329632) (xy 270.081498 -139.308368) (xy 270.077692 -139.298426) (xy 270.059447 -139.255764)
			(xy 270.030903 -139.167471) (xy 270.01171 -139.076686) (xy 270.002077 -138.984396) (xy 270.001492 -138.938)
			(xy 270.002075 -138.891604) (xy 270.01172 -138.799316) (xy 270.030916 -138.708532) (xy 270.059454 -138.620239)
			(xy 270.077692 -138.577574) (xy 270.081498 -138.567632) (xy 270.081498 -138.546368) (xy 270.077692 -138.536426)
			(xy 270.059447 -138.493764) (xy 270.030903 -138.405471) (xy 270.01171 -138.314686) (xy 270.002077 -138.222396)
			(xy 270.001492 -138.176) (xy 270.002075 -138.129604) (xy 270.01172 -138.037316) (xy 270.030916 -137.946532)
			(xy 270.059454 -137.858239) (xy 270.077692 -137.815574) (xy 270.081498 -137.805632) (xy 270.081498 -137.784368)
			(xy 270.077692 -137.774426) (xy 270.059447 -137.731764) (xy 270.030903 -137.643471) (xy 270.01171 -137.552686)
			(xy 270.002077 -137.460396) (xy 270.001492 -137.414) (xy 270.002075 -137.367604) (xy 270.01172 -137.275316)
			(xy 270.030916 -137.184532) (xy 270.059454 -137.096239) (xy 270.077692 -137.053574) (xy 270.081498 -137.043632)
			(xy 270.081498 -137.022368) (xy 270.077692 -137.012426) (xy 270.059447 -136.969764) (xy 270.030903 -136.881471)
			(xy 270.01171 -136.790686) (xy 270.002077 -136.698396) (xy 270.001492 -136.652) (xy 270.001967 -136.610898)
			(xy 270.009552 -136.529043) (xy 270.024657 -136.448238) (xy 270.047153 -136.369171) (xy 270.076849 -136.292517)
			(xy 270.113491 -136.21893) (xy 270.156766 -136.149038) (xy 270.206306 -136.083437) (xy 270.261687 -136.022687)
			(xy 270.322437 -135.967306) (xy 270.388038 -135.917766) (xy 270.45793 -135.874491) (xy 270.531517 -135.837849)
			(xy 270.608171 -135.808153) (xy 270.687238 -135.785657) (xy 270.768043 -135.770552) (xy 270.849898 -135.762967)
			(xy 270.891 -135.762492) (xy 270.937396 -135.763075) (xy 271.029684 -135.77272) (xy 271.120468 -135.791916)
			(xy 271.208761 -135.820454) (xy 271.251426 -135.838692) (xy 271.261368 -135.842498) (xy 271.282632 -135.842498)
			(xy 271.292574 -135.838692) (xy 271.335236 -135.820447) (xy 271.423529 -135.791903) (xy 271.514314 -135.77271)
			(xy 271.606604 -135.763077) (xy 271.653 -135.762492) (xy 271.694102 -135.762967) (xy 271.775957 -135.770552)
			(xy 271.856762 -135.785657) (xy 271.935829 -135.808153) (xy 272.012483 -135.837849) (xy 272.08607 -135.874491)
			(xy 272.155962 -135.917766) (xy 272.221563 -135.967306) (xy 272.282313 -136.022687) (xy 272.337694 -136.083437)
			(xy 272.387234 -136.149038) (xy 272.430509 -136.21893) (xy 272.467151 -136.292517) (xy 272.496847 -136.369171)
			(xy 272.519343 -136.448238) (xy 272.534448 -136.529043) (xy 272.542033 -136.610898) (xy 272.542508 -136.652)
			(xy 272.541925 -136.698396) (xy 272.53228 -136.790684) (xy 272.513084 -136.881468) (xy 272.484546 -136.969761)
			(xy 272.466308 -137.012426) (xy 272.462502 -137.022368) (xy 272.462502 -137.043632) (xy 272.466308 -137.053574)
			(xy 272.484553 -137.096236) (xy 272.513097 -137.184529) (xy 272.53229 -137.275314) (xy 272.541923 -137.367604)
			(xy 272.542508 -137.414) (xy 272.541925 -137.460396) (xy 272.53228 -137.552684) (xy 272.513084 -137.643468)
			(xy 272.484546 -137.731761) (xy 272.466308 -137.774426) (xy 272.462502 -137.784368) (xy 272.462502 -137.805632)
			(xy 272.466308 -137.815574) (xy 272.484553 -137.858236) (xy 272.513097 -137.946529) (xy 272.53229 -138.037314)
			(xy 272.541923 -138.129604) (xy 272.542508 -138.176) (xy 272.541925 -138.222396) (xy 272.53228 -138.314684)
			(xy 272.513084 -138.405468) (xy 272.484546 -138.493761) (xy 272.466308 -138.536426) (xy 272.462502 -138.546368)
			(xy 272.462502 -138.567632) (xy 272.466308 -138.577574) (xy 272.484553 -138.620236) (xy 272.513097 -138.708529)
			(xy 272.53229 -138.799314) (xy 272.541923 -138.891604) (xy 272.542508 -138.938) (xy 272.541925 -138.984396)
			(xy 272.53228 -139.076684) (xy 272.513084 -139.167468) (xy 272.484546 -139.255761) (xy 272.466308 -139.298426)
			(xy 272.462502 -139.308368) (xy 272.462502 -139.329632) (xy 272.466308 -139.339574) (xy 272.484553 -139.382236)
			(xy 272.513097 -139.470529) (xy 272.53229 -139.561314) (xy 272.541923 -139.653604) (xy 272.542508 -139.7)
			(xy 272.541925 -139.746396) (xy 272.53228 -139.838684) (xy 272.513084 -139.929468) (xy 272.484546 -140.017761)
			(xy 272.466308 -140.060426) (xy 272.462502 -140.070368) (xy 272.462502 -140.091632) (xy 272.466308 -140.101574)
			(xy 272.484553 -140.144236) (xy 272.513097 -140.232529) (xy 272.53229 -140.323314) (xy 272.541923 -140.415604)
			(xy 272.542508 -140.462) (xy 272.542033 -140.503102) (xy 272.534448 -140.584957) (xy 272.519343 -140.665762)
			(xy 272.496847 -140.744829) (xy 272.467151 -140.821483) (xy 272.430509 -140.89507) (xy 272.387234 -140.964962)
			(xy 272.337694 -141.030563) (xy 272.282313 -141.091313) (xy 272.221563 -141.146694) (xy 272.155962 -141.196234)
			(xy 272.08607 -141.239509) (xy 272.012483 -141.276151) (xy 271.935829 -141.305847) (xy 271.856762 -141.328343)
			(xy 271.775957 -141.343448) (xy 271.694102 -141.351033) (xy 271.653 -141.351508) (xy 271.606604 -141.350925)
			(xy 271.514316 -141.34128) (xy 271.423532 -141.322084) (xy 271.335239 -141.293546) (xy 271.292574 -141.275308)
			(xy 271.282632 -141.271502) (xy 271.261368 -141.271502) (xy 271.251426 -141.275308) (xy 271.208764 -141.293553)
			(xy 271.120471 -141.322097) (xy 271.029686 -141.34129) (xy 270.937396 -141.350923) (xy 270.891 -141.351508)
			(xy 270.849898 -141.351033) (xy 270.768043 -141.343448) (xy 270.687238 -141.328343) (xy 270.608171 -141.305847)
			(xy 270.531517 -141.276151) (xy 270.45793 -141.239509) (xy 270.388038 -141.196234) (xy 270.322437 -141.146694)
			(xy 270.261687 -141.091313) (xy 270.206306 -141.030563) (xy 270.156766 -140.964962) (xy 270.113491 -140.89507)
			(xy 270.076849 -140.821483) (xy 270.047153 -140.744829) (xy 270.024657 -140.665762) (xy 270.009552 -140.584957)
			(xy 270.001967 -140.503102) (xy 270.001492 -140.462) (xy 224.422133 -140.462) (xy 224.479829 -140.52529)
			(xy 224.56079 -140.6259) (xy 224.635404 -140.731303) (xy 224.703387 -140.8411) (xy 224.764482 -140.954874)
			(xy 224.818457 -141.072193) (xy 224.865108 -141.192612) (xy 224.904257 -141.315675) (xy 224.935756 -141.440914)
			(xy 224.959485 -141.567855) (xy 224.975355 -141.696015) (xy 224.983305 -141.82491) (xy 224.983802 -141.88948)
			(xy 224.983305 -141.95405) (xy 224.975355 -142.082945) (xy 224.959485 -142.211105) (xy 224.935756 -142.338046)
			(xy 224.904257 -142.463285) (xy 224.865108 -142.586348) (xy 224.818457 -142.706767) (xy 224.764482 -142.824086)
			(xy 224.703387 -142.93786) (xy 224.635404 -143.047657) (xy 224.56079 -143.15306) (xy 224.479829 -143.25367)
			(xy 224.392829 -143.349105) (xy 224.300118 -143.439004) (xy 224.202048 -143.523025) (xy 224.098993 -143.600849)
			(xy 223.991342 -143.672181) (xy 223.879503 -143.736751) (xy 223.763902 -143.794313) (xy 223.644977 -143.84465)
			(xy 223.523178 -143.88757) (xy 223.398968 -143.922911) (xy 223.272819 -143.950538) (xy 223.145207 -143.970347)
			(xy 223.016618 -143.982263) (xy 222.88754 -143.98624) (xy 222.758462 -143.982263) (xy 222.629873 -143.970347)
			(xy 222.502261 -143.950538) (xy 222.376112 -143.922911) (xy 222.251902 -143.88757) (xy 222.130103 -143.84465)
			(xy 222.011178 -143.794313) (xy 221.895577 -143.736751) (xy 221.783738 -143.672181) (xy 221.676087 -143.600849)
			(xy 221.573032 -143.523025) (xy 221.474962 -143.439004) (xy 221.382251 -143.349105) (xy 221.295251 -143.25367)
			(xy 221.21429 -143.15306) (xy 221.139676 -143.047657) (xy 221.071693 -142.93786) (xy 221.010598 -142.824086)
			(xy 220.956623 -142.706767) (xy 220.909972 -142.586348) (xy 220.870823 -142.463285) (xy 220.839324 -142.338046)
			(xy 220.815595 -142.211105) (xy 220.799725 -142.082945) (xy 220.791775 -141.95405) (xy 0.509016 -141.95405)
			(xy 0.509016 -141.99997) (xy 0.509522 -142.095303) (xy 0.517614 -142.285798) (xy 0.533784 -142.475778)
			(xy 0.558002 -142.664901) (xy 0.590225 -142.852825) (xy 0.630394 -143.039212) (xy 0.678438 -143.223727)
			(xy 0.73427 -143.406036) (xy 0.797788 -143.585811) (xy 0.86888 -143.762729) (xy 0.947415 -143.93647)
			(xy 1.033254 -144.106721) (xy 1.126242 -144.273176) (xy 1.22621 -144.435534) (xy 1.332978 -144.593504)
			(xy 1.446355 -144.746799) (xy 1.566136 -144.895145) (xy 1.692104 -145.038273) (xy 1.824034 -145.175926)
			(xy 1.961687 -145.307856) (xy 2.104815 -145.433824) (xy 2.253161 -145.553605) (xy 2.406456 -145.666982)
			(xy 2.564426 -145.77375) (xy 2.726784 -145.873718) (xy 2.893239 -145.966706) (xy 3.06349 -146.052545)
			(xy 3.237231 -146.13108) (xy 3.414149 -146.202172) (xy 3.593924 -146.26569) (xy 3.776233 -146.321522)
			(xy 3.960748 -146.369566) (xy 4.147135 -146.409735) (xy 4.335059 -146.441958) (xy 4.524182 -146.466176)
			(xy 4.714162 -146.482346) (xy 4.904657 -146.490438) (xy 4.99999 -146.490944) (xy 266.33297 -146.490944)
			(xy 266.33297 -146.49196) (xy 266.666472 -146.49196)
		)
		(stroke
			(width 0)
			(type solid)
		)
		(fill yes)
		(layer "In3.Cu")
		(net "GND")
	)
	(gr_circle
		(center 9.85012 -76.019914)
		(end 11.22172 -76.019914)
		(stroke
			(width 0.2)
			(type default)
		)
		(fill no)
		(layer "In3.Cu")
	)
	(gr_circle
		(center 9.85012 -74.319892)
		(end 11.22172 -74.319892)
		(stroke
			(width 0.2)
			(type default)
		)
		(fill no)
		(layer "In3.Cu")
	)
	(gr_circle
		(center 9.85012 -70.939914)
		(end 11.22172 -70.939914)
		(stroke
			(width 0.2)
			(type default)
		)
		(fill no)
		(layer "In3.Cu")
	)
	(gr_circle
		(center 9.85012 -69.239892)
		(end 11.22172 -69.239892)
		(stroke
			(width 0.2)
			(type default)
		)
		(fill no)
		(layer "In3.Cu")
	)
	(gr_circle
		(center 11.147552 -75.158854)
		(end 12.519152 -75.158854)
		(stroke
			(width 0.2)
			(type default)
		)
		(fill no)
		(layer "In3.Cu")
	)
	(gr_circle
		(center 11.205464 -70.108572)
		(end 12.577064 -70.108572)
		(stroke
			(width 0.2)
			(type default)
		)
		(fill no)
		(layer "In3.Cu")
	)
	(gr_circle
		(center 12.39012 -76.019914)
		(end 13.76172 -76.019914)
		(stroke
			(width 0.2)
			(type default)
		)
		(fill no)
		(layer "In3.Cu")
	)
	(gr_circle
		(center 12.39012 -74.319892)
		(end 13.76172 -74.319892)
		(stroke
			(width 0.2)
			(type default)
		)
		(fill no)
		(layer "In3.Cu")
	)
	(gr_circle
		(center 12.39012 -70.939914)
		(end 13.76172 -70.939914)
		(stroke
			(width 0.2)
			(type default)
		)
		(fill no)
		(layer "In3.Cu")
	)
	(gr_circle
		(center 12.39012 -69.239892)
		(end 13.76172 -69.239892)
		(stroke
			(width 0.2)
			(type default)
		)
		(fill no)
		(layer "In3.Cu")
	)
	(gr_circle
		(center 27.5844 -66.43624)
		(end 28.4734 -66.43624)
		(stroke
			(width 0.2)
			(type default)
		)
		(fill no)
		(layer "In3.Cu")
	)
	(gr_circle
		(center 27.5844 -65.67424)
		(end 28.4734 -65.67424)
		(stroke
			(width 0.2)
			(type default)
		)
		(fill no)
		(layer "In3.Cu")
	)
	(gr_circle
		(center 27.5844 -64.91224)
		(end 28.4734 -64.91224)
		(stroke
			(width 0.2)
			(type default)
		)
		(fill no)
		(layer "In3.Cu")
	)
	(gr_circle
		(center 28.3464 -66.43624)
		(end 29.2354 -66.43624)
		(stroke
			(width 0.2)
			(type default)
		)
		(fill no)
		(layer "In3.Cu")
	)
	(gr_circle
		(center 28.3464 -65.67424)
		(end 29.2354 -65.67424)
		(stroke
			(width 0.2)
			(type default)
		)
		(fill no)
		(layer "In3.Cu")
	)
	(gr_circle
		(center 28.3464 -64.91224)
		(end 29.2354 -64.91224)
		(stroke
			(width 0.2)
			(type default)
		)
		(fill no)
		(layer "In3.Cu")
	)
	(gr_circle
		(center 29.3878 -108.3818)
		(end 30.2768 -108.3818)
		(stroke
			(width 0.2)
			(type default)
		)
		(fill no)
		(layer "In3.Cu")
	)
	(gr_circle
		(center 29.3878 -107.6198)
		(end 30.2768 -107.6198)
		(stroke
			(width 0.2)
			(type default)
		)
		(fill no)
		(layer "In3.Cu")
	)
	(gr_circle
		(center 29.3878 -106.8324)
		(end 30.2768 -106.8324)
		(stroke
			(width 0.2)
			(type default)
		)
		(fill no)
		(layer "In3.Cu")
	)
	(gr_circle
		(center 29.3878 -106.0704)
		(end 30.2768 -106.0704)
		(stroke
			(width 0.2)
			(type default)
		)
		(fill no)
		(layer "In3.Cu")
	)
	(gr_circle
		(center 29.3878 -105.3084)
		(end 30.2768 -105.3084)
		(stroke
			(width 0.2)
			(type default)
		)
		(fill no)
		(layer "In3.Cu")
	)
	(gr_circle
		(center 29.3878 -104.5464)
		(end 30.2768 -104.5464)
		(stroke
			(width 0.2)
			(type default)
		)
		(fill no)
		(layer "In3.Cu")
	)
	(gr_circle
		(center 29.3878 -103.7844)
		(end 30.2768 -103.7844)
		(stroke
			(width 0.2)
			(type default)
		)
		(fill no)
		(layer "In3.Cu")
	)
	(gr_circle
		(center 30.353 -108.3564)
		(end 31.242 -108.3564)
		(stroke
			(width 0.2)
			(type default)
		)
		(fill no)
		(layer "In3.Cu")
	)
	(gr_circle
		(center 30.353 -107.5944)
		(end 31.242 -107.5944)
		(stroke
			(width 0.2)
			(type default)
		)
		(fill no)
		(layer "In3.Cu")
	)
	(gr_circle
		(center 30.353 -106.807)
		(end 31.242 -106.807)
		(stroke
			(width 0.2)
			(type default)
		)
		(fill no)
		(layer "In3.Cu")
	)
	(gr_circle
		(center 30.353 -106.045)
		(end 31.242 -106.045)
		(stroke
			(width 0.2)
			(type default)
		)
		(fill no)
		(layer "In3.Cu")
	)
	(gr_circle
		(center 30.353 -105.283)
		(end 31.242 -105.283)
		(stroke
			(width 0.2)
			(type default)
		)
		(fill no)
		(layer "In3.Cu")
	)
	(gr_circle
		(center 30.353 -104.521)
		(end 31.242 -104.521)
		(stroke
			(width 0.2)
			(type default)
		)
		(fill no)
		(layer "In3.Cu")
	)
	(gr_circle
		(center 30.353 -103.759)
		(end 31.242 -103.759)
		(stroke
			(width 0.2)
			(type default)
		)
		(fill no)
		(layer "In3.Cu")
	)
	(gr_circle
		(center 31.242 -108.3564)
		(end 32.131 -108.3564)
		(stroke
			(width 0.2)
			(type default)
		)
		(fill no)
		(layer "In3.Cu")
	)
	(gr_circle
		(center 31.242 -107.5944)
		(end 32.131 -107.5944)
		(stroke
			(width 0.2)
			(type default)
		)
		(fill no)
		(layer "In3.Cu")
	)
	(gr_circle
		(center 31.242 -106.807)
		(end 32.131 -106.807)
		(stroke
			(width 0.2)
			(type default)
		)
		(fill no)
		(layer "In3.Cu")
	)
	(gr_circle
		(center 31.242 -106.045)
		(end 32.131 -106.045)
		(stroke
			(width 0.2)
			(type default)
		)
		(fill no)
		(layer "In3.Cu")
	)
	(gr_circle
		(center 31.242 -105.283)
		(end 32.131 -105.283)
		(stroke
			(width 0.2)
			(type default)
		)
		(fill no)
		(layer "In3.Cu")
	)
	(gr_circle
		(center 31.242 -104.521)
		(end 32.131 -104.521)
		(stroke
			(width 0.2)
			(type default)
		)
		(fill no)
		(layer "In3.Cu")
	)
	(gr_circle
		(center 31.242 -103.759)
		(end 32.131 -103.759)
		(stroke
			(width 0.2)
			(type default)
		)
		(fill no)
		(layer "In3.Cu")
	)
	(gr_circle
		(center 38.261036 -55.642002)
		(end 39.150036 -55.642002)
		(stroke
			(width 0.2)
			(type default)
		)
		(fill no)
		(layer "In3.Cu")
	)
	(gr_circle
		(center 38.692836 -58.436002)
		(end 39.581836 -58.436002)
		(stroke
			(width 0.2)
			(type default)
		)
		(fill no)
		(layer "In3.Cu")
	)
	(gr_circle
		(center 38.692836 -57.547002)
		(end 39.581836 -57.547002)
		(stroke
			(width 0.2)
			(type default)
		)
		(fill no)
		(layer "In3.Cu")
	)
	(gr_circle
		(center 38.692836 -56.658002)
		(end 39.581836 -56.658002)
		(stroke
			(width 0.2)
			(type default)
		)
		(fill no)
		(layer "In3.Cu")
	)
	(gr_circle
		(center 39.378636 -58.817002)
		(end 40.267636 -58.817002)
		(stroke
			(width 0.2)
			(type default)
		)
		(fill no)
		(layer "In3.Cu")
	)
	(gr_circle
		(center 39.378636 -57.928002)
		(end 40.267636 -57.928002)
		(stroke
			(width 0.2)
			(type default)
		)
		(fill no)
		(layer "In3.Cu")
	)
	(gr_circle
		(center 39.378636 -57.039002)
		(end 40.267636 -57.039002)
		(stroke
			(width 0.2)
			(type default)
		)
		(fill no)
		(layer "In3.Cu")
	)
	(gr_circle
		(center 39.8272 -108.3564)
		(end 40.7162 -108.3564)
		(stroke
			(width 0.2)
			(type default)
		)
		(fill no)
		(layer "In3.Cu")
	)
	(gr_circle
		(center 39.8272 -107.5944)
		(end 40.7162 -107.5944)
		(stroke
			(width 0.2)
			(type default)
		)
		(fill no)
		(layer "In3.Cu")
	)
	(gr_circle
		(center 39.878 -106.807)
		(end 40.767 -106.807)
		(stroke
			(width 0.2)
			(type default)
		)
		(fill no)
		(layer "In3.Cu")
	)
	(gr_circle
		(center 39.878 -106.045)
		(end 40.767 -106.045)
		(stroke
			(width 0.2)
			(type default)
		)
		(fill no)
		(layer "In3.Cu")
	)
	(gr_circle
		(center 39.878 -105.283)
		(end 40.767 -105.283)
		(stroke
			(width 0.2)
			(type default)
		)
		(fill no)
		(layer "In3.Cu")
	)
	(gr_circle
		(center 39.878 -104.521)
		(end 40.767 -104.521)
		(stroke
			(width 0.2)
			(type default)
		)
		(fill no)
		(layer "In3.Cu")
	)
	(gr_circle
		(center 39.878 -103.759)
		(end 40.767 -103.759)
		(stroke
			(width 0.2)
			(type default)
		)
		(fill no)
		(layer "In3.Cu")
	)
	(gr_circle
		(center 40.7162 -108.3564)
		(end 41.6052 -108.3564)
		(stroke
			(width 0.2)
			(type default)
		)
		(fill no)
		(layer "In3.Cu")
	)
	(gr_circle
		(center 40.767 -106.807)
		(end 41.656 -106.807)
		(stroke
			(width 0.2)
			(type default)
		)
		(fill no)
		(layer "In3.Cu")
	)
	(gr_circle
		(center 40.767 -106.045)
		(end 41.656 -106.045)
		(stroke
			(width 0.2)
			(type default)
		)
		(fill no)
		(layer "In3.Cu")
	)
	(gr_circle
		(center 40.767 -105.283)
		(end 41.656 -105.283)
		(stroke
			(width 0.2)
			(type default)
		)
		(fill no)
		(layer "In3.Cu")
	)
	(gr_circle
		(center 40.767 -104.521)
		(end 41.656 -104.521)
		(stroke
			(width 0.2)
			(type default)
		)
		(fill no)
		(layer "In3.Cu")
	)
	(gr_circle
		(center 40.767 -103.759)
		(end 41.656 -103.759)
		(stroke
			(width 0.2)
			(type default)
		)
		(fill no)
		(layer "In3.Cu")
	)
	(gr_circle
		(center 41.3639 -58.604912)
		(end 42.2529 -58.604912)
		(stroke
			(width 0.2)
			(type default)
		)
		(fill no)
		(layer "In3.Cu")
	)
	(gr_circle
		(center 41.3639 -57.70499)
		(end 42.2529 -57.70499)
		(stroke
			(width 0.2)
			(type default)
		)
		(fill no)
		(layer "In3.Cu")
	)
	(gr_circle
		(center 41.3639 -56.805068)
		(end 42.2529 -56.805068)
		(stroke
			(width 0.2)
			(type default)
		)
		(fill no)
		(layer "In3.Cu")
	)
	(gr_circle
		(center 41.3639 -55.904892)
		(end 42.2529 -55.904892)
		(stroke
			(width 0.2)
			(type default)
		)
		(fill no)
		(layer "In3.Cu")
	)
	(gr_circle
		(center 41.6052 -108.3818)
		(end 42.4942 -108.3818)
		(stroke
			(width 0.2)
			(type default)
		)
		(fill no)
		(layer "In3.Cu")
	)
	(gr_circle
		(center 41.6052 -107.6198)
		(end 42.4942 -107.6198)
		(stroke
			(width 0.2)
			(type default)
		)
		(fill no)
		(layer "In3.Cu")
	)
	(gr_circle
		(center 41.656 -106.8324)
		(end 42.545 -106.8324)
		(stroke
			(width 0.2)
			(type default)
		)
		(fill no)
		(layer "In3.Cu")
	)
	(gr_circle
		(center 41.656 -106.0704)
		(end 42.545 -106.0704)
		(stroke
			(width 0.2)
			(type default)
		)
		(fill no)
		(layer "In3.Cu")
	)
	(gr_circle
		(center 41.656 -105.3084)
		(end 42.545 -105.3084)
		(stroke
			(width 0.2)
			(type default)
		)
		(fill no)
		(layer "In3.Cu")
	)
	(gr_circle
		(center 41.656 -104.5464)
		(end 42.545 -104.5464)
		(stroke
			(width 0.2)
			(type default)
		)
		(fill no)
		(layer "In3.Cu")
	)
	(gr_circle
		(center 41.656 -103.7844)
		(end 42.545 -103.7844)
		(stroke
			(width 0.2)
			(type default)
		)
		(fill no)
		(layer "In3.Cu")
	)
	(gr_circle
		(center 41.84904 -54.1147)
		(end 42.73804 -54.1147)
		(stroke
			(width 0.2)
			(type default)
		)
		(fill no)
		(layer "In3.Cu")
	)
	(gr_circle
		(center 41.84904 -53.3019)
		(end 42.73804 -53.3019)
		(stroke
			(width 0.2)
			(type default)
		)
		(fill no)
		(layer "In3.Cu")
	)
	(gr_circle
		(center 41.9989 -58.604912)
		(end 42.8879 -58.604912)
		(stroke
			(width 0.2)
			(type default)
		)
		(fill no)
		(layer "In3.Cu")
	)
	(gr_circle
		(center 41.9989 -57.70499)
		(end 42.8879 -57.70499)
		(stroke
			(width 0.2)
			(type default)
		)
		(fill no)
		(layer "In3.Cu")
	)
	(gr_circle
		(center 41.9989 -56.805068)
		(end 42.8879 -56.805068)
		(stroke
			(width 0.2)
			(type default)
		)
		(fill no)
		(layer "In3.Cu")
	)
	(gr_circle
		(center 41.9989 -55.904892)
		(end 42.8879 -55.904892)
		(stroke
			(width 0.2)
			(type default)
		)
		(fill no)
		(layer "In3.Cu")
	)
	(gr_circle
		(center 42.046906 -136.906)
		(end 43.469306 -136.906)
		(stroke
			(width 0.2)
			(type default)
		)
		(fill no)
		(layer "In3.Cu")
	)
	(gr_circle
		(center 42.58564 -54.1147)
		(end 43.47464 -54.1147)
		(stroke
			(width 0.2)
			(type default)
		)
		(fill no)
		(layer "In3.Cu")
	)
	(gr_circle
		(center 42.58564 -53.3019)
		(end 43.47464 -53.3019)
		(stroke
			(width 0.2)
			(type default)
		)
		(fill no)
		(layer "In3.Cu")
	)
	(gr_circle
		(center 42.910506 -131.572)
		(end 43.799506 -131.572)
		(stroke
			(width 0.2)
			(type default)
		)
		(fill no)
		(layer "In3.Cu")
	)
	(gr_circle
		(center 42.910506 -126.492)
		(end 43.799506 -126.492)
		(stroke
			(width 0.2)
			(type default)
		)
		(fill no)
		(layer "In3.Cu")
	)
	(gr_circle
		(center 43.672506 -131.572)
		(end 44.561506 -131.572)
		(stroke
			(width 0.2)
			(type default)
		)
		(fill no)
		(layer "In3.Cu")
	)
	(gr_circle
		(center 43.672506 -126.492)
		(end 44.561506 -126.492)
		(stroke
			(width 0.2)
			(type default)
		)
		(fill no)
		(layer "In3.Cu")
	)
	(gr_circle
		(center 44.36364 -52.2859)
		(end 45.25264 -52.2859)
		(stroke
			(width 0.2)
			(type default)
		)
		(fill no)
		(layer "In3.Cu")
	)
	(gr_circle
		(center 44.36364 -51.4731)
		(end 45.25264 -51.4731)
		(stroke
			(width 0.2)
			(type default)
		)
		(fill no)
		(layer "In3.Cu")
	)
	(gr_circle
		(center 44.84624 -50.0507)
		(end 45.73524 -50.0507)
		(stroke
			(width 0.2)
			(type default)
		)
		(fill no)
		(layer "In3.Cu")
	)
	(gr_circle
		(center 45.58284 -50.0507)
		(end 46.47184 -50.0507)
		(stroke
			(width 0.2)
			(type default)
		)
		(fill no)
		(layer "In3.Cu")
	)
	(gr_circle
		(center 46.29404 -50.0507)
		(end 47.18304 -50.0507)
		(stroke
			(width 0.2)
			(type default)
		)
		(fill no)
		(layer "In3.Cu")
	)
	(gr_circle
		(center 47.05604 -52.9209)
		(end 47.94504 -52.9209)
		(stroke
			(width 0.2)
			(type default)
		)
		(fill no)
		(layer "In3.Cu")
	)
	(gr_circle
		(center 47.05604 -52.1589)
		(end 47.94504 -52.1589)
		(stroke
			(width 0.2)
			(type default)
		)
		(fill no)
		(layer "In3.Cu")
	)
	(gr_circle
		(center 49.31664 -52.8828)
		(end 50.20564 -52.8828)
		(stroke
			(width 0.2)
			(type default)
		)
		(fill no)
		(layer "In3.Cu")
	)
	(gr_circle
		(center 49.31664 -52.1208)
		(end 50.20564 -52.1208)
		(stroke
			(width 0.2)
			(type default)
		)
		(fill no)
		(layer "In3.Cu")
	)
	(gr_circle
		(center 50.07864 -52.8828)
		(end 50.96764 -52.8828)
		(stroke
			(width 0.2)
			(type default)
		)
		(fill no)
		(layer "In3.Cu")
	)
	(gr_circle
		(center 50.07864 -52.1208)
		(end 50.96764 -52.1208)
		(stroke
			(width 0.2)
			(type default)
		)
		(fill no)
		(layer "In3.Cu")
	)
	(gr_circle
		(center 50.84064 -52.8828)
		(end 51.72964 -52.8828)
		(stroke
			(width 0.2)
			(type default)
		)
		(fill no)
		(layer "In3.Cu")
	)
	(gr_circle
		(center 50.84064 -52.1208)
		(end 51.72964 -52.1208)
		(stroke
			(width 0.2)
			(type default)
		)
		(fill no)
		(layer "In3.Cu")
	)
	(gr_circle
		(center 54.238906 -136.906)
		(end 55.661306 -136.906)
		(stroke
			(width 0.2)
			(type default)
		)
		(fill no)
		(layer "In3.Cu")
	)
	(gr_circle
		(center 55.102506 -131.572)
		(end 55.991506 -131.572)
		(stroke
			(width 0.2)
			(type default)
		)
		(fill no)
		(layer "In3.Cu")
	)
	(gr_circle
		(center 55.102506 -126.492)
		(end 55.991506 -126.492)
		(stroke
			(width 0.2)
			(type default)
		)
		(fill no)
		(layer "In3.Cu")
	)
	(gr_circle
		(center 55.864506 -131.572)
		(end 56.753506 -131.572)
		(stroke
			(width 0.2)
			(type default)
		)
		(fill no)
		(layer "In3.Cu")
	)
	(gr_circle
		(center 55.864506 -126.492)
		(end 56.753506 -126.492)
		(stroke
			(width 0.2)
			(type default)
		)
		(fill no)
		(layer "In3.Cu")
	)
	(gr_circle
		(center 62.850014 -77.71765)
		(end 63.739014 -77.71765)
		(stroke
			(width 0.2)
			(type default)
		)
		(fill no)
		(layer "In3.Cu")
	)
	(gr_circle
		(center 64.470026 -121.209816)
		(end 66.286126 -121.209816)
		(stroke
			(width 0.2)
			(type default)
		)
		(fill no)
		(layer "In3.Cu")
	)
	(gr_circle
		(center 64.470026 -70.409816)
		(end 66.667126 -70.409816)
		(stroke
			(width 0.2)
			(type default)
		)
		(fill no)
		(layer "In3.Cu")
	)
	(gr_circle
		(center 66.430906 -136.906)
		(end 67.853306 -136.906)
		(stroke
			(width 0.2)
			(type default)
		)
		(fill no)
		(layer "In3.Cu")
	)
	(gr_circle
		(center 67.294506 -131.572)
		(end 68.183506 -131.572)
		(stroke
			(width 0.2)
			(type default)
		)
		(fill no)
		(layer "In3.Cu")
	)
	(gr_circle
		(center 67.294506 -126.492)
		(end 68.183506 -126.492)
		(stroke
			(width 0.2)
			(type default)
		)
		(fill no)
		(layer "In3.Cu")
	)
	(gr_circle
		(center 68.056506 -131.572)
		(end 68.945506 -131.572)
		(stroke
			(width 0.2)
			(type default)
		)
		(fill no)
		(layer "In3.Cu")
	)
	(gr_circle
		(center 68.056506 -126.492)
		(end 68.945506 -126.492)
		(stroke
			(width 0.2)
			(type default)
		)
		(fill no)
		(layer "In3.Cu")
	)
	(gr_circle
		(center 68.072 -60.96)
		(end 69.469 -60.96)
		(stroke
			(width 0.2)
			(type default)
		)
		(fill no)
		(layer "In3.Cu")
	)
	(gr_circle
		(center 68.280026 -70.409816)
		(end 70.477126 -70.409816)
		(stroke
			(width 0.2)
			(type default)
		)
		(fill no)
		(layer "In3.Cu")
	)
	(gr_circle
		(center 70.413626 -71.901812)
		(end 71.302626 -71.901812)
		(stroke
			(width 0.2)
			(type default)
		)
		(fill no)
		(layer "In3.Cu")
	)
	(gr_circle
		(center 70.413626 -70.885812)
		(end 71.302626 -70.885812)
		(stroke
			(width 0.2)
			(type default)
		)
		(fill no)
		(layer "In3.Cu")
	)
	(gr_circle
		(center 70.413626 -69.869812)
		(end 71.302626 -69.869812)
		(stroke
			(width 0.2)
			(type default)
		)
		(fill no)
		(layer "In3.Cu")
	)
	(gr_circle
		(center 70.413626 -68.853812)
		(end 71.302626 -68.853812)
		(stroke
			(width 0.2)
			(type default)
		)
		(fill no)
		(layer "In3.Cu")
	)
	(gr_circle
		(center 71.429626 -71.901812)
		(end 72.318626 -71.901812)
		(stroke
			(width 0.2)
			(type default)
		)
		(fill no)
		(layer "In3.Cu")
	)
	(gr_circle
		(center 71.429626 -70.885812)
		(end 72.318626 -70.885812)
		(stroke
			(width 0.2)
			(type default)
		)
		(fill no)
		(layer "In3.Cu")
	)
	(gr_circle
		(center 71.429626 -69.869812)
		(end 72.318626 -69.869812)
		(stroke
			(width 0.2)
			(type default)
		)
		(fill no)
		(layer "In3.Cu")
	)
	(gr_circle
		(center 71.429626 -68.853812)
		(end 72.318626 -68.853812)
		(stroke
			(width 0.2)
			(type default)
		)
		(fill no)
		(layer "In3.Cu")
	)
	(gr_circle
		(center 71.882 -52.324)
		(end 72.771 -52.324)
		(stroke
			(width 0.2)
			(type default)
		)
		(fill no)
		(layer "In3.Cu")
	)
	(gr_circle
		(center 71.882 -51.689)
		(end 72.771 -51.689)
		(stroke
			(width 0.2)
			(type default)
		)
		(fill no)
		(layer "In3.Cu")
	)
	(gr_circle
		(center 71.882 -50.419)
		(end 72.771 -50.419)
		(stroke
			(width 0.2)
			(type default)
		)
		(fill no)
		(layer "In3.Cu")
	)
	(gr_circle
		(center 71.882 -49.784)
		(end 72.771 -49.784)
		(stroke
			(width 0.2)
			(type default)
		)
		(fill no)
		(layer "In3.Cu")
	)
	(gr_circle
		(center 72.445626 -71.901812)
		(end 73.334626 -71.901812)
		(stroke
			(width 0.2)
			(type default)
		)
		(fill no)
		(layer "In3.Cu")
	)
	(gr_circle
		(center 72.445626 -70.885812)
		(end 73.334626 -70.885812)
		(stroke
			(width 0.2)
			(type default)
		)
		(fill no)
		(layer "In3.Cu")
	)
	(gr_circle
		(center 72.445626 -69.869812)
		(end 73.334626 -69.869812)
		(stroke
			(width 0.2)
			(type default)
		)
		(fill no)
		(layer "In3.Cu")
	)
	(gr_circle
		(center 72.445626 -68.853812)
		(end 73.334626 -68.853812)
		(stroke
			(width 0.2)
			(type default)
		)
		(fill no)
		(layer "In3.Cu")
	)
	(gr_circle
		(center 77.343 -52.324)
		(end 78.232 -52.324)
		(stroke
			(width 0.2)
			(type default)
		)
		(fill no)
		(layer "In3.Cu")
	)
	(gr_circle
		(center 77.343 -51.689)
		(end 78.232 -51.689)
		(stroke
			(width 0.2)
			(type default)
		)
		(fill no)
		(layer "In3.Cu")
	)
	(gr_circle
		(center 77.343 -50.419)
		(end 78.232 -50.419)
		(stroke
			(width 0.2)
			(type default)
		)
		(fill no)
		(layer "In3.Cu")
	)
	(gr_circle
		(center 77.343 -49.784)
		(end 78.232 -49.784)
		(stroke
			(width 0.2)
			(type default)
		)
		(fill no)
		(layer "In3.Cu")
	)
	(gr_circle
		(center 79.375 -60.96)
		(end 80.772 -60.96)
		(stroke
			(width 0.2)
			(type default)
		)
		(fill no)
		(layer "In3.Cu")
	)
	(gr_circle
		(center 82.046826 -136.906)
		(end 83.469226 -136.906)
		(stroke
			(width 0.2)
			(type default)
		)
		(fill no)
		(layer "In3.Cu")
	)
	(gr_circle
		(center 82.804 -52.324)
		(end 83.693 -52.324)
		(stroke
			(width 0.2)
			(type default)
		)
		(fill no)
		(layer "In3.Cu")
	)
	(gr_circle
		(center 82.804 -51.689)
		(end 83.693 -51.689)
		(stroke
			(width 0.2)
			(type default)
		)
		(fill no)
		(layer "In3.Cu")
	)
	(gr_circle
		(center 82.804 -50.419)
		(end 83.693 -50.419)
		(stroke
			(width 0.2)
			(type default)
		)
		(fill no)
		(layer "In3.Cu")
	)
	(gr_circle
		(center 82.804 -49.784)
		(end 83.693 -49.784)
		(stroke
			(width 0.2)
			(type default)
		)
		(fill no)
		(layer "In3.Cu")
	)
	(gr_circle
		(center 82.910426 -131.572)
		(end 83.799426 -131.572)
		(stroke
			(width 0.2)
			(type default)
		)
		(fill no)
		(layer "In3.Cu")
	)
	(gr_circle
		(center 82.910426 -126.492)
		(end 83.799426 -126.492)
		(stroke
			(width 0.2)
			(type default)
		)
		(fill no)
		(layer "In3.Cu")
	)
	(gr_circle
		(center 83.672426 -131.572)
		(end 84.561426 -131.572)
		(stroke
			(width 0.2)
			(type default)
		)
		(fill no)
		(layer "In3.Cu")
	)
	(gr_circle
		(center 83.672426 -126.492)
		(end 84.561426 -126.492)
		(stroke
			(width 0.2)
			(type default)
		)
		(fill no)
		(layer "In3.Cu")
	)
	(gr_circle
		(center 88.265 -52.324)
		(end 89.154 -52.324)
		(stroke
			(width 0.2)
			(type default)
		)
		(fill no)
		(layer "In3.Cu")
	)
	(gr_circle
		(center 88.265 -51.689)
		(end 89.154 -51.689)
		(stroke
			(width 0.2)
			(type default)
		)
		(fill no)
		(layer "In3.Cu")
	)
	(gr_circle
		(center 88.265 -50.419)
		(end 89.154 -50.419)
		(stroke
			(width 0.2)
			(type default)
		)
		(fill no)
		(layer "In3.Cu")
	)
	(gr_circle
		(center 88.265 -49.784)
		(end 89.154 -49.784)
		(stroke
			(width 0.2)
			(type default)
		)
		(fill no)
		(layer "In3.Cu")
	)
	(gr_circle
		(center 90.678 -60.96)
		(end 92.075 -60.96)
		(stroke
			(width 0.2)
			(type default)
		)
		(fill no)
		(layer "In3.Cu")
	)
	(gr_circle
		(center 93.726 -52.324)
		(end 94.615 -52.324)
		(stroke
			(width 0.2)
			(type default)
		)
		(fill no)
		(layer "In3.Cu")
	)
	(gr_circle
		(center 93.726 -51.689)
		(end 94.615 -51.689)
		(stroke
			(width 0.2)
			(type default)
		)
		(fill no)
		(layer "In3.Cu")
	)
	(gr_circle
		(center 93.726 -50.419)
		(end 94.615 -50.419)
		(stroke
			(width 0.2)
			(type default)
		)
		(fill no)
		(layer "In3.Cu")
	)
	(gr_circle
		(center 93.726 -49.784)
		(end 94.615 -49.784)
		(stroke
			(width 0.2)
			(type default)
		)
		(fill no)
		(layer "In3.Cu")
	)
	(gr_circle
		(center 94.238826 -136.906)
		(end 95.661226 -136.906)
		(stroke
			(width 0.2)
			(type default)
		)
		(fill no)
		(layer "In3.Cu")
	)
	(gr_circle
		(center 95.102426 -131.572)
		(end 95.991426 -131.572)
		(stroke
			(width 0.2)
			(type default)
		)
		(fill no)
		(layer "In3.Cu")
	)
	(gr_circle
		(center 95.102426 -126.492)
		(end 95.991426 -126.492)
		(stroke
			(width 0.2)
			(type default)
		)
		(fill no)
		(layer "In3.Cu")
	)
	(gr_circle
		(center 95.864426 -131.572)
		(end 96.753426 -131.572)
		(stroke
			(width 0.2)
			(type default)
		)
		(fill no)
		(layer "In3.Cu")
	)
	(gr_circle
		(center 95.864426 -126.492)
		(end 96.753426 -126.492)
		(stroke
			(width 0.2)
			(type default)
		)
		(fill no)
		(layer "In3.Cu")
	)
	(gr_circle
		(center 99.187 -52.324)
		(end 100.076 -52.324)
		(stroke
			(width 0.2)
			(type default)
		)
		(fill no)
		(layer "In3.Cu")
	)
	(gr_circle
		(center 99.187 -51.689)
		(end 100.076 -51.689)
		(stroke
			(width 0.2)
			(type default)
		)
		(fill no)
		(layer "In3.Cu")
	)
	(gr_circle
		(center 99.187 -50.419)
		(end 100.076 -50.419)
		(stroke
			(width 0.2)
			(type default)
		)
		(fill no)
		(layer "In3.Cu")
	)
	(gr_circle
		(center 99.187 -49.784)
		(end 100.076 -49.784)
		(stroke
			(width 0.2)
			(type default)
		)
		(fill no)
		(layer "In3.Cu")
	)
	(gr_circle
		(center 102.045008 -40.55999)
		(end 103.44404 -40.55999)
		(stroke
			(width 0.2)
			(type default)
		)
		(fill no)
		(layer "In3.Cu")
	)
	(gr_circle
		(center 102.045008 -38.01999)
		(end 103.44404 -38.01999)
		(stroke
			(width 0.2)
			(type default)
		)
		(fill no)
		(layer "In3.Cu")
	)
	(gr_circle
		(center 102.045008 -35.47999)
		(end 103.44404 -35.47999)
		(stroke
			(width 0.2)
			(type default)
		)
		(fill no)
		(layer "In3.Cu")
	)
	(gr_circle
		(center 102.045008 -32.93999)
		(end 103.44404 -32.93999)
		(stroke
			(width 0.2)
			(type default)
		)
		(fill no)
		(layer "In3.Cu")
	)
	(gr_circle
		(center 102.849934 -77.71765)
		(end 103.738934 -77.71765)
		(stroke
			(width 0.2)
			(type default)
		)
		(fill no)
		(layer "In3.Cu")
	)
	(gr_circle
		(center 102.934008 -39.41699)
		(end 104.33304 -39.41699)
		(stroke
			(width 0.2)
			(type default)
		)
		(fill no)
		(layer "In3.Cu")
	)
	(gr_circle
		(center 103.188008 -34.20999)
		(end 104.58704 -34.20999)
		(stroke
			(width 0.2)
			(type default)
		)
		(fill no)
		(layer "In3.Cu")
	)
	(gr_circle
		(center 103.315008 -36.74999)
		(end 104.71404 -36.74999)
		(stroke
			(width 0.2)
			(type default)
		)
		(fill no)
		(layer "In3.Cu")
	)
	(gr_circle
		(center 104.469946 -121.209816)
		(end 106.286046 -121.209816)
		(stroke
			(width 0.2)
			(type default)
		)
		(fill no)
		(layer "In3.Cu")
	)
	(gr_circle
		(center 104.469946 -70.409816)
		(end 106.667046 -70.409816)
		(stroke
			(width 0.2)
			(type default)
		)
		(fill no)
		(layer "In3.Cu")
	)
	(gr_circle
		(center 104.585008 -40.55999)
		(end 105.98404 -40.55999)
		(stroke
			(width 0.2)
			(type default)
		)
		(fill no)
		(layer "In3.Cu")
	)
	(gr_circle
		(center 104.585008 -38.01999)
		(end 105.98404 -38.01999)
		(stroke
			(width 0.2)
			(type default)
		)
		(fill no)
		(layer "In3.Cu")
	)
	(gr_circle
		(center 104.585008 -35.47999)
		(end 105.98404 -35.47999)
		(stroke
			(width 0.2)
			(type default)
		)
		(fill no)
		(layer "In3.Cu")
	)
	(gr_circle
		(center 104.585008 -32.93999)
		(end 105.98404 -32.93999)
		(stroke
			(width 0.2)
			(type default)
		)
		(fill no)
		(layer "In3.Cu")
	)
	(gr_circle
		(center 104.648 -52.324)
		(end 105.537 -52.324)
		(stroke
			(width 0.2)
			(type default)
		)
		(fill no)
		(layer "In3.Cu")
	)
	(gr_circle
		(center 104.648 -51.689)
		(end 105.537 -51.689)
		(stroke
			(width 0.2)
			(type default)
		)
		(fill no)
		(layer "In3.Cu")
	)
	(gr_circle
		(center 104.648 -50.419)
		(end 105.537 -50.419)
		(stroke
			(width 0.2)
			(type default)
		)
		(fill no)
		(layer "In3.Cu")
	)
	(gr_circle
		(center 104.648 -49.784)
		(end 105.537 -49.784)
		(stroke
			(width 0.2)
			(type default)
		)
		(fill no)
		(layer "In3.Cu")
	)
	(gr_circle
		(center 106.430826 -136.906)
		(end 107.853226 -136.906)
		(stroke
			(width 0.2)
			(type default)
		)
		(fill no)
		(layer "In3.Cu")
	)
	(gr_circle
		(center 107.294426 -131.572)
		(end 108.183426 -131.572)
		(stroke
			(width 0.2)
			(type default)
		)
		(fill no)
		(layer "In3.Cu")
	)
	(gr_circle
		(center 107.294426 -126.492)
		(end 108.183426 -126.492)
		(stroke
			(width 0.2)
			(type default)
		)
		(fill no)
		(layer "In3.Cu")
	)
	(gr_circle
		(center 108.056426 -131.572)
		(end 108.945426 -131.572)
		(stroke
			(width 0.2)
			(type default)
		)
		(fill no)
		(layer "In3.Cu")
	)
	(gr_circle
		(center 108.056426 -126.492)
		(end 108.945426 -126.492)
		(stroke
			(width 0.2)
			(type default)
		)
		(fill no)
		(layer "In3.Cu")
	)
	(gr_circle
		(center 108.279946 -70.409816)
		(end 110.477046 -70.409816)
		(stroke
			(width 0.2)
			(type default)
		)
		(fill no)
		(layer "In3.Cu")
	)
	(gr_circle
		(center 108.839 -60.96)
		(end 110.236 -60.96)
		(stroke
			(width 0.2)
			(type default)
		)
		(fill no)
		(layer "In3.Cu")
	)
	(gr_circle
		(center 110.362746 -71.929244)
		(end 111.251746 -71.929244)
		(stroke
			(width 0.2)
			(type default)
		)
		(fill no)
		(layer "In3.Cu")
	)
	(gr_circle
		(center 110.362746 -70.913244)
		(end 111.251746 -70.913244)
		(stroke
			(width 0.2)
			(type default)
		)
		(fill no)
		(layer "In3.Cu")
	)
	(gr_circle
		(center 110.362746 -69.897244)
		(end 111.251746 -69.897244)
		(stroke
			(width 0.2)
			(type default)
		)
		(fill no)
		(layer "In3.Cu")
	)
	(gr_circle
		(center 110.362746 -68.881244)
		(end 111.251746 -68.881244)
		(stroke
			(width 0.2)
			(type default)
		)
		(fill no)
		(layer "In3.Cu")
	)
	(gr_circle
		(center 110.935008 -40.55999)
		(end 112.33404 -40.55999)
		(stroke
			(width 0.2)
			(type default)
		)
		(fill no)
		(layer "In3.Cu")
	)
	(gr_circle
		(center 110.935008 -38.01999)
		(end 112.33404 -38.01999)
		(stroke
			(width 0.2)
			(type default)
		)
		(fill no)
		(layer "In3.Cu")
	)
	(gr_circle
		(center 110.935008 -35.47999)
		(end 112.33404 -35.47999)
		(stroke
			(width 0.2)
			(type default)
		)
		(fill no)
		(layer "In3.Cu")
	)
	(gr_circle
		(center 110.935008 -32.93999)
		(end 112.33404 -32.93999)
		(stroke
			(width 0.2)
			(type default)
		)
		(fill no)
		(layer "In3.Cu")
	)
	(gr_circle
		(center 111.378746 -71.929244)
		(end 112.267746 -71.929244)
		(stroke
			(width 0.2)
			(type default)
		)
		(fill no)
		(layer "In3.Cu")
	)
	(gr_circle
		(center 111.378746 -70.913244)
		(end 112.267746 -70.913244)
		(stroke
			(width 0.2)
			(type default)
		)
		(fill no)
		(layer "In3.Cu")
	)
	(gr_circle
		(center 111.378746 -69.897244)
		(end 112.267746 -69.897244)
		(stroke
			(width 0.2)
			(type default)
		)
		(fill no)
		(layer "In3.Cu")
	)
	(gr_circle
		(center 111.378746 -68.881244)
		(end 112.267746 -68.881244)
		(stroke
			(width 0.2)
			(type default)
		)
		(fill no)
		(layer "In3.Cu")
	)
	(gr_circle
		(center 112.078008 -34.71799)
		(end 113.47704 -34.71799)
		(stroke
			(width 0.2)
			(type default)
		)
		(fill no)
		(layer "In3.Cu")
	)
	(gr_circle
		(center 112.205008 -39.03599)
		(end 113.60404 -39.03599)
		(stroke
			(width 0.2)
			(type default)
		)
		(fill no)
		(layer "In3.Cu")
	)
	(gr_circle
		(center 112.394746 -71.929244)
		(end 113.283746 -71.929244)
		(stroke
			(width 0.2)
			(type default)
		)
		(fill no)
		(layer "In3.Cu")
	)
	(gr_circle
		(center 112.394746 -70.913244)
		(end 113.283746 -70.913244)
		(stroke
			(width 0.2)
			(type default)
		)
		(fill no)
		(layer "In3.Cu")
	)
	(gr_circle
		(center 112.394746 -69.897244)
		(end 113.283746 -69.897244)
		(stroke
			(width 0.2)
			(type default)
		)
		(fill no)
		(layer "In3.Cu")
	)
	(gr_circle
		(center 112.394746 -68.881244)
		(end 113.283746 -68.881244)
		(stroke
			(width 0.2)
			(type default)
		)
		(fill no)
		(layer "In3.Cu")
	)
	(gr_circle
		(center 112.586008 -37.00399)
		(end 113.98504 -37.00399)
		(stroke
			(width 0.2)
			(type default)
		)
		(fill no)
		(layer "In3.Cu")
	)
	(gr_circle
		(center 113.475008 -40.55999)
		(end 114.87404 -40.55999)
		(stroke
			(width 0.2)
			(type default)
		)
		(fill no)
		(layer "In3.Cu")
	)
	(gr_circle
		(center 113.475008 -38.01999)
		(end 114.87404 -38.01999)
		(stroke
			(width 0.2)
			(type default)
		)
		(fill no)
		(layer "In3.Cu")
	)
	(gr_circle
		(center 113.475008 -35.47999)
		(end 114.87404 -35.47999)
		(stroke
			(width 0.2)
			(type default)
		)
		(fill no)
		(layer "In3.Cu")
	)
	(gr_circle
		(center 113.475008 -32.93999)
		(end 114.87404 -32.93999)
		(stroke
			(width 0.2)
			(type default)
		)
		(fill no)
		(layer "In3.Cu")
	)
	(gr_circle
		(center 119.825008 -40.55999)
		(end 121.22404 -40.55999)
		(stroke
			(width 0.2)
			(type default)
		)
		(fill no)
		(layer "In3.Cu")
	)
	(gr_circle
		(center 119.825008 -38.01999)
		(end 121.22404 -38.01999)
		(stroke
			(width 0.2)
			(type default)
		)
		(fill no)
		(layer "In3.Cu")
	)
	(gr_circle
		(center 119.825008 -35.47999)
		(end 121.22404 -35.47999)
		(stroke
			(width 0.2)
			(type default)
		)
		(fill no)
		(layer "In3.Cu")
	)
	(gr_circle
		(center 119.825008 -32.93999)
		(end 121.22404 -32.93999)
		(stroke
			(width 0.2)
			(type default)
		)
		(fill no)
		(layer "In3.Cu")
	)
	(gr_circle
		(center 120.015 -60.96)
		(end 121.412 -60.96)
		(stroke
			(width 0.2)
			(type default)
		)
		(fill no)
		(layer "In3.Cu")
	)
	(gr_circle
		(center 121.095008 -36.74999)
		(end 122.49404 -36.74999)
		(stroke
			(width 0.2)
			(type default)
		)
		(fill no)
		(layer "In3.Cu")
	)
	(gr_circle
		(center 121.222008 -39.03599)
		(end 122.62104 -39.03599)
		(stroke
			(width 0.2)
			(type default)
		)
		(fill no)
		(layer "In3.Cu")
	)
	(gr_circle
		(center 121.349008 -34.20999)
		(end 122.74804 -34.20999)
		(stroke
			(width 0.2)
			(type default)
		)
		(fill no)
		(layer "In3.Cu")
	)
	(gr_circle
		(center 122.047 -136.906)
		(end 123.4694 -136.906)
		(stroke
			(width 0.2)
			(type default)
		)
		(fill no)
		(layer "In3.Cu")
	)
	(gr_circle
		(center 122.365008 -40.55999)
		(end 123.76404 -40.55999)
		(stroke
			(width 0.2)
			(type default)
		)
		(fill no)
		(layer "In3.Cu")
	)
	(gr_circle
		(center 122.365008 -38.01999)
		(end 123.76404 -38.01999)
		(stroke
			(width 0.2)
			(type default)
		)
		(fill no)
		(layer "In3.Cu")
	)
	(gr_circle
		(center 122.365008 -35.47999)
		(end 123.76404 -35.47999)
		(stroke
			(width 0.2)
			(type default)
		)
		(fill no)
		(layer "In3.Cu")
	)
	(gr_circle
		(center 122.365008 -32.93999)
		(end 123.76404 -32.93999)
		(stroke
			(width 0.2)
			(type default)
		)
		(fill no)
		(layer "In3.Cu")
	)
	(gr_circle
		(center 122.9106 -131.572)
		(end 123.7996 -131.572)
		(stroke
			(width 0.2)
			(type default)
		)
		(fill no)
		(layer "In3.Cu")
	)
	(gr_circle
		(center 122.9106 -126.492)
		(end 123.7996 -126.492)
		(stroke
			(width 0.2)
			(type default)
		)
		(fill no)
		(layer "In3.Cu")
	)
	(gr_circle
		(center 123.6726 -131.572)
		(end 124.5616 -131.572)
		(stroke
			(width 0.2)
			(type default)
		)
		(fill no)
		(layer "In3.Cu")
	)
	(gr_circle
		(center 123.6726 -126.492)
		(end 124.5616 -126.492)
		(stroke
			(width 0.2)
			(type default)
		)
		(fill no)
		(layer "In3.Cu")
	)
	(gr_circle
		(center 131.191 -60.96)
		(end 132.588 -60.96)
		(stroke
			(width 0.2)
			(type default)
		)
		(fill no)
		(layer "In3.Cu")
	)
	(gr_circle
		(center 134.239 -136.906)
		(end 135.6614 -136.906)
		(stroke
			(width 0.2)
			(type default)
		)
		(fill no)
		(layer "In3.Cu")
	)
	(gr_circle
		(center 135.1026 -131.572)
		(end 135.9916 -131.572)
		(stroke
			(width 0.2)
			(type default)
		)
		(fill no)
		(layer "In3.Cu")
	)
	(gr_circle
		(center 135.1026 -126.492)
		(end 135.9916 -126.492)
		(stroke
			(width 0.2)
			(type default)
		)
		(fill no)
		(layer "In3.Cu")
	)
	(gr_circle
		(center 135.8646 -131.572)
		(end 136.7536 -131.572)
		(stroke
			(width 0.2)
			(type default)
		)
		(fill no)
		(layer "In3.Cu")
	)
	(gr_circle
		(center 135.8646 -126.492)
		(end 136.7536 -126.492)
		(stroke
			(width 0.2)
			(type default)
		)
		(fill no)
		(layer "In3.Cu")
	)
	(gr_circle
		(center 142.748 -112.268)
		(end 143.637 -112.268)
		(stroke
			(width 0.2)
			(type default)
		)
		(fill no)
		(layer "In3.Cu")
	)
	(gr_circle
		(center 142.850108 -77.71765)
		(end 143.739108 -77.71765)
		(stroke
			(width 0.2)
			(type default)
		)
		(fill no)
		(layer "In3.Cu")
	)
	(gr_circle
		(center 143.383 -112.268)
		(end 144.272 -112.268)
		(stroke
			(width 0.2)
			(type default)
		)
		(fill no)
		(layer "In3.Cu")
	)
	(gr_circle
		(center 144.47012 -121.209816)
		(end 146.28622 -121.209816)
		(stroke
			(width 0.2)
			(type default)
		)
		(fill no)
		(layer "In3.Cu")
	)
	(gr_circle
		(center 144.47012 -70.409816)
		(end 146.66722 -70.409816)
		(stroke
			(width 0.2)
			(type default)
		)
		(fill no)
		(layer "In3.Cu")
	)
	(gr_circle
		(center 146.431 -136.906)
		(end 147.8534 -136.906)
		(stroke
			(width 0.2)
			(type default)
		)
		(fill no)
		(layer "In3.Cu")
	)
	(gr_circle
		(center 146.939 -60.96)
		(end 148.336 -60.96)
		(stroke
			(width 0.2)
			(type default)
		)
		(fill no)
		(layer "In3.Cu")
	)
	(gr_circle
		(center 147.2946 -131.572)
		(end 148.1836 -131.572)
		(stroke
			(width 0.2)
			(type default)
		)
		(fill no)
		(layer "In3.Cu")
	)
	(gr_circle
		(center 147.2946 -126.492)
		(end 148.1836 -126.492)
		(stroke
			(width 0.2)
			(type default)
		)
		(fill no)
		(layer "In3.Cu")
	)
	(gr_circle
		(center 148.0566 -131.572)
		(end 148.9456 -131.572)
		(stroke
			(width 0.2)
			(type default)
		)
		(fill no)
		(layer "In3.Cu")
	)
	(gr_circle
		(center 148.0566 -126.492)
		(end 148.9456 -126.492)
		(stroke
			(width 0.2)
			(type default)
		)
		(fill no)
		(layer "In3.Cu")
	)
	(gr_circle
		(center 148.28012 -70.409816)
		(end 150.47722 -70.409816)
		(stroke
			(width 0.2)
			(type default)
		)
		(fill no)
		(layer "In3.Cu")
	)
	(gr_circle
		(center 149.987 -52.197)
		(end 150.876 -52.197)
		(stroke
			(width 0.2)
			(type default)
		)
		(fill no)
		(layer "In3.Cu")
	)
	(gr_circle
		(center 149.987 -51.562)
		(end 150.876 -51.562)
		(stroke
			(width 0.2)
			(type default)
		)
		(fill no)
		(layer "In3.Cu")
	)
	(gr_circle
		(center 149.987 -50.292)
		(end 150.876 -50.292)
		(stroke
			(width 0.2)
			(type default)
		)
		(fill no)
		(layer "In3.Cu")
	)
	(gr_circle
		(center 149.987 -49.657)
		(end 150.876 -49.657)
		(stroke
			(width 0.2)
			(type default)
		)
		(fill no)
		(layer "In3.Cu")
	)
	(gr_circle
		(center 155.448 -52.197)
		(end 156.337 -52.197)
		(stroke
			(width 0.2)
			(type default)
		)
		(fill no)
		(layer "In3.Cu")
	)
	(gr_circle
		(center 155.448 -51.562)
		(end 156.337 -51.562)
		(stroke
			(width 0.2)
			(type default)
		)
		(fill no)
		(layer "In3.Cu")
	)
	(gr_circle
		(center 155.448 -50.292)
		(end 156.337 -50.292)
		(stroke
			(width 0.2)
			(type default)
		)
		(fill no)
		(layer "In3.Cu")
	)
	(gr_circle
		(center 155.448 -49.657)
		(end 156.337 -49.657)
		(stroke
			(width 0.2)
			(type default)
		)
		(fill no)
		(layer "In3.Cu")
	)
	(gr_circle
		(center 158.115 -60.96)
		(end 159.512 -60.96)
		(stroke
			(width 0.2)
			(type default)
		)
		(fill no)
		(layer "In3.Cu")
	)
	(gr_circle
		(center 160.909 -52.197)
		(end 161.798 -52.197)
		(stroke
			(width 0.2)
			(type default)
		)
		(fill no)
		(layer "In3.Cu")
	)
	(gr_circle
		(center 160.909 -51.562)
		(end 161.798 -51.562)
		(stroke
			(width 0.2)
			(type default)
		)
		(fill no)
		(layer "In3.Cu")
	)
	(gr_circle
		(center 160.909 -50.292)
		(end 161.798 -50.292)
		(stroke
			(width 0.2)
			(type default)
		)
		(fill no)
		(layer "In3.Cu")
	)
	(gr_circle
		(center 160.909 -49.657)
		(end 161.798 -49.657)
		(stroke
			(width 0.2)
			(type default)
		)
		(fill no)
		(layer "In3.Cu")
	)
	(gr_circle
		(center 162.047174 -136.906)
		(end 163.469574 -136.906)
		(stroke
			(width 0.2)
			(type default)
		)
		(fill no)
		(layer "In3.Cu")
	)
	(gr_circle
		(center 162.1028 -11.811)
		(end 162.9918 -11.811)
		(stroke
			(width 0.2)
			(type default)
		)
		(fill no)
		(layer "In3.Cu")
	)
	(gr_circle
		(center 162.1028 -11.176)
		(end 162.9918 -11.176)
		(stroke
			(width 0.2)
			(type default)
		)
		(fill no)
		(layer "In3.Cu")
	)
	(gr_circle
		(center 162.7886 -10.7442)
		(end 163.6776 -10.7442)
		(stroke
			(width 0.2)
			(type default)
		)
		(fill no)
		(layer "In3.Cu")
	)
	(gr_circle
		(center 162.8394 -12.2174)
		(end 163.7284 -12.2174)
		(stroke
			(width 0.2)
			(type default)
		)
		(fill no)
		(layer "In3.Cu")
	)
	(gr_circle
		(center 162.910774 -131.572)
		(end 163.799774 -131.572)
		(stroke
			(width 0.2)
			(type default)
		)
		(fill no)
		(layer "In3.Cu")
	)
	(gr_circle
		(center 162.910774 -126.492)
		(end 163.799774 -126.492)
		(stroke
			(width 0.2)
			(type default)
		)
		(fill no)
		(layer "In3.Cu")
	)
	(gr_circle
		(center 163.672774 -131.572)
		(end 164.561774 -131.572)
		(stroke
			(width 0.2)
			(type default)
		)
		(fill no)
		(layer "In3.Cu")
	)
	(gr_circle
		(center 163.672774 -126.492)
		(end 164.561774 -126.492)
		(stroke
			(width 0.2)
			(type default)
		)
		(fill no)
		(layer "In3.Cu")
	)
	(gr_circle
		(center 166.37 -52.197)
		(end 167.259 -52.197)
		(stroke
			(width 0.2)
			(type default)
		)
		(fill no)
		(layer "In3.Cu")
	)
	(gr_circle
		(center 166.37 -51.562)
		(end 167.259 -51.562)
		(stroke
			(width 0.2)
			(type default)
		)
		(fill no)
		(layer "In3.Cu")
	)
	(gr_circle
		(center 166.37 -50.292)
		(end 167.259 -50.292)
		(stroke
			(width 0.2)
			(type default)
		)
		(fill no)
		(layer "In3.Cu")
	)
	(gr_circle
		(center 166.37 -49.657)
		(end 167.259 -49.657)
		(stroke
			(width 0.2)
			(type default)
		)
		(fill no)
		(layer "In3.Cu")
	)
	(gr_circle
		(center 169.291 -60.96)
		(end 170.688 -60.96)
		(stroke
			(width 0.2)
			(type default)
		)
		(fill no)
		(layer "In3.Cu")
	)
	(gr_circle
		(center 171.831 -52.197)
		(end 172.72 -52.197)
		(stroke
			(width 0.2)
			(type default)
		)
		(fill no)
		(layer "In3.Cu")
	)
	(gr_circle
		(center 171.831 -51.562)
		(end 172.72 -51.562)
		(stroke
			(width 0.2)
			(type default)
		)
		(fill no)
		(layer "In3.Cu")
	)
	(gr_circle
		(center 171.831 -50.292)
		(end 172.72 -50.292)
		(stroke
			(width 0.2)
			(type default)
		)
		(fill no)
		(layer "In3.Cu")
	)
	(gr_circle
		(center 171.831 -49.657)
		(end 172.72 -49.657)
		(stroke
			(width 0.2)
			(type default)
		)
		(fill no)
		(layer "In3.Cu")
	)
	(gr_circle
		(center 174.239174 -136.906)
		(end 175.661574 -136.906)
		(stroke
			(width 0.2)
			(type default)
		)
		(fill no)
		(layer "In3.Cu")
	)
	(gr_circle
		(center 175.102774 -131.572)
		(end 175.991774 -131.572)
		(stroke
			(width 0.2)
			(type default)
		)
		(fill no)
		(layer "In3.Cu")
	)
	(gr_circle
		(center 175.102774 -126.492)
		(end 175.991774 -126.492)
		(stroke
			(width 0.2)
			(type default)
		)
		(fill no)
		(layer "In3.Cu")
	)
	(gr_circle
		(center 175.864774 -131.572)
		(end 176.753774 -131.572)
		(stroke
			(width 0.2)
			(type default)
		)
		(fill no)
		(layer "In3.Cu")
	)
	(gr_circle
		(center 175.864774 -126.492)
		(end 176.753774 -126.492)
		(stroke
			(width 0.2)
			(type default)
		)
		(fill no)
		(layer "In3.Cu")
	)
	(gr_circle
		(center 177.28946 -52.197)
		(end 178.17846 -52.197)
		(stroke
			(width 0.2)
			(type default)
		)
		(fill no)
		(layer "In3.Cu")
	)
	(gr_circle
		(center 177.28946 -51.562)
		(end 178.17846 -51.562)
		(stroke
			(width 0.2)
			(type default)
		)
		(fill no)
		(layer "In3.Cu")
	)
	(gr_circle
		(center 177.28946 -50.292)
		(end 178.17846 -50.292)
		(stroke
			(width 0.2)
			(type default)
		)
		(fill no)
		(layer "In3.Cu")
	)
	(gr_circle
		(center 177.28946 -49.657)
		(end 178.17846 -49.657)
		(stroke
			(width 0.2)
			(type default)
		)
		(fill no)
		(layer "In3.Cu")
	)
	(gr_circle
		(center 180.989986 -37.949632)
		(end 182.389018 -37.949632)
		(stroke
			(width 0.2)
			(type default)
		)
		(fill no)
		(layer "In3.Cu")
	)
	(gr_circle
		(center 180.989986 -35.409632)
		(end 182.389018 -35.409632)
		(stroke
			(width 0.2)
			(type default)
		)
		(fill no)
		(layer "In3.Cu")
	)
	(gr_circle
		(center 180.989986 -32.869632)
		(end 182.389018 -32.869632)
		(stroke
			(width 0.2)
			(type default)
		)
		(fill no)
		(layer "In3.Cu")
	)
	(gr_circle
		(center 180.989986 -30.329632)
		(end 182.389018 -30.329632)
		(stroke
			(width 0.2)
			(type default)
		)
		(fill no)
		(layer "In3.Cu")
	)
	(gr_circle
		(center 182.182008 -36.62299)
		(end 183.58104 -36.62299)
		(stroke
			(width 0.2)
			(type default)
		)
		(fill no)
		(layer "In3.Cu")
	)
	(gr_circle
		(center 182.182008 -34.46399)
		(end 183.58104 -34.46399)
		(stroke
			(width 0.2)
			(type default)
		)
		(fill no)
		(layer "In3.Cu")
	)
	(gr_circle
		(center 182.182008 -31.66999)
		(end 183.58104 -31.66999)
		(stroke
			(width 0.2)
			(type default)
		)
		(fill no)
		(layer "In3.Cu")
	)
	(gr_circle
		(center 182.75046 -52.197)
		(end 183.63946 -52.197)
		(stroke
			(width 0.2)
			(type default)
		)
		(fill no)
		(layer "In3.Cu")
	)
	(gr_circle
		(center 182.75046 -51.562)
		(end 183.63946 -51.562)
		(stroke
			(width 0.2)
			(type default)
		)
		(fill no)
		(layer "In3.Cu")
	)
	(gr_circle
		(center 182.75046 -50.292)
		(end 183.63946 -50.292)
		(stroke
			(width 0.2)
			(type default)
		)
		(fill no)
		(layer "In3.Cu")
	)
	(gr_circle
		(center 182.75046 -49.657)
		(end 183.63946 -49.657)
		(stroke
			(width 0.2)
			(type default)
		)
		(fill no)
		(layer "In3.Cu")
	)
	(gr_circle
		(center 182.850282 -77.71765)
		(end 183.739282 -77.71765)
		(stroke
			(width 0.2)
			(type default)
		)
		(fill no)
		(layer "In3.Cu")
	)
	(gr_circle
		(center 183.529986 -37.949632)
		(end 184.929018 -37.949632)
		(stroke
			(width 0.2)
			(type default)
		)
		(fill no)
		(layer "In3.Cu")
	)
	(gr_circle
		(center 183.529986 -35.409632)
		(end 184.929018 -35.409632)
		(stroke
			(width 0.2)
			(type default)
		)
		(fill no)
		(layer "In3.Cu")
	)
	(gr_circle
		(center 183.529986 -32.869632)
		(end 184.929018 -32.869632)
		(stroke
			(width 0.2)
			(type default)
		)
		(fill no)
		(layer "In3.Cu")
	)
	(gr_circle
		(center 183.529986 -30.329632)
		(end 184.929018 -30.329632)
		(stroke
			(width 0.2)
			(type default)
		)
		(fill no)
		(layer "In3.Cu")
	)
	(gr_circle
		(center 184.470294 -121.209816)
		(end 186.286394 -121.209816)
		(stroke
			(width 0.2)
			(type default)
		)
		(fill no)
		(layer "In3.Cu")
	)
	(gr_circle
		(center 184.470294 -70.409816)
		(end 186.667394 -70.409816)
		(stroke
			(width 0.2)
			(type default)
		)
		(fill no)
		(layer "In3.Cu")
	)
	(gr_circle
		(center 186.431174 -136.906)
		(end 187.853574 -136.906)
		(stroke
			(width 0.2)
			(type default)
		)
		(fill no)
		(layer "In3.Cu")
	)
	(gr_circle
		(center 186.939174 -60.96)
		(end 188.336174 -60.96)
		(stroke
			(width 0.2)
			(type default)
		)
		(fill no)
		(layer "In3.Cu")
	)
	(gr_circle
		(center 187.294774 -131.572)
		(end 188.183774 -131.572)
		(stroke
			(width 0.2)
			(type default)
		)
		(fill no)
		(layer "In3.Cu")
	)
	(gr_circle
		(center 187.294774 -126.492)
		(end 188.183774 -126.492)
		(stroke
			(width 0.2)
			(type default)
		)
		(fill no)
		(layer "In3.Cu")
	)
	(gr_circle
		(center 188.056774 -131.572)
		(end 188.945774 -131.572)
		(stroke
			(width 0.2)
			(type default)
		)
		(fill no)
		(layer "In3.Cu")
	)
	(gr_circle
		(center 188.056774 -126.492)
		(end 188.945774 -126.492)
		(stroke
			(width 0.2)
			(type default)
		)
		(fill no)
		(layer "In3.Cu")
	)
	(gr_circle
		(center 188.280294 -70.409816)
		(end 190.477394 -70.409816)
		(stroke
			(width 0.2)
			(type default)
		)
		(fill no)
		(layer "In3.Cu")
	)
	(gr_circle
		(center 189.879986 -37.949632)
		(end 191.279018 -37.949632)
		(stroke
			(width 0.2)
			(type default)
		)
		(fill no)
		(layer "In3.Cu")
	)
	(gr_circle
		(center 189.879986 -35.409632)
		(end 191.279018 -35.409632)
		(stroke
			(width 0.2)
			(type default)
		)
		(fill no)
		(layer "In3.Cu")
	)
	(gr_circle
		(center 189.879986 -32.869632)
		(end 191.279018 -32.869632)
		(stroke
			(width 0.2)
			(type default)
		)
		(fill no)
		(layer "In3.Cu")
	)
	(gr_circle
		(center 189.879986 -30.329632)
		(end 191.279018 -30.329632)
		(stroke
			(width 0.2)
			(type default)
		)
		(fill no)
		(layer "In3.Cu")
	)
	(gr_circle
		(center 191.199008 -36.62299)
		(end 192.59804 -36.62299)
		(stroke
			(width 0.2)
			(type default)
		)
		(fill no)
		(layer "In3.Cu")
	)
	(gr_circle
		(center 191.199008 -34.33699)
		(end 192.59804 -34.33699)
		(stroke
			(width 0.2)
			(type default)
		)
		(fill no)
		(layer "In3.Cu")
	)
	(gr_circle
		(center 191.199008 -31.54299)
		(end 192.59804 -31.54299)
		(stroke
			(width 0.2)
			(type default)
		)
		(fill no)
		(layer "In3.Cu")
	)
	(gr_circle
		(center 192.419986 -37.949632)
		(end 193.819018 -37.949632)
		(stroke
			(width 0.2)
			(type default)
		)
		(fill no)
		(layer "In3.Cu")
	)
	(gr_circle
		(center 192.419986 -35.409632)
		(end 193.819018 -35.409632)
		(stroke
			(width 0.2)
			(type default)
		)
		(fill no)
		(layer "In3.Cu")
	)
	(gr_circle
		(center 192.419986 -32.869632)
		(end 193.819018 -32.869632)
		(stroke
			(width 0.2)
			(type default)
		)
		(fill no)
		(layer "In3.Cu")
	)
	(gr_circle
		(center 192.419986 -30.329632)
		(end 193.819018 -30.329632)
		(stroke
			(width 0.2)
			(type default)
		)
		(fill no)
		(layer "In3.Cu")
	)
	(gr_circle
		(center 198.115174 -60.96)
		(end 199.512174 -60.96)
		(stroke
			(width 0.2)
			(type default)
		)
		(fill no)
		(layer "In3.Cu")
	)
	(gr_circle
		(center 198.769986 -37.949632)
		(end 200.169018 -37.949632)
		(stroke
			(width 0.2)
			(type default)
		)
		(fill no)
		(layer "In3.Cu")
	)
	(gr_circle
		(center 198.769986 -35.409632)
		(end 200.169018 -35.409632)
		(stroke
			(width 0.2)
			(type default)
		)
		(fill no)
		(layer "In3.Cu")
	)
	(gr_circle
		(center 198.769986 -32.869632)
		(end 200.169018 -32.869632)
		(stroke
			(width 0.2)
			(type default)
		)
		(fill no)
		(layer "In3.Cu")
	)
	(gr_circle
		(center 198.769986 -30.329632)
		(end 200.169018 -30.329632)
		(stroke
			(width 0.2)
			(type default)
		)
		(fill no)
		(layer "In3.Cu")
	)
	(gr_circle
		(center 199.962008 -34.46399)
		(end 201.36104 -34.46399)
		(stroke
			(width 0.2)
			(type default)
		)
		(fill no)
		(layer "In3.Cu")
	)
	(gr_circle
		(center 200.089008 -36.62299)
		(end 201.48804 -36.62299)
		(stroke
			(width 0.2)
			(type default)
		)
		(fill no)
		(layer "In3.Cu")
	)
	(gr_circle
		(center 200.089008 -31.79699)
		(end 201.48804 -31.79699)
		(stroke
			(width 0.2)
			(type default)
		)
		(fill no)
		(layer "In3.Cu")
	)
	(gr_circle
		(center 201.309986 -37.949632)
		(end 202.709018 -37.949632)
		(stroke
			(width 0.2)
			(type default)
		)
		(fill no)
		(layer "In3.Cu")
	)
	(gr_circle
		(center 201.309986 -35.409632)
		(end 202.709018 -35.409632)
		(stroke
			(width 0.2)
			(type default)
		)
		(fill no)
		(layer "In3.Cu")
	)
	(gr_circle
		(center 201.309986 -32.869632)
		(end 202.709018 -32.869632)
		(stroke
			(width 0.2)
			(type default)
		)
		(fill no)
		(layer "In3.Cu")
	)
	(gr_circle
		(center 201.309986 -30.329632)
		(end 202.709018 -30.329632)
		(stroke
			(width 0.2)
			(type default)
		)
		(fill no)
		(layer "In3.Cu")
	)
	(gr_circle
		(center 202.3364 -105.883202)
		(end 203.2254 -105.883202)
		(stroke
			(width 0.2)
			(type default)
		)
		(fill no)
		(layer "In3.Cu")
	)
	(gr_circle
		(center 202.3364 -105.121202)
		(end 203.2254 -105.121202)
		(stroke
			(width 0.2)
			(type default)
		)
		(fill no)
		(layer "In3.Cu")
	)
	(gr_circle
		(center 202.3364 -104.418638)
		(end 203.2254 -104.418638)
		(stroke
			(width 0.2)
			(type default)
		)
		(fill no)
		(layer "In3.Cu")
	)
	(gr_circle
		(center 202.3364 -103.656638)
		(end 203.2254 -103.656638)
		(stroke
			(width 0.2)
			(type default)
		)
		(fill no)
		(layer "In3.Cu")
	)
	(gr_circle
		(center 202.3364 -102.894638)
		(end 203.2254 -102.894638)
		(stroke
			(width 0.2)
			(type default)
		)
		(fill no)
		(layer "In3.Cu")
	)
	(gr_circle
		(center 202.35037 -122.809762)
		(end 203.23937 -122.809762)
		(stroke
			(width 0.2)
			(type default)
		)
		(fill no)
		(layer "In3.Cu")
	)
	(gr_circle
		(center 202.35037 -122.047762)
		(end 203.23937 -122.047762)
		(stroke
			(width 0.2)
			(type default)
		)
		(fill no)
		(layer "In3.Cu")
	)
	(gr_circle
		(center 202.35037 -121.331736)
		(end 203.23937 -121.331736)
		(stroke
			(width 0.2)
			(type default)
		)
		(fill no)
		(layer "In3.Cu")
	)
	(gr_circle
		(center 202.35037 -120.569736)
		(end 203.23937 -120.569736)
		(stroke
			(width 0.2)
			(type default)
		)
		(fill no)
		(layer "In3.Cu")
	)
	(gr_circle
		(center 202.364086 -123.528328)
		(end 203.253086 -123.528328)
		(stroke
			(width 0.2)
			(type default)
		)
		(fill no)
		(layer "In3.Cu")
	)
	(gr_circle
		(center 203.028042 -105.896664)
		(end 203.917042 -105.896664)
		(stroke
			(width 0.2)
			(type default)
		)
		(fill no)
		(layer "In3.Cu")
	)
	(gr_circle
		(center 203.028042 -105.134664)
		(end 203.917042 -105.134664)
		(stroke
			(width 0.2)
			(type default)
		)
		(fill no)
		(layer "In3.Cu")
	)
	(gr_circle
		(center 203.028042 -104.4321)
		(end 203.917042 -104.4321)
		(stroke
			(width 0.2)
			(type default)
		)
		(fill no)
		(layer "In3.Cu")
	)
	(gr_circle
		(center 203.028042 -103.6701)
		(end 203.917042 -103.6701)
		(stroke
			(width 0.2)
			(type default)
		)
		(fill no)
		(layer "In3.Cu")
	)
	(gr_circle
		(center 203.028042 -102.9081)
		(end 203.917042 -102.9081)
		(stroke
			(width 0.2)
			(type default)
		)
		(fill no)
		(layer "In3.Cu")
	)
	(gr_circle
		(center 203.11237 -122.809762)
		(end 204.00137 -122.809762)
		(stroke
			(width 0.2)
			(type default)
		)
		(fill no)
		(layer "In3.Cu")
	)
	(gr_circle
		(center 203.11237 -122.047762)
		(end 204.00137 -122.047762)
		(stroke
			(width 0.2)
			(type default)
		)
		(fill no)
		(layer "In3.Cu")
	)
	(gr_circle
		(center 203.11237 -121.331736)
		(end 204.00137 -121.331736)
		(stroke
			(width 0.2)
			(type default)
		)
		(fill no)
		(layer "In3.Cu")
	)
	(gr_circle
		(center 203.11237 -120.569736)
		(end 204.00137 -120.569736)
		(stroke
			(width 0.2)
			(type default)
		)
		(fill no)
		(layer "In3.Cu")
	)
	(gr_circle
		(center 203.126086 -123.528328)
		(end 204.015086 -123.528328)
		(stroke
			(width 0.2)
			(type default)
		)
		(fill no)
		(layer "In3.Cu")
	)
	(gr_circle
		(center 203.790042 -105.896664)
		(end 204.679042 -105.896664)
		(stroke
			(width 0.2)
			(type default)
		)
		(fill no)
		(layer "In3.Cu")
	)
	(gr_circle
		(center 203.790042 -105.134664)
		(end 204.679042 -105.134664)
		(stroke
			(width 0.2)
			(type default)
		)
		(fill no)
		(layer "In3.Cu")
	)
	(gr_circle
		(center 203.790042 -104.4321)
		(end 204.679042 -104.4321)
		(stroke
			(width 0.2)
			(type default)
		)
		(fill no)
		(layer "In3.Cu")
	)
	(gr_circle
		(center 203.790042 -103.6701)
		(end 204.679042 -103.6701)
		(stroke
			(width 0.2)
			(type default)
		)
		(fill no)
		(layer "In3.Cu")
	)
	(gr_circle
		(center 203.790042 -102.9081)
		(end 204.679042 -102.9081)
		(stroke
			(width 0.2)
			(type default)
		)
		(fill no)
		(layer "In3.Cu")
	)
	(gr_circle
		(center 203.87437 -122.809762)
		(end 204.76337 -122.809762)
		(stroke
			(width 0.2)
			(type default)
		)
		(fill no)
		(layer "In3.Cu")
	)
	(gr_circle
		(center 203.87437 -122.047762)
		(end 204.76337 -122.047762)
		(stroke
			(width 0.2)
			(type default)
		)
		(fill no)
		(layer "In3.Cu")
	)
	(gr_circle
		(center 203.87437 -121.331736)
		(end 204.76337 -121.331736)
		(stroke
			(width 0.2)
			(type default)
		)
		(fill no)
		(layer "In3.Cu")
	)
	(gr_circle
		(center 203.87437 -120.569736)
		(end 204.76337 -120.569736)
		(stroke
			(width 0.2)
			(type default)
		)
		(fill no)
		(layer "In3.Cu")
	)
	(gr_circle
		(center 203.888086 -123.528328)
		(end 204.777086 -123.528328)
		(stroke
			(width 0.2)
			(type default)
		)
		(fill no)
		(layer "In3.Cu")
	)
	(gr_circle
		(center 204.552042 -105.896664)
		(end 205.441042 -105.896664)
		(stroke
			(width 0.2)
			(type default)
		)
		(fill no)
		(layer "In3.Cu")
	)
	(gr_circle
		(center 204.552042 -105.134664)
		(end 205.441042 -105.134664)
		(stroke
			(width 0.2)
			(type default)
		)
		(fill no)
		(layer "In3.Cu")
	)
	(gr_circle
		(center 204.552042 -104.4321)
		(end 205.441042 -104.4321)
		(stroke
			(width 0.2)
			(type default)
		)
		(fill no)
		(layer "In3.Cu")
	)
	(gr_circle
		(center 204.552042 -103.6701)
		(end 205.441042 -103.6701)
		(stroke
			(width 0.2)
			(type default)
		)
		(fill no)
		(layer "In3.Cu")
	)
	(gr_circle
		(center 204.552042 -102.9081)
		(end 205.441042 -102.9081)
		(stroke
			(width 0.2)
			(type default)
		)
		(fill no)
		(layer "In3.Cu")
	)
	(gr_circle
		(center 204.63637 -122.809762)
		(end 205.52537 -122.809762)
		(stroke
			(width 0.2)
			(type default)
		)
		(fill no)
		(layer "In3.Cu")
	)
	(gr_circle
		(center 204.63637 -122.047762)
		(end 205.52537 -122.047762)
		(stroke
			(width 0.2)
			(type default)
		)
		(fill no)
		(layer "In3.Cu")
	)
	(gr_circle
		(center 204.63637 -121.331736)
		(end 205.52537 -121.331736)
		(stroke
			(width 0.2)
			(type default)
		)
		(fill no)
		(layer "In3.Cu")
	)
	(gr_circle
		(center 204.63637 -120.569736)
		(end 205.52537 -120.569736)
		(stroke
			(width 0.2)
			(type default)
		)
		(fill no)
		(layer "In3.Cu")
	)
	(gr_circle
		(center 204.650086 -123.528328)
		(end 205.539086 -123.528328)
		(stroke
			(width 0.2)
			(type default)
		)
		(fill no)
		(layer "In3.Cu")
	)
	(gr_circle
		(center 205.314042 -105.896664)
		(end 206.203042 -105.896664)
		(stroke
			(width 0.2)
			(type default)
		)
		(fill no)
		(layer "In3.Cu")
	)
	(gr_circle
		(center 205.314042 -105.134664)
		(end 206.203042 -105.134664)
		(stroke
			(width 0.2)
			(type default)
		)
		(fill no)
		(layer "In3.Cu")
	)
	(gr_circle
		(center 205.314042 -104.4321)
		(end 206.203042 -104.4321)
		(stroke
			(width 0.2)
			(type default)
		)
		(fill no)
		(layer "In3.Cu")
	)
	(gr_circle
		(center 205.314042 -103.6701)
		(end 206.203042 -103.6701)
		(stroke
			(width 0.2)
			(type default)
		)
		(fill no)
		(layer "In3.Cu")
	)
	(gr_circle
		(center 205.314042 -102.9081)
		(end 206.203042 -102.9081)
		(stroke
			(width 0.2)
			(type default)
		)
		(fill no)
		(layer "In3.Cu")
	)
	(gr_circle
		(center 205.39837 -122.809762)
		(end 206.28737 -122.809762)
		(stroke
			(width 0.2)
			(type default)
		)
		(fill no)
		(layer "In3.Cu")
	)
	(gr_circle
		(center 205.39837 -122.047762)
		(end 206.28737 -122.047762)
		(stroke
			(width 0.2)
			(type default)
		)
		(fill no)
		(layer "In3.Cu")
	)
	(gr_circle
		(center 205.39837 -121.331736)
		(end 206.28737 -121.331736)
		(stroke
			(width 0.2)
			(type default)
		)
		(fill no)
		(layer "In3.Cu")
	)
	(gr_circle
		(center 205.39837 -120.569736)
		(end 206.28737 -120.569736)
		(stroke
			(width 0.2)
			(type default)
		)
		(fill no)
		(layer "In3.Cu")
	)
	(gr_circle
		(center 205.412086 -123.528328)
		(end 206.301086 -123.528328)
		(stroke
			(width 0.2)
			(type default)
		)
		(fill no)
		(layer "In3.Cu")
	)
	(gr_circle
		(center 206.076042 -105.896664)
		(end 206.965042 -105.896664)
		(stroke
			(width 0.2)
			(type default)
		)
		(fill no)
		(layer "In3.Cu")
	)
	(gr_circle
		(center 206.076042 -105.134664)
		(end 206.965042 -105.134664)
		(stroke
			(width 0.2)
			(type default)
		)
		(fill no)
		(layer "In3.Cu")
	)
	(gr_circle
		(center 206.076042 -104.4321)
		(end 206.965042 -104.4321)
		(stroke
			(width 0.2)
			(type default)
		)
		(fill no)
		(layer "In3.Cu")
	)
	(gr_circle
		(center 206.076042 -103.6701)
		(end 206.965042 -103.6701)
		(stroke
			(width 0.2)
			(type default)
		)
		(fill no)
		(layer "In3.Cu")
	)
	(gr_circle
		(center 206.076042 -102.9081)
		(end 206.965042 -102.9081)
		(stroke
			(width 0.2)
			(type default)
		)
		(fill no)
		(layer "In3.Cu")
	)
	(gr_circle
		(center 206.16037 -122.809762)
		(end 207.04937 -122.809762)
		(stroke
			(width 0.2)
			(type default)
		)
		(fill no)
		(layer "In3.Cu")
	)
	(gr_circle
		(center 206.16037 -122.047762)
		(end 207.04937 -122.047762)
		(stroke
			(width 0.2)
			(type default)
		)
		(fill no)
		(layer "In3.Cu")
	)
	(gr_circle
		(center 206.16037 -121.331736)
		(end 207.04937 -121.331736)
		(stroke
			(width 0.2)
			(type default)
		)
		(fill no)
		(layer "In3.Cu")
	)
	(gr_circle
		(center 206.16037 -120.569736)
		(end 207.04937 -120.569736)
		(stroke
			(width 0.2)
			(type default)
		)
		(fill no)
		(layer "In3.Cu")
	)
	(gr_circle
		(center 206.174086 -123.528328)
		(end 207.063086 -123.528328)
		(stroke
			(width 0.2)
			(type default)
		)
		(fill no)
		(layer "In3.Cu")
	)
	(gr_circle
		(center 206.838042 -105.896664)
		(end 207.727042 -105.896664)
		(stroke
			(width 0.2)
			(type default)
		)
		(fill no)
		(layer "In3.Cu")
	)
	(gr_circle
		(center 206.838042 -105.134664)
		(end 207.727042 -105.134664)
		(stroke
			(width 0.2)
			(type default)
		)
		(fill no)
		(layer "In3.Cu")
	)
	(gr_circle
		(center 206.838042 -104.4321)
		(end 207.727042 -104.4321)
		(stroke
			(width 0.2)
			(type default)
		)
		(fill no)
		(layer "In3.Cu")
	)
	(gr_circle
		(center 206.838042 -103.6701)
		(end 207.727042 -103.6701)
		(stroke
			(width 0.2)
			(type default)
		)
		(fill no)
		(layer "In3.Cu")
	)
	(gr_circle
		(center 206.838042 -102.9081)
		(end 207.727042 -102.9081)
		(stroke
			(width 0.2)
			(type default)
		)
		(fill no)
		(layer "In3.Cu")
	)
	(gr_circle
		(center 206.92237 -122.809762)
		(end 207.81137 -122.809762)
		(stroke
			(width 0.2)
			(type default)
		)
		(fill no)
		(layer "In3.Cu")
	)
	(gr_circle
		(center 206.92237 -122.047762)
		(end 207.81137 -122.047762)
		(stroke
			(width 0.2)
			(type default)
		)
		(fill no)
		(layer "In3.Cu")
	)
	(gr_circle
		(center 206.92237 -121.331736)
		(end 207.81137 -121.331736)
		(stroke
			(width 0.2)
			(type default)
		)
		(fill no)
		(layer "In3.Cu")
	)
	(gr_circle
		(center 206.92237 -120.569736)
		(end 207.81137 -120.569736)
		(stroke
			(width 0.2)
			(type default)
		)
		(fill no)
		(layer "In3.Cu")
	)
	(gr_circle
		(center 206.936086 -123.528328)
		(end 207.825086 -123.528328)
		(stroke
			(width 0.2)
			(type default)
		)
		(fill no)
		(layer "In3.Cu")
	)
	(gr_circle
		(center 207.556862 -105.882948)
		(end 208.445862 -105.882948)
		(stroke
			(width 0.2)
			(type default)
		)
		(fill no)
		(layer "In3.Cu")
	)
	(gr_circle
		(center 207.556862 -105.120948)
		(end 208.445862 -105.120948)
		(stroke
			(width 0.2)
			(type default)
		)
		(fill no)
		(layer "In3.Cu")
	)
	(gr_circle
		(center 207.556862 -104.418384)
		(end 208.445862 -104.418384)
		(stroke
			(width 0.2)
			(type default)
		)
		(fill no)
		(layer "In3.Cu")
	)
	(gr_circle
		(center 207.556862 -103.656384)
		(end 208.445862 -103.656384)
		(stroke
			(width 0.2)
			(type default)
		)
		(fill no)
		(layer "In3.Cu")
	)
	(gr_circle
		(center 207.556862 -102.894384)
		(end 208.445862 -102.894384)
		(stroke
			(width 0.2)
			(type default)
		)
		(fill no)
		(layer "In3.Cu")
	)
	(gr_circle
		(center 207.68437 -122.809762)
		(end 208.57337 -122.809762)
		(stroke
			(width 0.2)
			(type default)
		)
		(fill no)
		(layer "In3.Cu")
	)
	(gr_circle
		(center 207.68437 -122.047762)
		(end 208.57337 -122.047762)
		(stroke
			(width 0.2)
			(type default)
		)
		(fill no)
		(layer "In3.Cu")
	)
	(gr_circle
		(center 207.68437 -121.331736)
		(end 208.57337 -121.331736)
		(stroke
			(width 0.2)
			(type default)
		)
		(fill no)
		(layer "In3.Cu")
	)
	(gr_circle
		(center 207.68437 -120.569736)
		(end 208.57337 -120.569736)
		(stroke
			(width 0.2)
			(type default)
		)
		(fill no)
		(layer "In3.Cu")
	)
	(gr_circle
		(center 207.698086 -123.528328)
		(end 208.587086 -123.528328)
		(stroke
			(width 0.2)
			(type default)
		)
		(fill no)
		(layer "In3.Cu")
	)
	(gr_circle
		(center 209.291174 -60.96)
		(end 210.688174 -60.96)
		(stroke
			(width 0.2)
			(type default)
		)
		(fill no)
		(layer "In3.Cu")
	)
	(gr_circle
		(center 213.978236 -132.959856)
		(end 214.867236 -132.959856)
		(stroke
			(width 0.2)
			(type default)
		)
		(fill no)
		(layer "In3.Cu")
	)
	(gr_circle
		(center 213.978236 -132.197856)
		(end 214.867236 -132.197856)
		(stroke
			(width 0.2)
			(type default)
		)
		(fill no)
		(layer "In3.Cu")
	)
	(gr_circle
		(center 213.978236 -131.435856)
		(end 214.867236 -131.435856)
		(stroke
			(width 0.2)
			(type default)
		)
		(fill no)
		(layer "In3.Cu")
	)
	(gr_circle
		(center 213.978236 -130.673856)
		(end 214.867236 -130.673856)
		(stroke
			(width 0.2)
			(type default)
		)
		(fill no)
		(layer "In3.Cu")
	)
	(gr_circle
		(center 213.978236 -129.911856)
		(end 214.867236 -129.911856)
		(stroke
			(width 0.2)
			(type default)
		)
		(fill no)
		(layer "In3.Cu")
	)
	(gr_circle
		(center 213.978236 -129.149856)
		(end 214.867236 -129.149856)
		(stroke
			(width 0.2)
			(type default)
		)
		(fill no)
		(layer "In3.Cu")
	)
	(gr_circle
		(center 213.978236 -128.387856)
		(end 214.867236 -128.387856)
		(stroke
			(width 0.2)
			(type default)
		)
		(fill no)
		(layer "In3.Cu")
	)
	(gr_circle
		(center 213.978236 -127.625856)
		(end 214.867236 -127.625856)
		(stroke
			(width 0.2)
			(type default)
		)
		(fill no)
		(layer "In3.Cu")
	)
	(gr_circle
		(center 214.696802 -132.94614)
		(end 215.585802 -132.94614)
		(stroke
			(width 0.2)
			(type default)
		)
		(fill no)
		(layer "In3.Cu")
	)
	(gr_circle
		(center 214.696802 -132.18414)
		(end 215.585802 -132.18414)
		(stroke
			(width 0.2)
			(type default)
		)
		(fill no)
		(layer "In3.Cu")
	)
	(gr_circle
		(center 214.696802 -131.42214)
		(end 215.585802 -131.42214)
		(stroke
			(width 0.2)
			(type default)
		)
		(fill no)
		(layer "In3.Cu")
	)
	(gr_circle
		(center 214.696802 -130.66014)
		(end 215.585802 -130.66014)
		(stroke
			(width 0.2)
			(type default)
		)
		(fill no)
		(layer "In3.Cu")
	)
	(gr_circle
		(center 214.696802 -129.89814)
		(end 215.585802 -129.89814)
		(stroke
			(width 0.2)
			(type default)
		)
		(fill no)
		(layer "In3.Cu")
	)
	(gr_circle
		(center 214.696802 -129.13614)
		(end 215.585802 -129.13614)
		(stroke
			(width 0.2)
			(type default)
		)
		(fill no)
		(layer "In3.Cu")
	)
	(gr_circle
		(center 214.696802 -128.37414)
		(end 215.585802 -128.37414)
		(stroke
			(width 0.2)
			(type default)
		)
		(fill no)
		(layer "In3.Cu")
	)
	(gr_circle
		(center 214.696802 -127.61214)
		(end 215.585802 -127.61214)
		(stroke
			(width 0.2)
			(type default)
		)
		(fill no)
		(layer "In3.Cu")
	)
	(gr_circle
		(center 215.23706 -98.013012)
		(end 216.12606 -98.013012)
		(stroke
			(width 0.2)
			(type default)
		)
		(fill no)
		(layer "In3.Cu")
	)
	(gr_circle
		(center 215.458802 -132.94614)
		(end 216.347802 -132.94614)
		(stroke
			(width 0.2)
			(type default)
		)
		(fill no)
		(layer "In3.Cu")
	)
	(gr_circle
		(center 215.458802 -132.18414)
		(end 216.347802 -132.18414)
		(stroke
			(width 0.2)
			(type default)
		)
		(fill no)
		(layer "In3.Cu")
	)
	(gr_circle
		(center 215.458802 -131.42214)
		(end 216.347802 -131.42214)
		(stroke
			(width 0.2)
			(type default)
		)
		(fill no)
		(layer "In3.Cu")
	)
	(gr_circle
		(center 215.458802 -130.66014)
		(end 216.347802 -130.66014)
		(stroke
			(width 0.2)
			(type default)
		)
		(fill no)
		(layer "In3.Cu")
	)
	(gr_circle
		(center 215.458802 -129.89814)
		(end 216.347802 -129.89814)
		(stroke
			(width 0.2)
			(type default)
		)
		(fill no)
		(layer "In3.Cu")
	)
	(gr_circle
		(center 215.458802 -129.13614)
		(end 216.347802 -129.13614)
		(stroke
			(width 0.2)
			(type default)
		)
		(fill no)
		(layer "In3.Cu")
	)
	(gr_circle
		(center 215.458802 -128.37414)
		(end 216.347802 -128.37414)
		(stroke
			(width 0.2)
			(type default)
		)
		(fill no)
		(layer "In3.Cu")
	)
	(gr_circle
		(center 215.458802 -127.61214)
		(end 216.347802 -127.61214)
		(stroke
			(width 0.2)
			(type default)
		)
		(fill no)
		(layer "In3.Cu")
	)
	(gr_circle
		(center 215.646 -101.346)
		(end 216.535 -101.346)
		(stroke
			(width 0.2)
			(type default)
		)
		(fill no)
		(layer "In3.Cu")
	)
	(gr_circle
		(center 215.99906 -98.013012)
		(end 216.88806 -98.013012)
		(stroke
			(width 0.2)
			(type default)
		)
		(fill no)
		(layer "In3.Cu")
	)
	(gr_circle
		(center 216.174828 -132.94614)
		(end 217.063828 -132.94614)
		(stroke
			(width 0.2)
			(type default)
		)
		(fill no)
		(layer "In3.Cu")
	)
	(gr_circle
		(center 216.174828 -132.18414)
		(end 217.063828 -132.18414)
		(stroke
			(width 0.2)
			(type default)
		)
		(fill no)
		(layer "In3.Cu")
	)
	(gr_circle
		(center 216.174828 -131.42214)
		(end 217.063828 -131.42214)
		(stroke
			(width 0.2)
			(type default)
		)
		(fill no)
		(layer "In3.Cu")
	)
	(gr_circle
		(center 216.174828 -130.66014)
		(end 217.063828 -130.66014)
		(stroke
			(width 0.2)
			(type default)
		)
		(fill no)
		(layer "In3.Cu")
	)
	(gr_circle
		(center 216.174828 -129.89814)
		(end 217.063828 -129.89814)
		(stroke
			(width 0.2)
			(type default)
		)
		(fill no)
		(layer "In3.Cu")
	)
	(gr_circle
		(center 216.174828 -129.13614)
		(end 217.063828 -129.13614)
		(stroke
			(width 0.2)
			(type default)
		)
		(fill no)
		(layer "In3.Cu")
	)
	(gr_circle
		(center 216.174828 -128.37414)
		(end 217.063828 -128.37414)
		(stroke
			(width 0.2)
			(type default)
		)
		(fill no)
		(layer "In3.Cu")
	)
	(gr_circle
		(center 216.174828 -127.61214)
		(end 217.063828 -127.61214)
		(stroke
			(width 0.2)
			(type default)
		)
		(fill no)
		(layer "In3.Cu")
	)
	(gr_circle
		(center 216.727278 -122.809762)
		(end 217.616278 -122.809762)
		(stroke
			(width 0.2)
			(type default)
		)
		(fill no)
		(layer "In3.Cu")
	)
	(gr_circle
		(center 216.727278 -122.047762)
		(end 217.616278 -122.047762)
		(stroke
			(width 0.2)
			(type default)
		)
		(fill no)
		(layer "In3.Cu")
	)
	(gr_circle
		(center 216.727278 -121.331736)
		(end 217.616278 -121.331736)
		(stroke
			(width 0.2)
			(type default)
		)
		(fill no)
		(layer "In3.Cu")
	)
	(gr_circle
		(center 216.727278 -120.569736)
		(end 217.616278 -120.569736)
		(stroke
			(width 0.2)
			(type default)
		)
		(fill no)
		(layer "In3.Cu")
	)
	(gr_circle
		(center 216.740994 -123.528328)
		(end 217.629994 -123.528328)
		(stroke
			(width 0.2)
			(type default)
		)
		(fill no)
		(layer "In3.Cu")
	)
	(gr_circle
		(center 216.819226 -105.883202)
		(end 217.708226 -105.883202)
		(stroke
			(width 0.2)
			(type default)
		)
		(fill no)
		(layer "In3.Cu")
	)
	(gr_circle
		(center 216.819226 -105.121202)
		(end 217.708226 -105.121202)
		(stroke
			(width 0.2)
			(type default)
		)
		(fill no)
		(layer "In3.Cu")
	)
	(gr_circle
		(center 216.819226 -104.418638)
		(end 217.708226 -104.418638)
		(stroke
			(width 0.2)
			(type default)
		)
		(fill no)
		(layer "In3.Cu")
	)
	(gr_circle
		(center 216.819226 -103.656638)
		(end 217.708226 -103.656638)
		(stroke
			(width 0.2)
			(type default)
		)
		(fill no)
		(layer "In3.Cu")
	)
	(gr_circle
		(center 216.819226 -102.894638)
		(end 217.708226 -102.894638)
		(stroke
			(width 0.2)
			(type default)
		)
		(fill no)
		(layer "In3.Cu")
	)
	(gr_circle
		(center 216.936828 -132.94614)
		(end 217.825828 -132.94614)
		(stroke
			(width 0.2)
			(type default)
		)
		(fill no)
		(layer "In3.Cu")
	)
	(gr_circle
		(center 216.936828 -132.18414)
		(end 217.825828 -132.18414)
		(stroke
			(width 0.2)
			(type default)
		)
		(fill no)
		(layer "In3.Cu")
	)
	(gr_circle
		(center 216.936828 -131.42214)
		(end 217.825828 -131.42214)
		(stroke
			(width 0.2)
			(type default)
		)
		(fill no)
		(layer "In3.Cu")
	)
	(gr_circle
		(center 216.936828 -130.66014)
		(end 217.825828 -130.66014)
		(stroke
			(width 0.2)
			(type default)
		)
		(fill no)
		(layer "In3.Cu")
	)
	(gr_circle
		(center 216.936828 -129.89814)
		(end 217.825828 -129.89814)
		(stroke
			(width 0.2)
			(type default)
		)
		(fill no)
		(layer "In3.Cu")
	)
	(gr_circle
		(center 216.936828 -129.13614)
		(end 217.825828 -129.13614)
		(stroke
			(width 0.2)
			(type default)
		)
		(fill no)
		(layer "In3.Cu")
	)
	(gr_circle
		(center 216.936828 -128.37414)
		(end 217.825828 -128.37414)
		(stroke
			(width 0.2)
			(type default)
		)
		(fill no)
		(layer "In3.Cu")
	)
	(gr_circle
		(center 216.936828 -127.61214)
		(end 217.825828 -127.61214)
		(stroke
			(width 0.2)
			(type default)
		)
		(fill no)
		(layer "In3.Cu")
	)
	(gr_circle
		(center 217.488262 -98.013012)
		(end 218.377262 -98.013012)
		(stroke
			(width 0.2)
			(type default)
		)
		(fill no)
		(layer "In3.Cu")
	)
	(gr_circle
		(center 217.489278 -122.809762)
		(end 218.378278 -122.809762)
		(stroke
			(width 0.2)
			(type default)
		)
		(fill no)
		(layer "In3.Cu")
	)
	(gr_circle
		(center 217.489278 -122.047762)
		(end 218.378278 -122.047762)
		(stroke
			(width 0.2)
			(type default)
		)
		(fill no)
		(layer "In3.Cu")
	)
	(gr_circle
		(center 217.489278 -121.331736)
		(end 218.378278 -121.331736)
		(stroke
			(width 0.2)
			(type default)
		)
		(fill no)
		(layer "In3.Cu")
	)
	(gr_circle
		(center 217.489278 -120.569736)
		(end 218.378278 -120.569736)
		(stroke
			(width 0.2)
			(type default)
		)
		(fill no)
		(layer "In3.Cu")
	)
	(gr_circle
		(center 217.502994 -123.528328)
		(end 218.391994 -123.528328)
		(stroke
			(width 0.2)
			(type default)
		)
		(fill no)
		(layer "In3.Cu")
	)
	(gr_circle
		(center 217.510868 -105.896664)
		(end 218.399868 -105.896664)
		(stroke
			(width 0.2)
			(type default)
		)
		(fill no)
		(layer "In3.Cu")
	)
	(gr_circle
		(center 217.510868 -105.134664)
		(end 218.399868 -105.134664)
		(stroke
			(width 0.2)
			(type default)
		)
		(fill no)
		(layer "In3.Cu")
	)
	(gr_circle
		(center 217.510868 -104.4321)
		(end 218.399868 -104.4321)
		(stroke
			(width 0.2)
			(type default)
		)
		(fill no)
		(layer "In3.Cu")
	)
	(gr_circle
		(center 217.510868 -103.6701)
		(end 218.399868 -103.6701)
		(stroke
			(width 0.2)
			(type default)
		)
		(fill no)
		(layer "In3.Cu")
	)
	(gr_circle
		(center 217.510868 -102.9081)
		(end 218.399868 -102.9081)
		(stroke
			(width 0.2)
			(type default)
		)
		(fill no)
		(layer "In3.Cu")
	)
	(gr_circle
		(center 218.250262 -98.013012)
		(end 219.139262 -98.013012)
		(stroke
			(width 0.2)
			(type default)
		)
		(fill no)
		(layer "In3.Cu")
	)
	(gr_circle
		(center 218.251278 -122.809762)
		(end 219.140278 -122.809762)
		(stroke
			(width 0.2)
			(type default)
		)
		(fill no)
		(layer "In3.Cu")
	)
	(gr_circle
		(center 218.251278 -122.047762)
		(end 219.140278 -122.047762)
		(stroke
			(width 0.2)
			(type default)
		)
		(fill no)
		(layer "In3.Cu")
	)
	(gr_circle
		(center 218.251278 -121.331736)
		(end 219.140278 -121.331736)
		(stroke
			(width 0.2)
			(type default)
		)
		(fill no)
		(layer "In3.Cu")
	)
	(gr_circle
		(center 218.251278 -120.569736)
		(end 219.140278 -120.569736)
		(stroke
			(width 0.2)
			(type default)
		)
		(fill no)
		(layer "In3.Cu")
	)
	(gr_circle
		(center 218.264994 -123.528328)
		(end 219.153994 -123.528328)
		(stroke
			(width 0.2)
			(type default)
		)
		(fill no)
		(layer "In3.Cu")
	)
	(gr_circle
		(center 218.272868 -105.896664)
		(end 219.161868 -105.896664)
		(stroke
			(width 0.2)
			(type default)
		)
		(fill no)
		(layer "In3.Cu")
	)
	(gr_circle
		(center 218.272868 -105.134664)
		(end 219.161868 -105.134664)
		(stroke
			(width 0.2)
			(type default)
		)
		(fill no)
		(layer "In3.Cu")
	)
	(gr_circle
		(center 218.272868 -104.4321)
		(end 219.161868 -104.4321)
		(stroke
			(width 0.2)
			(type default)
		)
		(fill no)
		(layer "In3.Cu")
	)
	(gr_circle
		(center 218.272868 -103.6701)
		(end 219.161868 -103.6701)
		(stroke
			(width 0.2)
			(type default)
		)
		(fill no)
		(layer "In3.Cu")
	)
	(gr_circle
		(center 218.272868 -102.9081)
		(end 219.161868 -102.9081)
		(stroke
			(width 0.2)
			(type default)
		)
		(fill no)
		(layer "In3.Cu")
	)
	(gr_circle
		(center 219.013278 -122.809762)
		(end 219.902278 -122.809762)
		(stroke
			(width 0.2)
			(type default)
		)
		(fill no)
		(layer "In3.Cu")
	)
	(gr_circle
		(center 219.013278 -122.047762)
		(end 219.902278 -122.047762)
		(stroke
			(width 0.2)
			(type default)
		)
		(fill no)
		(layer "In3.Cu")
	)
	(gr_circle
		(center 219.013278 -121.331736)
		(end 219.902278 -121.331736)
		(stroke
			(width 0.2)
			(type default)
		)
		(fill no)
		(layer "In3.Cu")
	)
	(gr_circle
		(center 219.013278 -120.569736)
		(end 219.902278 -120.569736)
		(stroke
			(width 0.2)
			(type default)
		)
		(fill no)
		(layer "In3.Cu")
	)
	(gr_circle
		(center 219.026994 -123.528328)
		(end 219.915994 -123.528328)
		(stroke
			(width 0.2)
			(type default)
		)
		(fill no)
		(layer "In3.Cu")
	)
	(gr_circle
		(center 219.034868 -105.896664)
		(end 219.923868 -105.896664)
		(stroke
			(width 0.2)
			(type default)
		)
		(fill no)
		(layer "In3.Cu")
	)
	(gr_circle
		(center 219.034868 -105.134664)
		(end 219.923868 -105.134664)
		(stroke
			(width 0.2)
			(type default)
		)
		(fill no)
		(layer "In3.Cu")
	)
	(gr_circle
		(center 219.034868 -104.4321)
		(end 219.923868 -104.4321)
		(stroke
			(width 0.2)
			(type default)
		)
		(fill no)
		(layer "In3.Cu")
	)
	(gr_circle
		(center 219.034868 -103.6701)
		(end 219.923868 -103.6701)
		(stroke
			(width 0.2)
			(type default)
		)
		(fill no)
		(layer "In3.Cu")
	)
	(gr_circle
		(center 219.034868 -102.9081)
		(end 219.923868 -102.9081)
		(stroke
			(width 0.2)
			(type default)
		)
		(fill no)
		(layer "In3.Cu")
	)
	(gr_circle
		(center 219.775278 -122.809762)
		(end 220.664278 -122.809762)
		(stroke
			(width 0.2)
			(type default)
		)
		(fill no)
		(layer "In3.Cu")
	)
	(gr_circle
		(center 219.775278 -122.047762)
		(end 220.664278 -122.047762)
		(stroke
			(width 0.2)
			(type default)
		)
		(fill no)
		(layer "In3.Cu")
	)
	(gr_circle
		(center 219.775278 -121.331736)
		(end 220.664278 -121.331736)
		(stroke
			(width 0.2)
			(type default)
		)
		(fill no)
		(layer "In3.Cu")
	)
	(gr_circle
		(center 219.775278 -120.569736)
		(end 220.664278 -120.569736)
		(stroke
			(width 0.2)
			(type default)
		)
		(fill no)
		(layer "In3.Cu")
	)
	(gr_circle
		(center 219.788994 -123.528328)
		(end 220.677994 -123.528328)
		(stroke
			(width 0.2)
			(type default)
		)
		(fill no)
		(layer "In3.Cu")
	)
	(gr_circle
		(center 219.796868 -105.896664)
		(end 220.685868 -105.896664)
		(stroke
			(width 0.2)
			(type default)
		)
		(fill no)
		(layer "In3.Cu")
	)
	(gr_circle
		(center 219.796868 -105.134664)
		(end 220.685868 -105.134664)
		(stroke
			(width 0.2)
			(type default)
		)
		(fill no)
		(layer "In3.Cu")
	)
	(gr_circle
		(center 219.796868 -104.4321)
		(end 220.685868 -104.4321)
		(stroke
			(width 0.2)
			(type default)
		)
		(fill no)
		(layer "In3.Cu")
	)
	(gr_circle
		(center 219.796868 -103.6701)
		(end 220.685868 -103.6701)
		(stroke
			(width 0.2)
			(type default)
		)
		(fill no)
		(layer "In3.Cu")
	)
	(gr_circle
		(center 219.796868 -102.9081)
		(end 220.685868 -102.9081)
		(stroke
			(width 0.2)
			(type default)
		)
		(fill no)
		(layer "In3.Cu")
	)
	(gr_circle
		(center 219.847668 -97.985834)
		(end 220.736668 -97.985834)
		(stroke
			(width 0.2)
			(type default)
		)
		(fill no)
		(layer "In3.Cu")
	)
	(gr_circle
		(center 220.537278 -122.809762)
		(end 221.426278 -122.809762)
		(stroke
			(width 0.2)
			(type default)
		)
		(fill no)
		(layer "In3.Cu")
	)
	(gr_circle
		(center 220.537278 -122.047762)
		(end 221.426278 -122.047762)
		(stroke
			(width 0.2)
			(type default)
		)
		(fill no)
		(layer "In3.Cu")
	)
	(gr_circle
		(center 220.537278 -121.331736)
		(end 221.426278 -121.331736)
		(stroke
			(width 0.2)
			(type default)
		)
		(fill no)
		(layer "In3.Cu")
	)
	(gr_circle
		(center 220.537278 -120.569736)
		(end 221.426278 -120.569736)
		(stroke
			(width 0.2)
			(type default)
		)
		(fill no)
		(layer "In3.Cu")
	)
	(gr_circle
		(center 220.550994 -123.528328)
		(end 221.439994 -123.528328)
		(stroke
			(width 0.2)
			(type default)
		)
		(fill no)
		(layer "In3.Cu")
	)
	(gr_circle
		(center 220.558868 -105.896664)
		(end 221.447868 -105.896664)
		(stroke
			(width 0.2)
			(type default)
		)
		(fill no)
		(layer "In3.Cu")
	)
	(gr_circle
		(center 220.558868 -105.134664)
		(end 221.447868 -105.134664)
		(stroke
			(width 0.2)
			(type default)
		)
		(fill no)
		(layer "In3.Cu")
	)
	(gr_circle
		(center 220.558868 -104.4321)
		(end 221.447868 -104.4321)
		(stroke
			(width 0.2)
			(type default)
		)
		(fill no)
		(layer "In3.Cu")
	)
	(gr_circle
		(center 220.558868 -103.6701)
		(end 221.447868 -103.6701)
		(stroke
			(width 0.2)
			(type default)
		)
		(fill no)
		(layer "In3.Cu")
	)
	(gr_circle
		(center 220.558868 -102.9081)
		(end 221.447868 -102.9081)
		(stroke
			(width 0.2)
			(type default)
		)
		(fill no)
		(layer "In3.Cu")
	)
	(gr_circle
		(center 220.609668 -97.985834)
		(end 221.498668 -97.985834)
		(stroke
			(width 0.2)
			(type default)
		)
		(fill no)
		(layer "In3.Cu")
	)
	(gr_circle
		(center 221.299278 -122.809762)
		(end 222.188278 -122.809762)
		(stroke
			(width 0.2)
			(type default)
		)
		(fill no)
		(layer "In3.Cu")
	)
	(gr_circle
		(center 221.299278 -122.047762)
		(end 222.188278 -122.047762)
		(stroke
			(width 0.2)
			(type default)
		)
		(fill no)
		(layer "In3.Cu")
	)
	(gr_circle
		(center 221.299278 -121.331736)
		(end 222.188278 -121.331736)
		(stroke
			(width 0.2)
			(type default)
		)
		(fill no)
		(layer "In3.Cu")
	)
	(gr_circle
		(center 221.299278 -120.569736)
		(end 222.188278 -120.569736)
		(stroke
			(width 0.2)
			(type default)
		)
		(fill no)
		(layer "In3.Cu")
	)
	(gr_circle
		(center 221.312994 -123.528328)
		(end 222.201994 -123.528328)
		(stroke
			(width 0.2)
			(type default)
		)
		(fill no)
		(layer "In3.Cu")
	)
	(gr_circle
		(center 221.320868 -105.896664)
		(end 222.209868 -105.896664)
		(stroke
			(width 0.2)
			(type default)
		)
		(fill no)
		(layer "In3.Cu")
	)
	(gr_circle
		(center 221.320868 -105.134664)
		(end 222.209868 -105.134664)
		(stroke
			(width 0.2)
			(type default)
		)
		(fill no)
		(layer "In3.Cu")
	)
	(gr_circle
		(center 221.320868 -104.4321)
		(end 222.209868 -104.4321)
		(stroke
			(width 0.2)
			(type default)
		)
		(fill no)
		(layer "In3.Cu")
	)
	(gr_circle
		(center 221.320868 -103.6701)
		(end 222.209868 -103.6701)
		(stroke
			(width 0.2)
			(type default)
		)
		(fill no)
		(layer "In3.Cu")
	)
	(gr_circle
		(center 221.320868 -102.9081)
		(end 222.209868 -102.9081)
		(stroke
			(width 0.2)
			(type default)
		)
		(fill no)
		(layer "In3.Cu")
	)
	(gr_circle
		(center 222.039688 -105.882948)
		(end 222.928688 -105.882948)
		(stroke
			(width 0.2)
			(type default)
		)
		(fill no)
		(layer "In3.Cu")
	)
	(gr_circle
		(center 222.039688 -105.120948)
		(end 222.928688 -105.120948)
		(stroke
			(width 0.2)
			(type default)
		)
		(fill no)
		(layer "In3.Cu")
	)
	(gr_circle
		(center 222.039688 -104.418384)
		(end 222.928688 -104.418384)
		(stroke
			(width 0.2)
			(type default)
		)
		(fill no)
		(layer "In3.Cu")
	)
	(gr_circle
		(center 222.039688 -103.656384)
		(end 222.928688 -103.656384)
		(stroke
			(width 0.2)
			(type default)
		)
		(fill no)
		(layer "In3.Cu")
	)
	(gr_circle
		(center 222.039688 -102.894384)
		(end 222.928688 -102.894384)
		(stroke
			(width 0.2)
			(type default)
		)
		(fill no)
		(layer "In3.Cu")
	)
	(gr_circle
		(center 222.061278 -122.809762)
		(end 222.950278 -122.809762)
		(stroke
			(width 0.2)
			(type default)
		)
		(fill no)
		(layer "In3.Cu")
	)
	(gr_circle
		(center 222.061278 -122.047762)
		(end 222.950278 -122.047762)
		(stroke
			(width 0.2)
			(type default)
		)
		(fill no)
		(layer "In3.Cu")
	)
	(gr_circle
		(center 222.061278 -121.331736)
		(end 222.950278 -121.331736)
		(stroke
			(width 0.2)
			(type default)
		)
		(fill no)
		(layer "In3.Cu")
	)
	(gr_circle
		(center 222.061278 -120.569736)
		(end 222.950278 -120.569736)
		(stroke
			(width 0.2)
			(type default)
		)
		(fill no)
		(layer "In3.Cu")
	)
	(gr_circle
		(center 222.074994 -123.528328)
		(end 222.963994 -123.528328)
		(stroke
			(width 0.2)
			(type default)
		)
		(fill no)
		(layer "In3.Cu")
	)
	(gr_circle
		(center 222.09887 -97.985834)
		(end 222.98787 -97.985834)
		(stroke
			(width 0.2)
			(type default)
		)
		(fill no)
		(layer "In3.Cu")
	)
	(gr_circle
		(center 222.86087 -97.985834)
		(end 223.74987 -97.985834)
		(stroke
			(width 0.2)
			(type default)
		)
		(fill no)
		(layer "In3.Cu")
	)
	(gr_circle
		(center 224.593912 -97.985834)
		(end 225.482912 -97.985834)
		(stroke
			(width 0.2)
			(type default)
		)
		(fill no)
		(layer "In3.Cu")
	)
	(gr_circle
		(center 225.355912 -97.985834)
		(end 226.244912 -97.985834)
		(stroke
			(width 0.2)
			(type default)
		)
		(fill no)
		(layer "In3.Cu")
	)
	(gr_circle
		(center 226.845114 -97.985834)
		(end 227.734114 -97.985834)
		(stroke
			(width 0.2)
			(type default)
		)
		(fill no)
		(layer "In3.Cu")
	)
	(gr_circle
		(center 227.607114 -97.985834)
		(end 228.496114 -97.985834)
		(stroke
			(width 0.2)
			(type default)
		)
		(fill no)
		(layer "In3.Cu")
	)
	(gr_circle
		(center 229.530148 -98.012758)
		(end 230.419148 -98.012758)
		(stroke
			(width 0.2)
			(type default)
		)
		(fill no)
		(layer "In3.Cu")
	)
	(gr_circle
		(center 230.292148 -98.012758)
		(end 231.181148 -98.012758)
		(stroke
			(width 0.2)
			(type default)
		)
		(fill no)
		(layer "In3.Cu")
	)
	(gr_circle
		(center 231.591104 -131.110736)
		(end 232.480104 -131.110736)
		(stroke
			(width 0.2)
			(type default)
		)
		(fill no)
		(layer "In3.Cu")
	)
	(gr_circle
		(center 231.591104 -130.348736)
		(end 232.480104 -130.348736)
		(stroke
			(width 0.2)
			(type default)
		)
		(fill no)
		(layer "In3.Cu")
	)
	(gr_circle
		(center 231.591104 -129.586736)
		(end 232.480104 -129.586736)
		(stroke
			(width 0.2)
			(type default)
		)
		(fill no)
		(layer "In3.Cu")
	)
	(gr_circle
		(center 231.591104 -128.824736)
		(end 232.480104 -128.824736)
		(stroke
			(width 0.2)
			(type default)
		)
		(fill no)
		(layer "In3.Cu")
	)
	(gr_circle
		(center 231.591104 -128.062736)
		(end 232.480104 -128.062736)
		(stroke
			(width 0.2)
			(type default)
		)
		(fill no)
		(layer "In3.Cu")
	)
	(gr_circle
		(center 231.591104 -127.300736)
		(end 232.480104 -127.300736)
		(stroke
			(width 0.2)
			(type default)
		)
		(fill no)
		(layer "In3.Cu")
	)
	(gr_circle
		(center 231.604566 -126.609094)
		(end 232.493566 -126.609094)
		(stroke
			(width 0.2)
			(type default)
		)
		(fill no)
		(layer "In3.Cu")
	)
	(gr_circle
		(center 231.60482 -131.829556)
		(end 232.49382 -131.829556)
		(stroke
			(width 0.2)
			(type default)
		)
		(fill no)
		(layer "In3.Cu")
	)
	(gr_circle
		(center 231.78135 -98.012758)
		(end 232.67035 -98.012758)
		(stroke
			(width 0.2)
			(type default)
		)
		(fill no)
		(layer "In3.Cu")
	)
	(gr_circle
		(center 232.353104 -131.110736)
		(end 233.242104 -131.110736)
		(stroke
			(width 0.2)
			(type default)
		)
		(fill no)
		(layer "In3.Cu")
	)
	(gr_circle
		(center 232.353104 -130.348736)
		(end 233.242104 -130.348736)
		(stroke
			(width 0.2)
			(type default)
		)
		(fill no)
		(layer "In3.Cu")
	)
	(gr_circle
		(center 232.353104 -129.586736)
		(end 233.242104 -129.586736)
		(stroke
			(width 0.2)
			(type default)
		)
		(fill no)
		(layer "In3.Cu")
	)
	(gr_circle
		(center 232.353104 -128.824736)
		(end 233.242104 -128.824736)
		(stroke
			(width 0.2)
			(type default)
		)
		(fill no)
		(layer "In3.Cu")
	)
	(gr_circle
		(center 232.353104 -128.062736)
		(end 233.242104 -128.062736)
		(stroke
			(width 0.2)
			(type default)
		)
		(fill no)
		(layer "In3.Cu")
	)
	(gr_circle
		(center 232.353104 -127.300736)
		(end 233.242104 -127.300736)
		(stroke
			(width 0.2)
			(type default)
		)
		(fill no)
		(layer "In3.Cu")
	)
	(gr_circle
		(center 232.366566 -126.609094)
		(end 233.255566 -126.609094)
		(stroke
			(width 0.2)
			(type default)
		)
		(fill no)
		(layer "In3.Cu")
	)
	(gr_circle
		(center 232.36682 -131.829556)
		(end 233.25582 -131.829556)
		(stroke
			(width 0.2)
			(type default)
		)
		(fill no)
		(layer "In3.Cu")
	)
	(gr_circle
		(center 232.54335 -98.012758)
		(end 233.43235 -98.012758)
		(stroke
			(width 0.2)
			(type default)
		)
		(fill no)
		(layer "In3.Cu")
	)
	(gr_circle
		(center 233.055668 -131.110736)
		(end 233.944668 -131.110736)
		(stroke
			(width 0.2)
			(type default)
		)
		(fill no)
		(layer "In3.Cu")
	)
	(gr_circle
		(center 233.055668 -130.348736)
		(end 233.944668 -130.348736)
		(stroke
			(width 0.2)
			(type default)
		)
		(fill no)
		(layer "In3.Cu")
	)
	(gr_circle
		(center 233.055668 -129.586736)
		(end 233.944668 -129.586736)
		(stroke
			(width 0.2)
			(type default)
		)
		(fill no)
		(layer "In3.Cu")
	)
	(gr_circle
		(center 233.055668 -128.824736)
		(end 233.944668 -128.824736)
		(stroke
			(width 0.2)
			(type default)
		)
		(fill no)
		(layer "In3.Cu")
	)
	(gr_circle
		(center 233.055668 -128.062736)
		(end 233.944668 -128.062736)
		(stroke
			(width 0.2)
			(type default)
		)
		(fill no)
		(layer "In3.Cu")
	)
	(gr_circle
		(center 233.055668 -127.300736)
		(end 233.944668 -127.300736)
		(stroke
			(width 0.2)
			(type default)
		)
		(fill no)
		(layer "In3.Cu")
	)
	(gr_circle
		(center 233.06913 -126.609094)
		(end 233.95813 -126.609094)
		(stroke
			(width 0.2)
			(type default)
		)
		(fill no)
		(layer "In3.Cu")
	)
	(gr_circle
		(center 233.069384 -131.829556)
		(end 233.958384 -131.829556)
		(stroke
			(width 0.2)
			(type default)
		)
		(fill no)
		(layer "In3.Cu")
	)
	(gr_circle
		(center 233.817668 -131.110736)
		(end 234.706668 -131.110736)
		(stroke
			(width 0.2)
			(type default)
		)
		(fill no)
		(layer "In3.Cu")
	)
	(gr_circle
		(center 233.817668 -130.348736)
		(end 234.706668 -130.348736)
		(stroke
			(width 0.2)
			(type default)
		)
		(fill no)
		(layer "In3.Cu")
	)
	(gr_circle
		(center 233.817668 -129.586736)
		(end 234.706668 -129.586736)
		(stroke
			(width 0.2)
			(type default)
		)
		(fill no)
		(layer "In3.Cu")
	)
	(gr_circle
		(center 233.817668 -128.824736)
		(end 234.706668 -128.824736)
		(stroke
			(width 0.2)
			(type default)
		)
		(fill no)
		(layer "In3.Cu")
	)
	(gr_circle
		(center 233.817668 -128.062736)
		(end 234.706668 -128.062736)
		(stroke
			(width 0.2)
			(type default)
		)
		(fill no)
		(layer "In3.Cu")
	)
	(gr_circle
		(center 233.817668 -127.300736)
		(end 234.706668 -127.300736)
		(stroke
			(width 0.2)
			(type default)
		)
		(fill no)
		(layer "In3.Cu")
	)
	(gr_circle
		(center 233.83113 -126.609094)
		(end 234.72013 -126.609094)
		(stroke
			(width 0.2)
			(type default)
		)
		(fill no)
		(layer "In3.Cu")
	)
	(gr_circle
		(center 233.831384 -131.829556)
		(end 234.720384 -131.829556)
		(stroke
			(width 0.2)
			(type default)
		)
		(fill no)
		(layer "In3.Cu")
	)
	(gr_circle
		(center 234.303316 -97.985834)
		(end 235.192316 -97.985834)
		(stroke
			(width 0.2)
			(type default)
		)
		(fill no)
		(layer "In3.Cu")
	)
	(gr_circle
		(center 234.579668 -131.110736)
		(end 235.468668 -131.110736)
		(stroke
			(width 0.2)
			(type default)
		)
		(fill no)
		(layer "In3.Cu")
	)
	(gr_circle
		(center 234.579668 -130.348736)
		(end 235.468668 -130.348736)
		(stroke
			(width 0.2)
			(type default)
		)
		(fill no)
		(layer "In3.Cu")
	)
	(gr_circle
		(center 234.579668 -129.586736)
		(end 235.468668 -129.586736)
		(stroke
			(width 0.2)
			(type default)
		)
		(fill no)
		(layer "In3.Cu")
	)
	(gr_circle
		(center 234.579668 -128.824736)
		(end 235.468668 -128.824736)
		(stroke
			(width 0.2)
			(type default)
		)
		(fill no)
		(layer "In3.Cu")
	)
	(gr_circle
		(center 234.579668 -128.062736)
		(end 235.468668 -128.062736)
		(stroke
			(width 0.2)
			(type default)
		)
		(fill no)
		(layer "In3.Cu")
	)
	(gr_circle
		(center 234.579668 -127.300736)
		(end 235.468668 -127.300736)
		(stroke
			(width 0.2)
			(type default)
		)
		(fill no)
		(layer "In3.Cu")
	)
	(gr_circle
		(center 234.59313 -126.609094)
		(end 235.48213 -126.609094)
		(stroke
			(width 0.2)
			(type default)
		)
		(fill no)
		(layer "In3.Cu")
	)
	(gr_circle
		(center 234.593384 -131.829556)
		(end 235.482384 -131.829556)
		(stroke
			(width 0.2)
			(type default)
		)
		(fill no)
		(layer "In3.Cu")
	)
	(gr_circle
		(center 235.065316 -97.985834)
		(end 235.954316 -97.985834)
		(stroke
			(width 0.2)
			(type default)
		)
		(fill no)
		(layer "In3.Cu")
	)
	(gr_circle
		(center 236.554518 -97.985834)
		(end 237.443518 -97.985834)
		(stroke
			(width 0.2)
			(type default)
		)
		(fill no)
		(layer "In3.Cu")
	)
	(gr_circle
		(center 237.316518 -97.985834)
		(end 238.205518 -97.985834)
		(stroke
			(width 0.2)
			(type default)
		)
		(fill no)
		(layer "In3.Cu")
	)
	(gr_circle
		(center 239.076738 -98.012758)
		(end 239.965738 -98.012758)
		(stroke
			(width 0.2)
			(type default)
		)
		(fill no)
		(layer "In3.Cu")
	)
	(gr_circle
		(center 239.838738 -98.012758)
		(end 240.727738 -98.012758)
		(stroke
			(width 0.2)
			(type default)
		)
		(fill no)
		(layer "In3.Cu")
	)
	(gr_circle
		(center 241.32794 -98.012758)
		(end 242.21694 -98.012758)
		(stroke
			(width 0.2)
			(type default)
		)
		(fill no)
		(layer "In3.Cu")
	)
	(gr_circle
		(center 242.08994 -98.012758)
		(end 242.97894 -98.012758)
		(stroke
			(width 0.2)
			(type default)
		)
		(fill no)
		(layer "In3.Cu")
	)
	(gr_circle
		(center 258.219956 -50.232818)
		(end 259.108956 -50.232818)
		(stroke
			(width 0.2)
			(type default)
		)
		(fill no)
		(layer "In3.Cu")
	)
	(gr_circle
		(center 258.219956 -48.327818)
		(end 259.108956 -48.327818)
		(stroke
			(width 0.2)
			(type default)
		)
		(fill no)
		(layer "In3.Cu")
	)
	(gr_circle
		(center 258.219956 -47.565818)
		(end 259.108956 -47.565818)
		(stroke
			(width 0.2)
			(type default)
		)
		(fill no)
		(layer "In3.Cu")
	)
	(gr_circle
		(center 258.530598 -39.18712)
		(end 259.419598 -39.18712)
		(stroke
			(width 0.2)
			(type default)
		)
		(fill no)
		(layer "In3.Cu")
	)
	(gr_circle
		(center 258.548886 -38.461696)
		(end 259.437886 -38.461696)
		(stroke
			(width 0.2)
			(type default)
		)
		(fill no)
		(layer "In3.Cu")
	)
	(gr_circle
		(center 258.83362 -40.72382)
		(end 259.72262 -40.72382)
		(stroke
			(width 0.2)
			(type default)
		)
		(fill no)
		(layer "In3.Cu")
	)
	(gr_circle
		(center 258.83616 -39.95674)
		(end 259.72516 -39.95674)
		(stroke
			(width 0.2)
			(type default)
		)
		(fill no)
		(layer "In3.Cu")
	)
	(gr_circle
		(center 259.0038 -42.3164)
		(end 259.8928 -42.3164)
		(stroke
			(width 0.2)
			(type default)
		)
		(fill no)
		(layer "In3.Cu")
	)
	(gr_circle
		(center 259.588 -43.4848)
		(end 260.477 -43.4848)
		(stroke
			(width 0.2)
			(type default)
		)
		(fill no)
		(layer "In3.Cu")
	)
	(gr_circle
		(center 259.630672 -41.092882)
		(end 260.519672 -41.092882)
		(stroke
			(width 0.2)
			(type default)
		)
		(fill no)
		(layer "In3.Cu")
	)
	(gr_circle
		(center 259.630672 -39.592758)
		(end 260.519672 -39.592758)
		(stroke
			(width 0.2)
			(type default)
		)
		(fill no)
		(layer "In3.Cu")
	)
	(gr_circle
		(center 260.182106 -37.2364)
		(end 261.071106 -37.2364)
		(stroke
			(width 0.2)
			(type default)
		)
		(fill no)
		(layer "In3.Cu")
	)
	(gr_circle
		(center 269.24 -125.857)
		(end 270.129 -125.857)
		(stroke
			(width 0.2)
			(type default)
		)
		(fill no)
		(layer "In3.Cu")
	)
	(gr_circle
		(center 269.24 -125.095)
		(end 270.129 -125.095)
		(stroke
			(width 0.2)
			(type default)
		)
		(fill no)
		(layer "In3.Cu")
	)
	(gr_circle
		(center 269.24 -124.333)
		(end 270.129 -124.333)
		(stroke
			(width 0.2)
			(type default)
		)
		(fill no)
		(layer "In3.Cu")
	)
	(gr_circle
		(center 269.24 -123.571)
		(end 270.129 -123.571)
		(stroke
			(width 0.2)
			(type default)
		)
		(fill no)
		(layer "In3.Cu")
	)
	(gr_circle
		(center 269.24 -122.809)
		(end 270.129 -122.809)
		(stroke
			(width 0.2)
			(type default)
		)
		(fill no)
		(layer "In3.Cu")
	)
	(gr_circle
		(center 269.24 -122.047)
		(end 270.129 -122.047)
		(stroke
			(width 0.2)
			(type default)
		)
		(fill no)
		(layer "In3.Cu")
	)
	(gr_circle
		(center 269.24 -113.792)
		(end 270.129 -113.792)
		(stroke
			(width 0.2)
			(type default)
		)
		(fill no)
		(layer "In3.Cu")
	)
	(gr_circle
		(center 269.24 -113.03)
		(end 270.129 -113.03)
		(stroke
			(width 0.2)
			(type default)
		)
		(fill no)
		(layer "In3.Cu")
	)
	(gr_circle
		(center 269.24 -112.268)
		(end 270.129 -112.268)
		(stroke
			(width 0.2)
			(type default)
		)
		(fill no)
		(layer "In3.Cu")
	)
	(gr_circle
		(center 269.24 -111.506)
		(end 270.129 -111.506)
		(stroke
			(width 0.2)
			(type default)
		)
		(fill no)
		(layer "In3.Cu")
	)
	(gr_circle
		(center 269.24 -110.744)
		(end 270.129 -110.744)
		(stroke
			(width 0.2)
			(type default)
		)
		(fill no)
		(layer "In3.Cu")
	)
	(gr_circle
		(center 269.24 -109.982)
		(end 270.129 -109.982)
		(stroke
			(width 0.2)
			(type default)
		)
		(fill no)
		(layer "In3.Cu")
	)
	(gr_circle
		(center 269.24 -101.727)
		(end 270.129 -101.727)
		(stroke
			(width 0.2)
			(type default)
		)
		(fill no)
		(layer "In3.Cu")
	)
	(gr_circle
		(center 269.24 -100.965)
		(end 270.129 -100.965)
		(stroke
			(width 0.2)
			(type default)
		)
		(fill no)
		(layer "In3.Cu")
	)
	(gr_circle
		(center 269.24 -100.203)
		(end 270.129 -100.203)
		(stroke
			(width 0.2)
			(type default)
		)
		(fill no)
		(layer "In3.Cu")
	)
	(gr_circle
		(center 269.24 -99.441)
		(end 270.129 -99.441)
		(stroke
			(width 0.2)
			(type default)
		)
		(fill no)
		(layer "In3.Cu")
	)
	(gr_circle
		(center 269.24 -98.679)
		(end 270.129 -98.679)
		(stroke
			(width 0.2)
			(type default)
		)
		(fill no)
		(layer "In3.Cu")
	)
	(gr_circle
		(center 269.24 -97.917)
		(end 270.129 -97.917)
		(stroke
			(width 0.2)
			(type default)
		)
		(fill no)
		(layer "In3.Cu")
	)
	(gr_circle
		(center 269.24 -89.662)
		(end 270.129 -89.662)
		(stroke
			(width 0.2)
			(type default)
		)
		(fill no)
		(layer "In3.Cu")
	)
	(gr_circle
		(center 269.24 -88.9)
		(end 270.129 -88.9)
		(stroke
			(width 0.2)
			(type default)
		)
		(fill no)
		(layer "In3.Cu")
	)
	(gr_circle
		(center 269.24 -88.138)
		(end 270.129 -88.138)
		(stroke
			(width 0.2)
			(type default)
		)
		(fill no)
		(layer "In3.Cu")
	)
	(gr_circle
		(center 269.24 -87.376)
		(end 270.129 -87.376)
		(stroke
			(width 0.2)
			(type default)
		)
		(fill no)
		(layer "In3.Cu")
	)
	(gr_circle
		(center 269.24 -86.614)
		(end 270.129 -86.614)
		(stroke
			(width 0.2)
			(type default)
		)
		(fill no)
		(layer "In3.Cu")
	)
	(gr_circle
		(center 269.24 -85.852)
		(end 270.129 -85.852)
		(stroke
			(width 0.2)
			(type default)
		)
		(fill no)
		(layer "In3.Cu")
	)
	(gr_circle
		(center 269.24 -77.597)
		(end 270.129 -77.597)
		(stroke
			(width 0.2)
			(type default)
		)
		(fill no)
		(layer "In3.Cu")
	)
	(gr_circle
		(center 269.24 -76.835)
		(end 270.129 -76.835)
		(stroke
			(width 0.2)
			(type default)
		)
		(fill no)
		(layer "In3.Cu")
	)
	(gr_circle
		(center 269.24 -76.073)
		(end 270.129 -76.073)
		(stroke
			(width 0.2)
			(type default)
		)
		(fill no)
		(layer "In3.Cu")
	)
	(gr_circle
		(center 269.24 -75.311)
		(end 270.129 -75.311)
		(stroke
			(width 0.2)
			(type default)
		)
		(fill no)
		(layer "In3.Cu")
	)
	(gr_circle
		(center 269.24 -74.549)
		(end 270.129 -74.549)
		(stroke
			(width 0.2)
			(type default)
		)
		(fill no)
		(layer "In3.Cu")
	)
	(gr_circle
		(center 269.24 -73.787)
		(end 270.129 -73.787)
		(stroke
			(width 0.2)
			(type default)
		)
		(fill no)
		(layer "In3.Cu")
	)
	(gr_circle
		(center 269.24 -65.532)
		(end 270.129 -65.532)
		(stroke
			(width 0.2)
			(type default)
		)
		(fill no)
		(layer "In3.Cu")
	)
	(gr_circle
		(center 269.24 -64.77)
		(end 270.129 -64.77)
		(stroke
			(width 0.2)
			(type default)
		)
		(fill no)
		(layer "In3.Cu")
	)
	(gr_circle
		(center 269.24 -64.008)
		(end 270.129 -64.008)
		(stroke
			(width 0.2)
			(type default)
		)
		(fill no)
		(layer "In3.Cu")
	)
	(gr_circle
		(center 269.24 -63.246)
		(end 270.129 -63.246)
		(stroke
			(width 0.2)
			(type default)
		)
		(fill no)
		(layer "In3.Cu")
	)
	(gr_circle
		(center 269.24 -62.484)
		(end 270.129 -62.484)
		(stroke
			(width 0.2)
			(type default)
		)
		(fill no)
		(layer "In3.Cu")
	)
	(gr_circle
		(center 269.24 -61.722)
		(end 270.129 -61.722)
		(stroke
			(width 0.2)
			(type default)
		)
		(fill no)
		(layer "In3.Cu")
	)
	(gr_circle
		(center 270.002 -125.857)
		(end 270.891 -125.857)
		(stroke
			(width 0.2)
			(type default)
		)
		(fill no)
		(layer "In3.Cu")
	)
	(gr_circle
		(center 270.002 -125.095)
		(end 270.891 -125.095)
		(stroke
			(width 0.2)
			(type default)
		)
		(fill no)
		(layer "In3.Cu")
	)
	(gr_circle
		(center 270.002 -124.333)
		(end 270.891 -124.333)
		(stroke
			(width 0.2)
			(type default)
		)
		(fill no)
		(layer "In3.Cu")
	)
	(gr_circle
		(center 270.002 -123.571)
		(end 270.891 -123.571)
		(stroke
			(width 0.2)
			(type default)
		)
		(fill no)
		(layer "In3.Cu")
	)
	(gr_circle
		(center 270.002 -122.809)
		(end 270.891 -122.809)
		(stroke
			(width 0.2)
			(type default)
		)
		(fill no)
		(layer "In3.Cu")
	)
	(gr_circle
		(center 270.002 -122.047)
		(end 270.891 -122.047)
		(stroke
			(width 0.2)
			(type default)
		)
		(fill no)
		(layer "In3.Cu")
	)
	(gr_circle
		(center 270.002 -113.792)
		(end 270.891 -113.792)
		(stroke
			(width 0.2)
			(type default)
		)
		(fill no)
		(layer "In3.Cu")
	)
	(gr_circle
		(center 270.002 -113.03)
		(end 270.891 -113.03)
		(stroke
			(width 0.2)
			(type default)
		)
		(fill no)
		(layer "In3.Cu")
	)
	(gr_circle
		(center 270.002 -112.268)
		(end 270.891 -112.268)
		(stroke
			(width 0.2)
			(type default)
		)
		(fill no)
		(layer "In3.Cu")
	)
	(gr_circle
		(center 270.002 -111.506)
		(end 270.891 -111.506)
		(stroke
			(width 0.2)
			(type default)
		)
		(fill no)
		(layer "In3.Cu")
	)
	(gr_circle
		(center 270.002 -110.744)
		(end 270.891 -110.744)
		(stroke
			(width 0.2)
			(type default)
		)
		(fill no)
		(layer "In3.Cu")
	)
	(gr_circle
		(center 270.002 -109.982)
		(end 270.891 -109.982)
		(stroke
			(width 0.2)
			(type default)
		)
		(fill no)
		(layer "In3.Cu")
	)
	(gr_circle
		(center 270.002 -101.727)
		(end 270.891 -101.727)
		(stroke
			(width 0.2)
			(type default)
		)
		(fill no)
		(layer "In3.Cu")
	)
	(gr_circle
		(center 270.002 -100.965)
		(end 270.891 -100.965)
		(stroke
			(width 0.2)
			(type default)
		)
		(fill no)
		(layer "In3.Cu")
	)
	(gr_circle
		(center 270.002 -100.203)
		(end 270.891 -100.203)
		(stroke
			(width 0.2)
			(type default)
		)
		(fill no)
		(layer "In3.Cu")
	)
	(gr_circle
		(center 270.002 -99.441)
		(end 270.891 -99.441)
		(stroke
			(width 0.2)
			(type default)
		)
		(fill no)
		(layer "In3.Cu")
	)
	(gr_circle
		(center 270.002 -98.679)
		(end 270.891 -98.679)
		(stroke
			(width 0.2)
			(type default)
		)
		(fill no)
		(layer "In3.Cu")
	)
	(gr_circle
		(center 270.002 -97.917)
		(end 270.891 -97.917)
		(stroke
			(width 0.2)
			(type default)
		)
		(fill no)
		(layer "In3.Cu")
	)
	(gr_circle
		(center 270.002 -89.662)
		(end 270.891 -89.662)
		(stroke
			(width 0.2)
			(type default)
		)
		(fill no)
		(layer "In3.Cu")
	)
	(gr_circle
		(center 270.002 -88.9)
		(end 270.891 -88.9)
		(stroke
			(width 0.2)
			(type default)
		)
		(fill no)
		(layer "In3.Cu")
	)
	(gr_circle
		(center 270.002 -88.138)
		(end 270.891 -88.138)
		(stroke
			(width 0.2)
			(type default)
		)
		(fill no)
		(layer "In3.Cu")
	)
	(gr_circle
		(center 270.002 -87.376)
		(end 270.891 -87.376)
		(stroke
			(width 0.2)
			(type default)
		)
		(fill no)
		(layer "In3.Cu")
	)
	(gr_circle
		(center 270.002 -86.614)
		(end 270.891 -86.614)
		(stroke
			(width 0.2)
			(type default)
		)
		(fill no)
		(layer "In3.Cu")
	)
	(gr_circle
		(center 270.002 -85.852)
		(end 270.891 -85.852)
		(stroke
			(width 0.2)
			(type default)
		)
		(fill no)
		(layer "In3.Cu")
	)
	(gr_circle
		(center 270.002 -77.597)
		(end 270.891 -77.597)
		(stroke
			(width 0.2)
			(type default)
		)
		(fill no)
		(layer "In3.Cu")
	)
	(gr_circle
		(center 270.002 -76.835)
		(end 270.891 -76.835)
		(stroke
			(width 0.2)
			(type default)
		)
		(fill no)
		(layer "In3.Cu")
	)
	(gr_circle
		(center 270.002 -76.073)
		(end 270.891 -76.073)
		(stroke
			(width 0.2)
			(type default)
		)
		(fill no)
		(layer "In3.Cu")
	)
	(gr_circle
		(center 270.002 -75.311)
		(end 270.891 -75.311)
		(stroke
			(width 0.2)
			(type default)
		)
		(fill no)
		(layer "In3.Cu")
	)
	(gr_circle
		(center 270.002 -74.549)
		(end 270.891 -74.549)
		(stroke
			(width 0.2)
			(type default)
		)
		(fill no)
		(layer "In3.Cu")
	)
	(gr_circle
		(center 270.002 -73.787)
		(end 270.891 -73.787)
		(stroke
			(width 0.2)
			(type default)
		)
		(fill no)
		(layer "In3.Cu")
	)
	(gr_circle
		(center 270.002 -65.532)
		(end 270.891 -65.532)
		(stroke
			(width 0.2)
			(type default)
		)
		(fill no)
		(layer "In3.Cu")
	)
	(gr_circle
		(center 270.002 -64.77)
		(end 270.891 -64.77)
		(stroke
			(width 0.2)
			(type default)
		)
		(fill no)
		(layer "In3.Cu")
	)
	(gr_circle
		(center 270.002 -64.008)
		(end 270.891 -64.008)
		(stroke
			(width 0.2)
			(type default)
		)
		(fill no)
		(layer "In3.Cu")
	)
	(gr_circle
		(center 270.002 -63.246)
		(end 270.891 -63.246)
		(stroke
			(width 0.2)
			(type default)
		)
		(fill no)
		(layer "In3.Cu")
	)
	(gr_circle
		(center 270.002 -62.484)
		(end 270.891 -62.484)
		(stroke
			(width 0.2)
			(type default)
		)
		(fill no)
		(layer "In3.Cu")
	)
	(gr_circle
		(center 270.002 -61.722)
		(end 270.891 -61.722)
		(stroke
			(width 0.2)
			(type default)
		)
		(fill no)
		(layer "In3.Cu")
	)
	(gr_circle
		(center 270.764 -125.857)
		(end 271.653 -125.857)
		(stroke
			(width 0.2)
			(type default)
		)
		(fill no)
		(layer "In3.Cu")
	)
	(gr_circle
		(center 270.764 -125.095)
		(end 271.653 -125.095)
		(stroke
			(width 0.2)
			(type default)
		)
		(fill no)
		(layer "In3.Cu")
	)
	(gr_circle
		(center 270.764 -124.333)
		(end 271.653 -124.333)
		(stroke
			(width 0.2)
			(type default)
		)
		(fill no)
		(layer "In3.Cu")
	)
	(gr_circle
		(center 270.764 -123.571)
		(end 271.653 -123.571)
		(stroke
			(width 0.2)
			(type default)
		)
		(fill no)
		(layer "In3.Cu")
	)
	(gr_circle
		(center 270.764 -122.809)
		(end 271.653 -122.809)
		(stroke
			(width 0.2)
			(type default)
		)
		(fill no)
		(layer "In3.Cu")
	)
	(gr_circle
		(center 270.764 -122.047)
		(end 271.653 -122.047)
		(stroke
			(width 0.2)
			(type default)
		)
		(fill no)
		(layer "In3.Cu")
	)
	(gr_circle
		(center 270.764 -113.792)
		(end 271.653 -113.792)
		(stroke
			(width 0.2)
			(type default)
		)
		(fill no)
		(layer "In3.Cu")
	)
	(gr_circle
		(center 270.764 -113.03)
		(end 271.653 -113.03)
		(stroke
			(width 0.2)
			(type default)
		)
		(fill no)
		(layer "In3.Cu")
	)
	(gr_circle
		(center 270.764 -112.268)
		(end 271.653 -112.268)
		(stroke
			(width 0.2)
			(type default)
		)
		(fill no)
		(layer "In3.Cu")
	)
	(gr_circle
		(center 270.764 -111.506)
		(end 271.653 -111.506)
		(stroke
			(width 0.2)
			(type default)
		)
		(fill no)
		(layer "In3.Cu")
	)
	(gr_circle
		(center 270.764 -110.744)
		(end 271.653 -110.744)
		(stroke
			(width 0.2)
			(type default)
		)
		(fill no)
		(layer "In3.Cu")
	)
	(gr_circle
		(center 270.764 -109.982)
		(end 271.653 -109.982)
		(stroke
			(width 0.2)
			(type default)
		)
		(fill no)
		(layer "In3.Cu")
	)
	(gr_circle
		(center 270.764 -101.727)
		(end 271.653 -101.727)
		(stroke
			(width 0.2)
			(type default)
		)
		(fill no)
		(layer "In3.Cu")
	)
	(gr_circle
		(center 270.764 -100.965)
		(end 271.653 -100.965)
		(stroke
			(width 0.2)
			(type default)
		)
		(fill no)
		(layer "In3.Cu")
	)
	(gr_circle
		(center 270.764 -100.203)
		(end 271.653 -100.203)
		(stroke
			(width 0.2)
			(type default)
		)
		(fill no)
		(layer "In3.Cu")
	)
	(gr_circle
		(center 270.764 -99.441)
		(end 271.653 -99.441)
		(stroke
			(width 0.2)
			(type default)
		)
		(fill no)
		(layer "In3.Cu")
	)
	(gr_circle
		(center 270.764 -98.679)
		(end 271.653 -98.679)
		(stroke
			(width 0.2)
			(type default)
		)
		(fill no)
		(layer "In3.Cu")
	)
	(gr_circle
		(center 270.764 -97.917)
		(end 271.653 -97.917)
		(stroke
			(width 0.2)
			(type default)
		)
		(fill no)
		(layer "In3.Cu")
	)
	(gr_circle
		(center 270.764 -89.662)
		(end 271.653 -89.662)
		(stroke
			(width 0.2)
			(type default)
		)
		(fill no)
		(layer "In3.Cu")
	)
	(gr_circle
		(center 270.764 -88.9)
		(end 271.653 -88.9)
		(stroke
			(width 0.2)
			(type default)
		)
		(fill no)
		(layer "In3.Cu")
	)
	(gr_circle
		(center 270.764 -88.138)
		(end 271.653 -88.138)
		(stroke
			(width 0.2)
			(type default)
		)
		(fill no)
		(layer "In3.Cu")
	)
	(gr_circle
		(center 270.764 -87.376)
		(end 271.653 -87.376)
		(stroke
			(width 0.2)
			(type default)
		)
		(fill no)
		(layer "In3.Cu")
	)
	(gr_circle
		(center 270.764 -86.614)
		(end 271.653 -86.614)
		(stroke
			(width 0.2)
			(type default)
		)
		(fill no)
		(layer "In3.Cu")
	)
	(gr_circle
		(center 270.764 -85.852)
		(end 271.653 -85.852)
		(stroke
			(width 0.2)
			(type default)
		)
		(fill no)
		(layer "In3.Cu")
	)
	(gr_circle
		(center 270.764 -77.597)
		(end 271.653 -77.597)
		(stroke
			(width 0.2)
			(type default)
		)
		(fill no)
		(layer "In3.Cu")
	)
	(gr_circle
		(center 270.764 -76.835)
		(end 271.653 -76.835)
		(stroke
			(width 0.2)
			(type default)
		)
		(fill no)
		(layer "In3.Cu")
	)
	(gr_circle
		(center 270.764 -76.073)
		(end 271.653 -76.073)
		(stroke
			(width 0.2)
			(type default)
		)
		(fill no)
		(layer "In3.Cu")
	)
	(gr_circle
		(center 270.764 -75.311)
		(end 271.653 -75.311)
		(stroke
			(width 0.2)
			(type default)
		)
		(fill no)
		(layer "In3.Cu")
	)
	(gr_circle
		(center 270.764 -74.549)
		(end 271.653 -74.549)
		(stroke
			(width 0.2)
			(type default)
		)
		(fill no)
		(layer "In3.Cu")
	)
	(gr_circle
		(center 270.764 -73.787)
		(end 271.653 -73.787)
		(stroke
			(width 0.2)
			(type default)
		)
		(fill no)
		(layer "In3.Cu")
	)
	(gr_circle
		(center 270.764 -65.532)
		(end 271.653 -65.532)
		(stroke
			(width 0.2)
			(type default)
		)
		(fill no)
		(layer "In3.Cu")
	)
	(gr_circle
		(center 270.764 -64.77)
		(end 271.653 -64.77)
		(stroke
			(width 0.2)
			(type default)
		)
		(fill no)
		(layer "In3.Cu")
	)
	(gr_circle
		(center 270.764 -64.008)
		(end 271.653 -64.008)
		(stroke
			(width 0.2)
			(type default)
		)
		(fill no)
		(layer "In3.Cu")
	)
	(gr_circle
		(center 270.764 -63.246)
		(end 271.653 -63.246)
		(stroke
			(width 0.2)
			(type default)
		)
		(fill no)
		(layer "In3.Cu")
	)
	(gr_circle
		(center 270.764 -62.484)
		(end 271.653 -62.484)
		(stroke
			(width 0.2)
			(type default)
		)
		(fill no)
		(layer "In3.Cu")
	)
	(gr_circle
		(center 270.764 -61.722)
		(end 271.653 -61.722)
		(stroke
			(width 0.2)
			(type default)
		)
		(fill no)
		(layer "In3.Cu")
	)
	(gr_circle
		(center 270.891 -140.462)
		(end 271.78 -140.462)
		(stroke
			(width 0.2)
			(type default)
		)
		(fill no)
		(layer "In3.Cu")
	)
	(gr_circle
		(center 270.891 -139.7)
		(end 271.78 -139.7)
		(stroke
			(width 0.2)
			(type default)
		)
		(fill no)
		(layer "In3.Cu")
	)
	(gr_circle
		(center 270.891 -138.938)
		(end 271.78 -138.938)
		(stroke
			(width 0.2)
			(type default)
		)
		(fill no)
		(layer "In3.Cu")
	)
	(gr_circle
		(center 270.891 -138.176)
		(end 271.78 -138.176)
		(stroke
			(width 0.2)
			(type default)
		)
		(fill no)
		(layer "In3.Cu")
	)
	(gr_circle
		(center 270.891 -137.414)
		(end 271.78 -137.414)
		(stroke
			(width 0.2)
			(type default)
		)
		(fill no)
		(layer "In3.Cu")
	)
	(gr_circle
		(center 270.891 -136.652)
		(end 271.78 -136.652)
		(stroke
			(width 0.2)
			(type default)
		)
		(fill no)
		(layer "In3.Cu")
	)
	(gr_circle
		(center 271.526 -125.857)
		(end 272.415 -125.857)
		(stroke
			(width 0.2)
			(type default)
		)
		(fill no)
		(layer "In3.Cu")
	)
	(gr_circle
		(center 271.526 -125.095)
		(end 272.415 -125.095)
		(stroke
			(width 0.2)
			(type default)
		)
		(fill no)
		(layer "In3.Cu")
	)
	(gr_circle
		(center 271.526 -122.809)
		(end 272.415 -122.809)
		(stroke
			(width 0.2)
			(type default)
		)
		(fill no)
		(layer "In3.Cu")
	)
	(gr_circle
		(center 271.526 -122.047)
		(end 272.415 -122.047)
		(stroke
			(width 0.2)
			(type default)
		)
		(fill no)
		(layer "In3.Cu")
	)
	(gr_circle
		(center 271.526 -113.792)
		(end 272.415 -113.792)
		(stroke
			(width 0.2)
			(type default)
		)
		(fill no)
		(layer "In3.Cu")
	)
	(gr_circle
		(center 271.526 -113.03)
		(end 272.415 -113.03)
		(stroke
			(width 0.2)
			(type default)
		)
		(fill no)
		(layer "In3.Cu")
	)
	(gr_circle
		(center 271.526 -110.744)
		(end 272.415 -110.744)
		(stroke
			(width 0.2)
			(type default)
		)
		(fill no)
		(layer "In3.Cu")
	)
	(gr_circle
		(center 271.526 -109.982)
		(end 272.415 -109.982)
		(stroke
			(width 0.2)
			(type default)
		)
		(fill no)
		(layer "In3.Cu")
	)
	(gr_circle
		(center 271.526 -101.727)
		(end 272.415 -101.727)
		(stroke
			(width 0.2)
			(type default)
		)
		(fill no)
		(layer "In3.Cu")
	)
	(gr_circle
		(center 271.526 -100.965)
		(end 272.415 -100.965)
		(stroke
			(width 0.2)
			(type default)
		)
		(fill no)
		(layer "In3.Cu")
	)
	(gr_circle
		(center 271.526 -98.679)
		(end 272.415 -98.679)
		(stroke
			(width 0.2)
			(type default)
		)
		(fill no)
		(layer "In3.Cu")
	)
	(gr_circle
		(center 271.526 -97.917)
		(end 272.415 -97.917)
		(stroke
			(width 0.2)
			(type default)
		)
		(fill no)
		(layer "In3.Cu")
	)
	(gr_circle
		(center 271.526 -89.662)
		(end 272.415 -89.662)
		(stroke
			(width 0.2)
			(type default)
		)
		(fill no)
		(layer "In3.Cu")
	)
	(gr_circle
		(center 271.526 -88.9)
		(end 272.415 -88.9)
		(stroke
			(width 0.2)
			(type default)
		)
		(fill no)
		(layer "In3.Cu")
	)
	(gr_circle
		(center 271.526 -86.614)
		(end 272.415 -86.614)
		(stroke
			(width 0.2)
			(type default)
		)
		(fill no)
		(layer "In3.Cu")
	)
	(gr_circle
		(center 271.526 -85.852)
		(end 272.415 -85.852)
		(stroke
			(width 0.2)
			(type default)
		)
		(fill no)
		(layer "In3.Cu")
	)
	(gr_circle
		(center 271.526 -77.597)
		(end 272.415 -77.597)
		(stroke
			(width 0.2)
			(type default)
		)
		(fill no)
		(layer "In3.Cu")
	)
	(gr_circle
		(center 271.526 -76.835)
		(end 272.415 -76.835)
		(stroke
			(width 0.2)
			(type default)
		)
		(fill no)
		(layer "In3.Cu")
	)
	(gr_circle
		(center 271.526 -74.549)
		(end 272.415 -74.549)
		(stroke
			(width 0.2)
			(type default)
		)
		(fill no)
		(layer "In3.Cu")
	)
	(gr_circle
		(center 271.526 -73.787)
		(end 272.415 -73.787)
		(stroke
			(width 0.2)
			(type default)
		)
		(fill no)
		(layer "In3.Cu")
	)
	(gr_circle
		(center 271.526 -65.532)
		(end 272.415 -65.532)
		(stroke
			(width 0.2)
			(type default)
		)
		(fill no)
		(layer "In3.Cu")
	)
	(gr_circle
		(center 271.526 -64.77)
		(end 272.415 -64.77)
		(stroke
			(width 0.2)
			(type default)
		)
		(fill no)
		(layer "In3.Cu")
	)
	(gr_circle
		(center 271.526 -62.484)
		(end 272.415 -62.484)
		(stroke
			(width 0.2)
			(type default)
		)
		(fill no)
		(layer "In3.Cu")
	)
	(gr_circle
		(center 271.526 -61.722)
		(end 272.415 -61.722)
		(stroke
			(width 0.2)
			(type default)
		)
		(fill no)
		(layer "In3.Cu")
	)
	(gr_circle
		(center 271.653 -140.462)
		(end 272.542 -140.462)
		(stroke
			(width 0.2)
			(type default)
		)
		(fill no)
		(layer "In3.Cu")
	)
	(gr_circle
		(center 271.653 -139.7)
		(end 272.542 -139.7)
		(stroke
			(width 0.2)
			(type default)
		)
		(fill no)
		(layer "In3.Cu")
	)
	(gr_circle
		(center 271.653 -138.938)
		(end 272.542 -138.938)
		(stroke
			(width 0.2)
			(type default)
		)
		(fill no)
		(layer "In3.Cu")
	)
	(gr_circle
		(center 271.653 -138.176)
		(end 272.542 -138.176)
		(stroke
			(width 0.2)
			(type default)
		)
		(fill no)
		(layer "In3.Cu")
	)
	(gr_circle
		(center 271.653 -137.414)
		(end 272.542 -137.414)
		(stroke
			(width 0.2)
			(type default)
		)
		(fill no)
		(layer "In3.Cu")
	)
	(gr_circle
		(center 271.653 -136.652)
		(end 272.542 -136.652)
		(stroke
			(width 0.2)
			(type default)
		)
		(fill no)
		(layer "In3.Cu")
	)
	(gr_circle
		(center 272.288 -125.857)
		(end 273.177 -125.857)
		(stroke
			(width 0.2)
			(type default)
		)
		(fill no)
		(layer "In3.Cu")
	)
	(gr_circle
		(center 272.288 -125.095)
		(end 273.177 -125.095)
		(stroke
			(width 0.2)
			(type default)
		)
		(fill no)
		(layer "In3.Cu")
	)
	(gr_circle
		(center 272.288 -122.809)
		(end 273.177 -122.809)
		(stroke
			(width 0.2)
			(type default)
		)
		(fill no)
		(layer "In3.Cu")
	)
	(gr_circle
		(center 272.288 -122.047)
		(end 273.177 -122.047)
		(stroke
			(width 0.2)
			(type default)
		)
		(fill no)
		(layer "In3.Cu")
	)
	(gr_circle
		(center 272.288 -113.792)
		(end 273.177 -113.792)
		(stroke
			(width 0.2)
			(type default)
		)
		(fill no)
		(layer "In3.Cu")
	)
	(gr_circle
		(center 272.288 -113.03)
		(end 273.177 -113.03)
		(stroke
			(width 0.2)
			(type default)
		)
		(fill no)
		(layer "In3.Cu")
	)
	(gr_circle
		(center 272.288 -110.744)
		(end 273.177 -110.744)
		(stroke
			(width 0.2)
			(type default)
		)
		(fill no)
		(layer "In3.Cu")
	)
	(gr_circle
		(center 272.288 -109.982)
		(end 273.177 -109.982)
		(stroke
			(width 0.2)
			(type default)
		)
		(fill no)
		(layer "In3.Cu")
	)
	(gr_circle
		(center 272.288 -101.727)
		(end 273.177 -101.727)
		(stroke
			(width 0.2)
			(type default)
		)
		(fill no)
		(layer "In3.Cu")
	)
	(gr_circle
		(center 272.288 -100.965)
		(end 273.177 -100.965)
		(stroke
			(width 0.2)
			(type default)
		)
		(fill no)
		(layer "In3.Cu")
	)
	(gr_circle
		(center 272.288 -98.679)
		(end 273.177 -98.679)
		(stroke
			(width 0.2)
			(type default)
		)
		(fill no)
		(layer "In3.Cu")
	)
	(gr_circle
		(center 272.288 -97.917)
		(end 273.177 -97.917)
		(stroke
			(width 0.2)
			(type default)
		)
		(fill no)
		(layer "In3.Cu")
	)
	(gr_circle
		(center 272.288 -89.662)
		(end 273.177 -89.662)
		(stroke
			(width 0.2)
			(type default)
		)
		(fill no)
		(layer "In3.Cu")
	)
	(gr_circle
		(center 272.288 -88.9)
		(end 273.177 -88.9)
		(stroke
			(width 0.2)
			(type default)
		)
		(fill no)
		(layer "In3.Cu")
	)
	(gr_circle
		(center 272.288 -86.614)
		(end 273.177 -86.614)
		(stroke
			(width 0.2)
			(type default)
		)
		(fill no)
		(layer "In3.Cu")
	)
	(gr_circle
		(center 272.288 -85.852)
		(end 273.177 -85.852)
		(stroke
			(width 0.2)
			(type default)
		)
		(fill no)
		(layer "In3.Cu")
	)
	(gr_circle
		(center 272.288 -77.597)
		(end 273.177 -77.597)
		(stroke
			(width 0.2)
			(type default)
		)
		(fill no)
		(layer "In3.Cu")
	)
	(gr_circle
		(center 272.288 -76.835)
		(end 273.177 -76.835)
		(stroke
			(width 0.2)
			(type default)
		)
		(fill no)
		(layer "In3.Cu")
	)
	(gr_circle
		(center 272.288 -74.549)
		(end 273.177 -74.549)
		(stroke
			(width 0.2)
			(type default)
		)
		(fill no)
		(layer "In3.Cu")
	)
	(gr_circle
		(center 272.288 -73.787)
		(end 273.177 -73.787)
		(stroke
			(width 0.2)
			(type default)
		)
		(fill no)
		(layer "In3.Cu")
	)
	(gr_circle
		(center 272.288 -65.532)
		(end 273.177 -65.532)
		(stroke
			(width 0.2)
			(type default)
		)
		(fill no)
		(layer "In3.Cu")
	)
	(gr_circle
		(center 272.288 -64.77)
		(end 273.177 -64.77)
		(stroke
			(width 0.2)
			(type default)
		)
		(fill no)
		(layer "In3.Cu")
	)
	(gr_circle
		(center 272.288 -62.484)
		(end 273.177 -62.484)
		(stroke
			(width 0.2)
			(type default)
		)
		(fill no)
		(layer "In3.Cu")
	)
	(gr_circle
		(center 272.288 -61.722)
		(end 273.177 -61.722)
		(stroke
			(width 0.2)
			(type default)
		)
		(fill no)
		(layer "In3.Cu")
	)
	(gr_circle
		(center 272.5928 -23.0886)
		(end 273.4818 -23.0886)
		(stroke
			(width 0.2)
			(type default)
		)
		(fill no)
		(layer "In3.Cu")
	)
	(gr_circle
		(center 273.6088 -23.0886)
		(end 274.4978 -23.0886)
		(stroke
			(width 0.2)
			(type default)
		)
		(fill no)
		(layer "In3.Cu")
	)
	(gr_circle
		(center 275.41855 -33.070038)
		(end 276.30755 -33.070038)
		(stroke
			(width 0.2)
			(type default)
		)
		(fill no)
		(layer "In3.Cu")
	)
	(gr_circle
		(center 277.368 -20.955)
		(end 278.257 -20.955)
		(stroke
			(width 0.2)
			(type default)
		)
		(fill no)
		(layer "In3.Cu")
	)
	(gr_line
		(start 278.19985 -131.594352)
		(end 278.19985 -61.165994)
		(stroke
			(width 1.016)
			(type default)
		)
		(layer "In3.Cu")
	)
	(gr_line
		(start 278.19985 -97.85985)
		(end 279.6921 -96.3676)
		(stroke
			(width 1.016)
			(type default)
		)
		(layer "In3.Cu")
	)
	(gr_line
		(start 278.19985 -94.87535)
		(end 279.6921 -96.3676)
		(stroke
			(width 1.016)
			(type default)
		)
		(layer "In3.Cu")
	)
	(gr_line
		(start 279.565862 -132.960364)
		(end 278.19985 -131.594352)
		(stroke
			(width 1.016)
			(type default)
		)
		(layer "In3.Cu")
	)
	(gr_line
		(start 279.648666 -59.717178)
		(end 278.19985 -61.165994)
		(stroke
			(width 1.016)
			(type default)
		)
		(layer "In3.Cu")
	)
	(gr_line
		(start 279.648666 -59.717178)
		(end 291.200078 -59.717178)
		(stroke
			(width 1.016)
			(type default)
		)
		(layer "In3.Cu")
	)
	(gr_circle
		(center 283.413454 -32.1564)
		(end 284.302454 -32.1564)
		(stroke
			(width 0.2)
			(type default)
		)
		(fill no)
		(layer "In3.Cu")
	)
	(gr_circle
		(center 285.242 -30.687264)
		(end 286.131 -30.687264)
		(stroke
			(width 0.2)
			(type default)
		)
		(fill no)
		(layer "In3.Cu")
	)
	(gr_circle
		(center 286.004 -30.687264)
		(end 286.893 -30.687264)
		(stroke
			(width 0.2)
			(type default)
		)
		(fill no)
		(layer "In3.Cu")
	)
	(gr_circle
		(center 287.401 -30.687264)
		(end 288.29 -30.687264)
		(stroke
			(width 0.2)
			(type default)
		)
		(fill no)
		(layer "In3.Cu")
	)
	(gr_circle
		(center 288.163 -30.687264)
		(end 289.052 -30.687264)
		(stroke
			(width 0.2)
			(type default)
		)
		(fill no)
		(layer "In3.Cu")
	)
	(gr_line
		(start 291.200078 -59.717178)
		(end 298.525184 -59.717178)
		(stroke
			(width 1.016)
			(type default)
		)
		(layer "In3.Cu")
	)
	(gr_circle
		(center 294.132 -45.466)
		(end 295.021 -45.466)
		(stroke
			(width 0.2)
			(type default)
		)
		(fill no)
		(layer "In3.Cu")
	)
	(gr_circle
		(center 294.1828 -34.9758)
		(end 295.0718 -34.9758)
		(stroke
			(width 0.2)
			(type default)
		)
		(fill no)
		(layer "In3.Cu")
	)
	(gr_circle
		(center 294.6908 -44.699428)
		(end 295.5798 -44.699428)
		(stroke
			(width 0.2)
			(type default)
		)
		(fill no)
		(layer "In3.Cu")
	)
	(gr_circle
		(center 295.3258 -44.693586)
		(end 296.2148 -44.693586)
		(stroke
			(width 0.2)
			(type default)
		)
		(fill no)
		(layer "In3.Cu")
	)
	(gr_circle
		(center 297.561 -54.356)
		(end 298.45 -54.356)
		(stroke
			(width 0.2)
			(type default)
		)
		(fill no)
		(layer "In3.Cu")
	)
	(gr_circle
		(center 297.561 -53.594)
		(end 298.45 -53.594)
		(stroke
			(width 0.2)
			(type default)
		)
		(fill no)
		(layer "In3.Cu")
	)
	(gr_circle
		(center 297.561 -52.832)
		(end 298.45 -52.832)
		(stroke
			(width 0.2)
			(type default)
		)
		(fill no)
		(layer "In3.Cu")
	)
	(gr_circle
		(center 297.561 -52.07)
		(end 298.45 -52.07)
		(stroke
			(width 0.2)
			(type default)
		)
		(fill no)
		(layer "In3.Cu")
	)
	(gr_line
		(start 298.271184 -96.3676)
		(end 278.19985 -96.3676)
		(stroke
			(width 1.016)
			(type default)
		)
		(layer "In3.Cu")
	)
	(gr_circle
		(center 298.323 -54.356)
		(end 299.212 -54.356)
		(stroke
			(width 0.2)
			(type default)
		)
		(fill no)
		(layer "In3.Cu")
	)
	(gr_circle
		(center 298.323 -53.594)
		(end 299.212 -53.594)
		(stroke
			(width 0.2)
			(type default)
		)
		(fill no)
		(layer "In3.Cu")
	)
	(gr_circle
		(center 298.323 -52.832)
		(end 299.212 -52.832)
		(stroke
			(width 0.2)
			(type default)
		)
		(fill no)
		(layer "In3.Cu")
	)
	(gr_circle
		(center 298.323 -52.07)
		(end 299.212 -52.07)
		(stroke
			(width 0.2)
			(type default)
		)
		(fill no)
		(layer "In3.Cu")
	)
	(gr_line
		(start 298.525184 -59.717178)
		(end 299.763434 -60.955428)
		(stroke
			(width 1.016)
			(type default)
		)
		(layer "In3.Cu")
	)
	(gr_line
		(start 298.533566 -132.960364)
		(end 279.565862 -132.960364)
		(stroke
			(width 1.016)
			(type default)
		)
		(layer "In3.Cu")
	)
	(gr_circle
		(center 299.090334 -42.151808)
		(end 299.979334 -42.151808)
		(stroke
			(width 0.2)
			(type default)
		)
		(fill no)
		(layer "In3.Cu")
	)
	(gr_circle
		(center 299.090334 -41.389808)
		(end 299.979334 -41.389808)
		(stroke
			(width 0.2)
			(type default)
		)
		(fill no)
		(layer "In3.Cu")
	)
	(gr_line
		(start 299.763434 -131.730496)
		(end 298.533566 -132.960364)
		(stroke
			(width 1.016)
			(type default)
		)
		(layer "In3.Cu")
	)
	(gr_line
		(start 299.763434 -127.672338)
		(end 299.763434 -131.730496)
		(stroke
			(width 1.016)
			(type default)
		)
		(layer "In3.Cu")
	)
	(gr_line
		(start 299.763434 -127.672338)
		(end 299.763434 -126.359666)
		(stroke
			(width 1.016)
			(type default)
		)
		(layer "In3.Cu")
	)
	(gr_line
		(start 299.763434 -127.672338)
		(end 299.763434 -126.219966)
		(stroke
			(width 1.016)
			(type default)
		)
		(layer "In3.Cu")
	)
	(gr_line
		(start 299.763434 -126.219966)
		(end 303.6824 -122.301)
		(stroke
			(width 1.016)
			(type default)
		)
		(layer "In3.Cu")
	)
	(gr_line
		(start 299.763434 -125.046994)
		(end 299.763434 -126.359666)
		(stroke
			(width 1.016)
			(type default)
		)
		(layer "In3.Cu")
	)
	(gr_line
		(start 299.763434 -125.046994)
		(end 299.763434 -122.1994)
		(stroke
			(width 1.016)
			(type default)
		)
		(layer "In3.Cu")
	)
	(gr_line
		(start 299.763434 -97.85985)
		(end 298.271184 -96.3676)
		(stroke
			(width 1.016)
			(type default)
		)
		(layer "In3.Cu")
	)
	(gr_line
		(start 299.763434 -96.3676)
		(end 298.271184 -96.3676)
		(stroke
			(width 1.016)
			(type default)
		)
		(layer "In3.Cu")
	)
	(gr_line
		(start 299.763434 -94.87535)
		(end 298.271184 -96.3676)
		(stroke
			(width 1.016)
			(type default)
		)
		(layer "In3.Cu")
	)
	(gr_line
		(start 299.763434 -60.955428)
		(end 299.763434 -122.1994)
		(stroke
			(width 1.016)
			(type default)
		)
		(layer "In3.Cu")
	)
	(gr_circle
		(center 299.852334 -42.151808)
		(end 300.741334 -42.151808)
		(stroke
			(width 0.2)
			(type default)
		)
		(fill no)
		(layer "In3.Cu")
	)
	(gr_circle
		(center 299.852334 -41.389808)
		(end 300.741334 -41.389808)
		(stroke
			(width 0.2)
			(type default)
		)
		(fill no)
		(layer "In3.Cu")
	)
	(gr_line
		(start 300.4185 -73.53935)
		(end 299.806868 -72.927718)
		(stroke
			(width 1.016)
			(type default)
		)
		(layer "In3.Cu")
	)
	(gr_circle
		(center 300.487334 -42.151808)
		(end 301.376334 -42.151808)
		(stroke
			(width 0.2)
			(type default)
		)
		(fill no)
		(layer "In3.Cu")
	)
	(gr_circle
		(center 300.487334 -41.389808)
		(end 301.376334 -41.389808)
		(stroke
			(width 0.2)
			(type default)
		)
		(fill no)
		(layer "In3.Cu")
	)
	(gr_line
		(start 300.61789 -73.554336)
		(end 299.798994 -74.373232)
		(stroke
			(width 1.016)
			(type default)
		)
		(layer "In3.Cu")
	)
	(gr_line
		(start 301.084742 -122.1994)
		(end 299.763434 -123.520708)
		(stroke
			(width 1.016)
			(type default)
		)
		(layer "In3.Cu")
	)
	(gr_line
		(start 301.084742 -122.1994)
		(end 299.763434 -120.878092)
		(stroke
			(width 1.016)
			(type default)
		)
		(layer "In3.Cu")
	)
	(gr_circle
		(center 301.122334 -42.151808)
		(end 302.011334 -42.151808)
		(stroke
			(width 0.2)
			(type default)
		)
		(fill no)
		(layer "In3.Cu")
	)
	(gr_circle
		(center 301.122334 -41.389808)
		(end 302.011334 -41.389808)
		(stroke
			(width 0.2)
			(type default)
		)
		(fill no)
		(layer "In3.Cu")
	)
	(gr_line
		(start 301.447708 -122.503692)
		(end 300.1264 -123.825)
		(stroke
			(width 1.016)
			(type default)
		)
		(layer "In3.Cu")
	)
	(gr_circle
		(center 301.9044 -42.164)
		(end 302.7934 -42.164)
		(stroke
			(width 0.2)
			(type default)
		)
		(fill no)
		(layer "In3.Cu")
	)
	(gr_circle
		(center 301.908972 -41.346628)
		(end 302.797972 -41.346628)
		(stroke
			(width 0.2)
			(type default)
		)
		(fill no)
		(layer "In3.Cu")
	)
	(gr_line
		(start 302.509428 -122.301)
		(end 299.763434 -125.046994)
		(stroke
			(width 1.016)
			(type default)
		)
		(layer "In3.Cu")
	)
	(gr_line
		(start 303.6824 -122.301)
		(end 302.509428 -122.301)
		(stroke
			(width 1.016)
			(type default)
		)
		(layer "In3.Cu")
	)
	(gr_line
		(start 304.071782 -73.53935)
		(end 300.4185 -73.53935)
		(stroke
			(width 1.016)
			(type default)
		)
		(layer "In3.Cu")
	)
	(gr_line
		(start 304.365406 -122.1994)
		(end 304.688494 -122.1994)
		(stroke
			(width 1.016)
			(type default)
		)
		(layer "In3.Cu")
	)
	(gr_line
		(start 306.38115 -73.53935)
		(end 304.071782 -73.53935)
		(stroke
			(width 1.016)
			(type default)
		)
		(layer "In3.Cu")
	)
	(gr_line
		(start 306.451 -73.6092)
		(end 306.38115 -73.53935)
		(stroke
			(width 1.016)
			(type default)
		)
		(layer "In3.Cu")
	)
	(gr_line
		(start 306.451 -73.6092)
		(end 308.6608 -75.819)
		(stroke
			(width 1.016)
			(type default)
		)
		(layer "In3.Cu")
	)
	(gr_line
		(start 308.6608 -75.819)
		(end 319.8876 -75.819)
		(stroke
			(width 1.016)
			(type default)
		)
		(layer "In3.Cu")
	)
	(gr_circle
		(center 311.410096 -72.879966)
		(end 312.809128 -72.879966)
		(stroke
			(width 0.2)
			(type default)
		)
		(fill no)
		(layer "In3.Cu")
	)
	(gr_line
		(start 319.6336 -122.1994)
		(end 299.763434 -122.1994)
		(stroke
			(width 1.016)
			(type default)
		)
		(layer "In3.Cu")
	)
	(gr_line
		(start 319.8876 -75.819)
		(end 320.929 -76.8604)
		(stroke
			(width 1.016)
			(type default)
		)
		(layer "In3.Cu")
	)
	(gr_line
		(start 320.929 -120.904)
		(end 319.6336 -122.1994)
		(stroke
			(width 1.016)
			(type default)
		)
		(layer "In3.Cu")
	)
	(gr_line
		(start 320.929 -76.8604)
		(end 320.929 -120.904)
		(stroke
			(width 1.016)
			(type default)
		)
		(layer "In3.Cu")
	)
	(gr_arc
		(start 0 -141.99997)
		(mid 1.464463 -145.535497)
		(end 4.99999 -146.99996)
		(stroke
			(width 2.032)
			(type default)
		)
		(layer "In4.Cu")
	)
	(gr_line
		(start 0 -131.729988)
		(end 0 -141.99997)
		(stroke
			(width 2.032)
			(type default)
		)
		(layer "In4.Cu")
	)
	(gr_arc
		(start 0 -113.229898)
		(mid 0.878678 -115.351214)
		(end 2.999994 -116.229892)
		(stroke
			(width 2.032)
			(type default)
		)
		(layer "In4.Cu")
	)
	(gr_line
		(start 0 -96.562164)
		(end 0 -113.229898)
		(stroke
			(width 2.032)
			(type default)
		)
		(layer "In4.Cu")
	)
	(gr_line
		(start 0 -96.562164)
		(end 0 -74.304398)
		(stroke
			(width 2.032)
			(type default)
		)
		(layer "In4.Cu")
	)
	(gr_line
		(start 0 -74.304398)
		(end 0 -34.569908)
		(stroke
			(width 2.032)
			(type default)
		)
		(layer "In4.Cu")
	)
	(gr_arc
		(start 0 -16.070072)
		(mid 0.878678 -18.191388)
		(end 2.999994 -19.070066)
		(stroke
			(width 2.032)
			(type default)
		)
		(layer "In4.Cu")
	)
	(gr_line
		(start 0 -4.99999)
		(end 0 -16.070072)
		(stroke
			(width 2.032)
			(type default)
		)
		(layer "In4.Cu")
	)
	(gr_poly
		(pts
			(arc
				(start 298.302172 -132.45211)
				(mid 298.321695 -132.448209)
				(end 298.33824 -132.437124)
			)
			(arc
				(start 299.240448 -131.534916)
				(mid 299.251559 -131.518382)
				(end 299.255434 -131.498848)
			)
			(xy 299.255434 -122.167396) (xy 299.252894 -122.156474)
			(arc
				(start 299.250354 -122.15114)
				(mid 299.221372 -122.069537)
				(end 299.211492 -121.9835)
			)
			(arc
				(start 299.211492 -121.9835)
				(mid 299.221323 -121.897451)
				(end 299.250354 -121.81586)
			)
			(xy 299.252894 -121.810526) (xy 299.255434 -121.799604) (xy 299.255434 -121.278396) (xy 299.252894 -121.267474)
			(arc
				(start 299.250354 -121.26214)
				(mid 299.221372 -121.180537)
				(end 299.211492 -121.0945)
			)
			(arc
				(start 299.211492 -121.0945)
				(mid 299.221323 -121.008451)
				(end 299.250354 -120.92686)
			)
			(xy 299.252894 -120.921526) (xy 299.255434 -120.910604) (xy 299.255434 -120.389396) (xy 299.252894 -120.378474)
			(arc
				(start 299.250354 -120.37314)
				(mid 299.221372 -120.291537)
				(end 299.211492 -120.2055)
			)
			(arc
				(start 299.211492 -120.2055)
				(mid 299.221323 -120.119451)
				(end 299.250354 -120.03786)
			)
			(xy 299.252894 -120.032526) (xy 299.255434 -120.021604) (xy 299.255434 -119.500396) (xy 299.252894 -119.489474)
			(arc
				(start 299.250354 -119.48414)
				(mid 299.221372 -119.402537)
				(end 299.211492 -119.3165)
			)
			(arc
				(start 299.211492 -119.3165)
				(mid 299.221323 -119.230451)
				(end 299.250354 -119.14886)
			)
			(xy 299.252894 -119.143526) (xy 299.255434 -119.132604)
			(arc
				(start 299.255434 -98.091244)
				(mid 299.251533 -98.071721)
				(end 299.240448 -98.055176)
			)
			(arc
				(start 298.075858 -96.890586)
				(mid 298.059324 -96.879475)
				(end 298.03979 -96.8756)
			)
			(arc
				(start 279.923494 -96.8756)
				(mid 279.903971 -96.879501)
				(end 279.887426 -96.890586)
			)
			(arc
				(start 278.722836 -98.055176)
				(mid 278.711725 -98.07171)
				(end 278.70785 -98.091244)
			)
			(arc
				(start 278.70785 -131.362704)
				(mid 278.711751 -131.382227)
				(end 278.722836 -131.398772)
			)
			(arc
				(start 279.761188 -132.437124)
				(mid 279.777722 -132.448235)
				(end 279.797256 -132.45211)
			)
		)
		(stroke
			(width 0)
			(type solid)
		)
		(fill yes)
		(layer "In4.Cu")
		(net "P52V_HS1_DRAIN_1")
	)
	(gr_poly
		(pts
			(arc
				(start 298.03979 -95.8596)
				(mid 298.059313 -95.855699)
				(end 298.075858 -95.844614)
			)
			(arc
				(start 299.240448 -94.680024)
				(mid 299.251559 -94.66349)
				(end 299.255434 -94.643956)
			)
			(arc
				(start 299.255434 -86.018878)
				(mid 299.25339 -86.004863)
				(end 299.24756 -85.991954)
			)
			(arc
				(start 299.24756 -85.991954)
				(mid 299.203848 -85.894376)
				(end 299.188886 -85.7885)
			)
			(arc
				(start 299.188886 -85.7885)
				(mid 299.203802 -85.682611)
				(end 299.24756 -85.585046)
			)
			(arc
				(start 299.24756 -85.585046)
				(mid 299.253395 -85.572139)
				(end 299.255434 -85.558122)
			)
			(arc
				(start 299.255434 -85.129878)
				(mid 299.25339 -85.115863)
				(end 299.24756 -85.102954)
			)
			(arc
				(start 299.24756 -85.102954)
				(mid 299.203848 -85.005376)
				(end 299.188886 -84.8995)
			)
			(arc
				(start 299.188886 -84.8995)
				(mid 299.203802 -84.793611)
				(end 299.24756 -84.696046)
			)
			(arc
				(start 299.24756 -84.696046)
				(mid 299.253395 -84.683139)
				(end 299.255434 -84.669122)
			)
			(arc
				(start 299.255434 -84.240878)
				(mid 299.25339 -84.226863)
				(end 299.24756 -84.213954)
			)
			(arc
				(start 299.24756 -84.213954)
				(mid 299.203848 -84.116376)
				(end 299.188886 -84.0105)
			)
			(arc
				(start 299.188886 -84.0105)
				(mid 299.203802 -83.904611)
				(end 299.24756 -83.807046)
			)
			(arc
				(start 299.24756 -83.807046)
				(mid 299.253395 -83.794139)
				(end 299.255434 -83.780122)
			)
			(arc
				(start 299.255434 -83.351878)
				(mid 299.25339 -83.337863)
				(end 299.24756 -83.324954)
			)
			(arc
				(start 299.24756 -83.324954)
				(mid 299.203848 -83.227376)
				(end 299.188886 -83.1215)
			)
			(arc
				(start 299.188886 -83.1215)
				(mid 299.203802 -83.015611)
				(end 299.24756 -82.918046)
			)
			(arc
				(start 299.24756 -82.918046)
				(mid 299.253395 -82.905139)
				(end 299.255434 -82.891122)
			)
			(xy 299.255434 -78.790546)
			(arc
				(start 299.254672 -78.786482)
				(mid 299.251029 -78.755972)
				(end 299.249846 -78.725268)
			)
			(arc
				(start 299.249846 -78.725268)
				(mid 299.251022 -78.694563)
				(end 299.254672 -78.664054)
			)
			(xy 299.255434 -78.65999) (xy 299.255434 -77.774546)
			(arc
				(start 299.254672 -77.770482)
				(mid 299.251029 -77.739972)
				(end 299.249846 -77.709268)
			)
			(arc
				(start 299.249846 -77.709268)
				(mid 299.251022 -77.678563)
				(end 299.254672 -77.648054)
			)
			(xy 299.255434 -77.64399)
			(arc
				(start 299.255434 -61.186568)
				(mid 299.251533 -61.167045)
				(end 299.240448 -61.1505)
			)
			(arc
				(start 298.329858 -60.23991)
				(mid 298.313324 -60.228799)
				(end 298.29379 -60.224924)
			)
			(arc
				(start 279.88006 -60.224924)
				(mid 279.860537 -60.228825)
				(end 279.843992 -60.23991)
			)
			(arc
				(start 278.722836 -61.361066)
				(mid 278.711725 -61.3776)
				(end 278.70785 -61.397134)
			)
			(arc
				(start 278.70785 -94.643956)
				(mid 278.711751 -94.663479)
				(end 278.722836 -94.680024)
			)
			(arc
				(start 279.887426 -95.844614)
				(mid 279.90396 -95.855725)
				(end 279.923494 -95.8596)
			)
		)
		(stroke
			(width 0)
			(type solid)
		)
		(fill yes)
		(layer "In4.Cu")
		(net "P52V_HS1_DRAIN_2")
	)
	(gr_poly
		(pts
			(arc
				(start 34.21888 -118.409974)
				(mid 34.238403 -118.406073)
				(end 34.254948 -118.394988)
			)
			(arc
				(start 34.988754 -117.661182)
				(mid 34.999865 -117.644648)
				(end 35.00374 -117.625114)
			)
			(arc
				(start 35.00374 -84.78266)
				(mid 35.042424 -84.588271)
				(end 35.152584 -84.423504)
			)
			(arc
				(start 36.623244 -82.952844)
				(mid 36.788012 -82.842686)
				(end 36.9824 -82.804)
			)
			(arc
				(start 40.214042 -82.804)
				(mid 40.240942 -82.796293)
				(end 40.259762 -82.775552)
			)
			(xy 40.306244 -82.680302) (xy 40.303196 -82.6516)
			(arc
				(start 40.294052 -82.639916)
				(mid 40.154351 -82.382065)
				(end 40.106092 -82.0928)
			)
			(arc
				(start 40.106092 -82.0928)
				(mid 40.9956 -81.203292)
				(end 41.885108 -82.0928)
			)
			(arc
				(start 41.885108 -82.0928)
				(mid 41.836848 -82.382065)
				(end 41.697148 -82.639916)
			)
			(xy 41.688004 -82.6516) (xy 41.684956 -82.680302)
			(arc
				(start 41.731438 -82.775552)
				(mid 41.75021 -82.796371)
				(end 41.777158 -82.804)
			)
			(arc
				(start 44.370244 -82.804)
				(mid 44.389767 -82.800099)
				(end 44.406312 -82.789014)
			)
			(arc
				(start 44.840398 -82.354928)
				(mid 44.851509 -82.338394)
				(end 44.855384 -82.31886)
			)
			(arc
				(start 44.855384 -82.07375)
				(mid 44.851483 -82.054227)
				(end 44.840398 -82.037682)
			)
			(arc
				(start 37.994844 -75.192128)
				(mid 37.884686 -75.02736)
				(end 37.846 -74.832972)
			)
			(arc
				(start 37.846 -68.684394)
				(mid 37.842099 -68.664871)
				(end 37.831014 -68.648326)
			)
			(arc
				(start 37.295074 -68.112386)
				(mid 37.27854 -68.101275)
				(end 37.259006 -68.0974)
			)
			(arc
				(start 9.349994 -68.0974)
				(mid 9.330471 -68.101301)
				(end 9.313926 -68.112386)
			)
			(arc
				(start 8.676386 -68.749926)
				(mid 8.665275 -68.76646)
				(end 8.6614 -68.785994)
			)
			(arc
				(start 8.6614 -76.959206)
				(mid 8.665301 -76.978729)
				(end 8.676386 -76.995274)
			)
			(arc
				(start 9.110726 -77.429614)
				(mid 9.12726 -77.440725)
				(end 9.146794 -77.4446)
			)
			(arc
				(start 14.9606 -77.4446)
				(mid 15.154989 -77.483284)
				(end 15.319756 -77.593444)
			)
			(arc
				(start 15.599156 -77.872844)
				(mid 15.709314 -78.037612)
				(end 15.748 -78.232)
			)
			(arc
				(start 15.748 -117.679216)
				(mid 15.751901 -117.698739)
				(end 15.762986 -117.715284)
			)
			(arc
				(start 16.44269 -118.394988)
				(mid 16.459224 -118.406099)
				(end 16.478758 -118.409974)
			)
		)
		(stroke
			(width 0)
			(type solid)
		)
		(fill yes)
		(layer "In4.Cu")
		(net "P52V_FAN")
	)
	(gr_poly
		(pts
			(xy 319.402206 -121.6914) (xy 319.412276 -121.690976) (xy 319.430879 -121.68326) (xy 319.438274 -121.676414)
			(xy 320.406014 -120.708674) (xy 320.412866 -120.701278) (xy 320.420604 -120.682679) (xy 320.421 -120.672606)
			(xy 320.421 -77.091794) (xy 320.420576 -77.081724) (xy 320.41286 -77.063121) (xy 320.406014 -77.055726)
			(xy 319.692274 -76.341986) (xy 319.684878 -76.335134) (xy 319.666279 -76.327396) (xy 319.656206 -76.327)
			(xy 308.6608 -76.327) (xy 308.62754 -76.326479) (xy 308.56159 -76.317791) (xy 308.497339 -76.300566)
			(xy 308.435888 -76.275097) (xy 308.378289 -76.241821) (xy 308.325529 -76.201308) (xy 308.301644 -76.178156)
			(xy 306.255674 -74.132186) (xy 306.248278 -74.125334) (xy 306.229679 -74.117596) (xy 306.219606 -74.1172)
			(xy 300.730158 -74.1172) (xy 300.720091 -74.117631) (xy 300.701498 -74.125356) (xy 300.69409 -74.132186)
			(xy 300.28642 -74.539856) (xy 300.27958 -74.547257) (xy 300.271863 -74.565855) (xy 300.271434 -74.575924)
			(xy 300.271434 -88.45423) (xy 300.271729 -88.462103) (xy 300.276515 -88.477104) (xy 300.280832 -88.483694)
			(xy 300.295759 -88.505354) (xy 300.32016 -88.551955) (xy 300.337926 -88.601467) (xy 300.348721 -88.652951)
			(xy 300.352339 -88.705429) (xy 300.348712 -88.757907) (xy 300.33791 -88.809389) (xy 300.320136 -88.858899)
			(xy 300.295729 -88.905496) (xy 300.280832 -88.927178) (xy 300.276501 -88.933762) (xy 300.271707 -88.948766)
			(xy 300.271434 -88.956642) (xy 300.271434 -101.454966) (xy 307.269651 -101.454966) (xy 307.273647 -101.2731)
			(xy 307.285627 -101.091585) (xy 307.305569 -100.910772) (xy 307.333434 -100.731009) (xy 307.369168 -100.552644)
			(xy 307.412701 -100.37602) (xy 307.463951 -100.201479) (xy 307.522818 -100.029357) (xy 307.589189 -99.859987)
			(xy 307.662935 -99.693696) (xy 307.743914 -99.530805) (xy 307.831969 -99.371628) (xy 307.926932 -99.216472)
			(xy 308.028617 -99.065637) (xy 308.13683 -98.919415) (xy 308.251362 -98.778086) (xy 308.37199 -98.641925)
			(xy 308.498483 -98.511193) (xy 308.630596 -98.386144) (xy 308.768074 -98.267018) (xy 308.910652 -98.154046)
			(xy 309.058055 -98.047446) (xy 309.209998 -97.947423) (xy 309.366187 -97.854171) (xy 309.526322 -97.767869)
			(xy 309.690093 -97.688684) (xy 309.857184 -97.616769) (xy 310.027272 -97.552263) (xy 310.20003 -97.495291)
			(xy 310.375124 -97.445961) (xy 310.552215 -97.40437) (xy 310.730962 -97.370597) (xy 310.91102 -97.344709)
			(xy 311.092042 -97.326754) (xy 311.273677 -97.316768) (xy 311.455576 -97.31477) (xy 311.637387 -97.320764)
			(xy 311.818759 -97.334737) (xy 311.999343 -97.356664) (xy 312.178789 -97.386502) (xy 312.356751 -97.424193)
			(xy 312.532886 -97.469664) (xy 312.706854 -97.522828) (xy 312.878318 -97.583582) (xy 313.046949 -97.651809)
			(xy 313.21242 -97.727377) (xy 313.374412 -97.81014) (xy 313.532612 -97.899939) (xy 313.686715 -97.9966)
			(xy 313.836424 -98.099937) (xy 313.981449 -98.209749) (xy 314.121511 -98.325826) (xy 314.256339 -98.447943)
			(xy 314.385673 -98.575864) (xy 314.509264 -98.709343) (xy 314.626872 -98.848121) (xy 314.738271 -98.991932)
			(xy 314.843246 -99.140496) (xy 314.941594 -99.293528) (xy 315.033125 -99.450733) (xy 315.117663 -99.611806)
			(xy 315.195044 -99.776437) (xy 315.265119 -99.944308) (xy 315.327753 -100.115095) (xy 315.382824 -100.288468)
			(xy 315.430228 -100.464093) (xy 315.469871 -100.64163) (xy 315.501678 -100.820737) (xy 315.525587 -101.001069)
			(xy 315.541552 -101.182277) (xy 315.549542 -101.364011) (xy 315.550042 -101.454966) (xy 315.549542 -101.545921)
			(xy 315.541552 -101.727655) (xy 315.525587 -101.908863) (xy 315.501678 -102.089195) (xy 315.469871 -102.268302)
			(xy 315.430228 -102.445839) (xy 315.382824 -102.621464) (xy 315.327753 -102.794837) (xy 315.265119 -102.965624)
			(xy 315.195044 -103.133495) (xy 315.117663 -103.298126) (xy 315.033125 -103.459199) (xy 314.941594 -103.616404)
			(xy 314.843246 -103.769436) (xy 314.738271 -103.918) (xy 314.626872 -104.061811) (xy 314.509264 -104.200589)
			(xy 314.385673 -104.334068) (xy 314.256339 -104.461989) (xy 314.121511 -104.584106) (xy 313.981449 -104.700183)
			(xy 313.836424 -104.809995) (xy 313.686715 -104.913332) (xy 313.532612 -105.009993) (xy 313.374412 -105.099792)
			(xy 313.21242 -105.182555) (xy 313.046949 -105.258123) (xy 312.878318 -105.32635) (xy 312.706854 -105.387104)
			(xy 312.532886 -105.440268) (xy 312.356751 -105.485739) (xy 312.178789 -105.52343) (xy 311.999343 -105.553268)
			(xy 311.818759 -105.575195) (xy 311.637387 -105.589168) (xy 311.455576 -105.595162) (xy 311.273677 -105.593164)
			(xy 311.092042 -105.583178) (xy 310.91102 -105.565223) (xy 310.730962 -105.539335) (xy 310.552215 -105.505562)
			(xy 310.375124 -105.463971) (xy 310.20003 -105.414641) (xy 310.027272 -105.357669) (xy 309.857184 -105.293163)
			(xy 309.690093 -105.221248) (xy 309.526322 -105.142063) (xy 309.366187 -105.055761) (xy 309.209998 -104.962509)
			(xy 309.058055 -104.862486) (xy 308.910652 -104.755886) (xy 308.768074 -104.642914) (xy 308.630596 -104.523788)
			(xy 308.498483 -104.398739) (xy 308.37199 -104.268007) (xy 308.251362 -104.131846) (xy 308.13683 -103.990517)
			(xy 308.028617 -103.844295) (xy 307.926932 -103.69346) (xy 307.831969 -103.538304) (xy 307.743914 -103.379127)
			(xy 307.662935 -103.216236) (xy 307.589189 -103.049945) (xy 307.522818 -102.880575) (xy 307.463951 -102.708453)
			(xy 307.412701 -102.533912) (xy 307.369168 -102.357288) (xy 307.333434 -102.178923) (xy 307.305569 -101.99916)
			(xy 307.285627 -101.818347) (xy 307.273647 -101.636832) (xy 307.269651 -101.454966) (xy 300.271434 -101.454966)
			(xy 300.271434 -120.646698) (xy 300.271857 -120.656768) (xy 300.279575 -120.67537) (xy 300.28642 -120.682766)
			(xy 301.280068 -121.676414) (xy 301.287466 -121.683259) (xy 301.306065 -121.690982) (xy 301.316136 -121.6914)
		)
		(stroke
			(width 0)
			(type solid)
		)
		(fill yes)
		(layer "In4.Cu")
		(net "P52V_1")
	)
	(gr_poly
		(pts
			(xy 326.00011 -166.271956) (xy 326.055917 -166.271446) (xy 326.167218 -166.263105) (xy 326.277585 -166.246469)
			(xy 326.386399 -166.221631) (xy 326.493054 -166.188731) (xy 326.596951 -166.147953) (xy 326.697511 -166.099525)
			(xy 326.79417 -166.043717) (xy 326.886389 -165.980841) (xy 326.973651 -165.91125) (xy 327.055468 -165.835332)
			(xy 327.131383 -165.753513) (xy 327.200971 -165.666249) (xy 327.263843 -165.574028) (xy 327.319648 -165.477367)
			(xy 327.368073 -165.376806) (xy 327.408848 -165.272907) (xy 327.441744 -165.166251) (xy 327.466578 -165.057436)
			(xy 327.48321 -164.947068) (xy 327.491548 -164.835767) (xy 327.492106 -164.77996) (xy 327.492106 -150.999952)
			(xy 327.491583 -150.944146) (xy 327.483238 -150.832846) (xy 327.4666 -150.722481) (xy 327.441761 -150.613668)
			(xy 327.408861 -150.507016) (xy 327.368082 -150.40312) (xy 327.319653 -150.302562) (xy 327.263845 -150.205904)
			(xy 327.20097 -150.113687) (xy 327.13138 -150.026426) (xy 327.055463 -149.94461) (xy 326.973645 -149.868695)
			(xy 326.886382 -149.799107) (xy 326.794164 -149.736235) (xy 326.697504 -149.680429) (xy 326.596945 -149.632003)
			(xy 326.493048 -149.591227) (xy 326.386395 -149.558329) (xy 326.277581 -149.533493) (xy 326.167216 -149.516857)
			(xy 326.055916 -149.508516) (xy 326.00011 -149.507956) (xy 154.399996 -149.507956) (xy 154.344188 -149.508478)
			(xy 154.232885 -149.516819) (xy 154.122517 -149.533454) (xy 154.0137 -149.558291) (xy 153.907043 -149.591189)
			(xy 153.803144 -149.631966) (xy 153.702581 -149.680394) (xy 153.605919 -149.7362) (xy 153.513698 -149.799075)
			(xy 153.426433 -149.868664) (xy 153.344612 -149.944581) (xy 153.268693 -150.026399) (xy 153.199101 -150.113662)
			(xy 153.136224 -150.205882) (xy 153.080414 -150.302543) (xy 153.031984 -150.403103) (xy 152.991204 -150.507002)
			(xy 152.958302 -150.613657) (xy 152.933462 -150.722474) (xy 152.916824 -150.832842) (xy 152.908479 -150.944144)
			(xy 152.908 -150.999952) (xy 152.908 -161.844536) (xy 155.304225 -161.844536) (xy 155.304225 -161.715396)
			(xy 155.312175 -161.586501) (xy 155.328045 -161.458341) (xy 155.351774 -161.3314) (xy 155.383273 -161.206161)
			(xy 155.422422 -161.083098) (xy 155.469073 -160.962679) (xy 155.523048 -160.84536) (xy 155.584143 -160.731586)
			(xy 155.652126 -160.621789) (xy 155.72674 -160.516386) (xy 155.807701 -160.415776) (xy 155.894701 -160.320341)
			(xy 155.987412 -160.230442) (xy 156.085482 -160.146421) (xy 156.188537 -160.068597) (xy 156.296188 -159.997265)
			(xy 156.408027 -159.932695) (xy 156.523628 -159.875133) (xy 156.642553 -159.824796) (xy 156.764352 -159.781876)
			(xy 156.888562 -159.746535) (xy 157.014711 -159.718908) (xy 157.142323 -159.699099) (xy 157.270912 -159.687183)
			(xy 157.39999 -159.683207) (xy 157.529068 -159.687183) (xy 157.657657 -159.699099) (xy 157.785269 -159.718908)
			(xy 157.911418 -159.746535) (xy 158.035628 -159.781876) (xy 158.157427 -159.824796) (xy 158.276352 -159.875133)
			(xy 158.391953 -159.932695) (xy 158.503792 -159.997265) (xy 158.611443 -160.068597) (xy 158.714498 -160.146421)
			(xy 158.812568 -160.230442) (xy 158.905279 -160.320341) (xy 158.992279 -160.415776) (xy 159.07324 -160.516386)
			(xy 159.147854 -160.621789) (xy 159.215837 -160.731586) (xy 159.276932 -160.84536) (xy 159.330907 -160.962679)
			(xy 159.377558 -161.083098) (xy 159.416707 -161.206161) (xy 159.448206 -161.3314) (xy 159.471935 -161.458341)
			(xy 159.487805 -161.586501) (xy 159.495755 -161.715396) (xy 159.496252 -161.779966) (xy 159.495755 -161.844536)
			(xy 320.904351 -161.844536) (xy 320.904351 -161.715396) (xy 320.912301 -161.586501) (xy 320.928171 -161.458341)
			(xy 320.9519 -161.3314) (xy 320.983399 -161.206161) (xy 321.022548 -161.083098) (xy 321.069199 -160.962679)
			(xy 321.123174 -160.84536) (xy 321.184269 -160.731586) (xy 321.252252 -160.621789) (xy 321.326866 -160.516386)
			(xy 321.407827 -160.415776) (xy 321.494827 -160.320341) (xy 321.587538 -160.230442) (xy 321.685608 -160.146421)
			(xy 321.788663 -160.068597) (xy 321.896314 -159.997265) (xy 322.008153 -159.932695) (xy 322.123754 -159.875133)
			(xy 322.242679 -159.824796) (xy 322.364478 -159.781876) (xy 322.488688 -159.746535) (xy 322.614837 -159.718908)
			(xy 322.742449 -159.699099) (xy 322.871038 -159.687183) (xy 323.000116 -159.683207) (xy 323.129194 -159.687183)
			(xy 323.257783 -159.699099) (xy 323.385395 -159.718908) (xy 323.511544 -159.746535) (xy 323.635754 -159.781876)
			(xy 323.757553 -159.824796) (xy 323.876478 -159.875133) (xy 323.992079 -159.932695) (xy 324.103918 -159.997265)
			(xy 324.211569 -160.068597) (xy 324.314624 -160.146421) (xy 324.412694 -160.230442) (xy 324.505405 -160.320341)
			(xy 324.592405 -160.415776) (xy 324.673366 -160.516386) (xy 324.74798 -160.621789) (xy 324.815963 -160.731586)
			(xy 324.877058 -160.84536) (xy 324.931033 -160.962679) (xy 324.977684 -161.083098) (xy 325.016833 -161.206161)
			(xy 325.048332 -161.3314) (xy 325.072061 -161.458341) (xy 325.087931 -161.586501) (xy 325.095881 -161.715396)
			(xy 325.096378 -161.779966) (xy 325.095881 -161.844536) (xy 325.087931 -161.973431) (xy 325.072061 -162.101591)
			(xy 325.048332 -162.228532) (xy 325.016833 -162.353771) (xy 324.977684 -162.476834) (xy 324.931033 -162.597253)
			(xy 324.877058 -162.714572) (xy 324.815963 -162.828346) (xy 324.74798 -162.938143) (xy 324.673366 -163.043546)
			(xy 324.592405 -163.144156) (xy 324.505405 -163.239591) (xy 324.412694 -163.32949) (xy 324.314624 -163.413511)
			(xy 324.211569 -163.491335) (xy 324.103918 -163.562667) (xy 323.992079 -163.627237) (xy 323.876478 -163.684799)
			(xy 323.757553 -163.735136) (xy 323.635754 -163.778056) (xy 323.511544 -163.813397) (xy 323.385395 -163.841024)
			(xy 323.257783 -163.860833) (xy 323.129194 -163.872749) (xy 323.000116 -163.876726) (xy 322.871038 -163.872749)
			(xy 322.742449 -163.860833) (xy 322.614837 -163.841024) (xy 322.488688 -163.813397) (xy 322.364478 -163.778056)
			(xy 322.242679 -163.735136) (xy 322.123754 -163.684799) (xy 322.008153 -163.627237) (xy 321.896314 -163.562667)
			(xy 321.788663 -163.491335) (xy 321.685608 -163.413511) (xy 321.587538 -163.32949) (xy 321.494827 -163.239591)
			(xy 321.407827 -163.144156) (xy 321.326866 -163.043546) (xy 321.252252 -162.938143) (xy 321.184269 -162.828346)
			(xy 321.123174 -162.714572) (xy 321.069199 -162.597253) (xy 321.022548 -162.476834) (xy 320.983399 -162.353771)
			(xy 320.9519 -162.228532) (xy 320.928171 -162.101591) (xy 320.912301 -161.973431) (xy 320.904351 -161.844536)
			(xy 159.495755 -161.844536) (xy 159.487805 -161.973431) (xy 159.471935 -162.101591) (xy 159.448206 -162.228532)
			(xy 159.416707 -162.353771) (xy 159.377558 -162.476834) (xy 159.330907 -162.597253) (xy 159.276932 -162.714572)
			(xy 159.215837 -162.828346) (xy 159.147854 -162.938143) (xy 159.07324 -163.043546) (xy 158.992279 -163.144156)
			(xy 158.905279 -163.239591) (xy 158.812568 -163.32949) (xy 158.714498 -163.413511) (xy 158.611443 -163.491335)
			(xy 158.503792 -163.562667) (xy 158.391953 -163.627237) (xy 158.276352 -163.684799) (xy 158.157427 -163.735136)
			(xy 158.035628 -163.778056) (xy 157.911418 -163.813397) (xy 157.785269 -163.841024) (xy 157.657657 -163.860833)
			(xy 157.529068 -163.872749) (xy 157.39999 -163.876726) (xy 157.270912 -163.872749) (xy 157.142323 -163.860833)
			(xy 157.014711 -163.841024) (xy 156.888562 -163.813397) (xy 156.764352 -163.778056) (xy 156.642553 -163.735136)
			(xy 156.523628 -163.684799) (xy 156.408027 -163.627237) (xy 156.296188 -163.562667) (xy 156.188537 -163.491335)
			(xy 156.085482 -163.413511) (xy 155.987412 -163.32949) (xy 155.894701 -163.239591) (xy 155.807701 -163.144156)
			(xy 155.72674 -163.043546) (xy 155.652126 -162.938143) (xy 155.584143 -162.828346) (xy 155.523048 -162.714572)
			(xy 155.469073 -162.597253) (xy 155.422422 -162.476834) (xy 155.383273 -162.353771) (xy 155.351774 -162.228532)
			(xy 155.328045 -162.101591) (xy 155.312175 -161.973431) (xy 155.304225 -161.844536) (xy 152.908 -161.844536)
			(xy 152.908 -164.77996) (xy 152.908508 -164.835769) (xy 152.916846 -164.947074) (xy 152.933479 -165.057444)
			(xy 152.958314 -165.166264) (xy 152.991211 -165.272922) (xy 153.031987 -165.376825) (xy 153.080414 -165.477389)
			(xy 153.13622 -165.574053) (xy 153.199095 -165.666277) (xy 153.268686 -165.753543) (xy 153.344603 -165.835366)
			(xy 153.426423 -165.911286) (xy 153.513688 -165.980879) (xy 153.605909 -166.043756) (xy 153.702572 -166.099566)
			(xy 153.803135 -166.147995) (xy 153.907036 -166.188775) (xy 154.013694 -166.221675) (xy 154.122512 -166.246513)
			(xy 154.232883 -166.263149) (xy 154.344187 -166.271491) (xy 154.399996 -166.271956)
		)
		(stroke
			(width 0)
			(type solid)
		)
		(fill yes)
		(layer "In4.Cu")
		(net "GND3")
	)
	(gr_poly
		(pts
			(xy 284.29966 -145.98396) (xy 284.309724 -145.983525) (xy 284.328309 -145.97579) (xy 284.335728 -145.968974)
			(xy 284.355352 -145.949872) (xy 284.399091 -145.916919) (xy 284.447092 -145.890559) (xy 284.49837 -145.871333)
			(xy 284.55187 -145.859637) (xy 284.606492 -145.855712) (xy 284.661114 -145.859637) (xy 284.714614 -145.871333)
			(xy 284.765892 -145.890559) (xy 284.813893 -145.916919) (xy 284.857632 -145.949872) (xy 284.877256 -145.968974)
			(xy 284.884656 -145.975814) (xy 284.903255 -145.983532) (xy 284.913324 -145.98396) (xy 289.37966 -145.98396)
			(xy 289.389724 -145.983525) (xy 289.408309 -145.97579) (xy 289.415728 -145.968974) (xy 289.435352 -145.949872)
			(xy 289.479091 -145.916919) (xy 289.527092 -145.890559) (xy 289.57837 -145.871333) (xy 289.63187 -145.859637)
			(xy 289.686492 -145.855712) (xy 289.741114 -145.859637) (xy 289.794614 -145.871333) (xy 289.845892 -145.890559)
			(xy 289.893893 -145.916919) (xy 289.937632 -145.949872) (xy 289.957256 -145.968974) (xy 289.964656 -145.975814)
			(xy 289.983255 -145.983532) (xy 289.993324 -145.98396) (xy 294.45966 -145.98396) (xy 294.469724 -145.983525)
			(xy 294.488309 -145.97579) (xy 294.495728 -145.968974) (xy 294.515352 -145.949872) (xy 294.559091 -145.916919)
			(xy 294.607092 -145.890559) (xy 294.65837 -145.871333) (xy 294.71187 -145.859637) (xy 294.766492 -145.855712)
			(xy 294.821114 -145.859637) (xy 294.874614 -145.871333) (xy 294.925892 -145.890559) (xy 294.973893 -145.916919)
			(xy 295.017632 -145.949872) (xy 295.037256 -145.968974) (xy 295.044656 -145.975814) (xy 295.063255 -145.983532)
			(xy 295.073324 -145.98396) (xy 299.53966 -145.98396) (xy 299.549724 -145.983525) (xy 299.568309 -145.97579)
			(xy 299.575728 -145.968974) (xy 299.595352 -145.949872) (xy 299.639091 -145.916919) (xy 299.687092 -145.890559)
			(xy 299.73837 -145.871333) (xy 299.79187 -145.859637) (xy 299.846492 -145.855712) (xy 299.901114 -145.859637)
			(xy 299.954614 -145.871333) (xy 300.005892 -145.890559) (xy 300.053893 -145.916919) (xy 300.097632 -145.949872)
			(xy 300.117256 -145.968974) (xy 300.124656 -145.975814) (xy 300.143255 -145.983532) (xy 300.153324 -145.98396)
			(xy 304.61966 -145.98396) (xy 304.629724 -145.983525) (xy 304.648309 -145.97579) (xy 304.655728 -145.968974)
			(xy 304.675352 -145.949872) (xy 304.719091 -145.916919) (xy 304.767092 -145.890559) (xy 304.81837 -145.871333)
			(xy 304.87187 -145.859637) (xy 304.926492 -145.855712) (xy 304.981114 -145.859637) (xy 305.034614 -145.871333)
			(xy 305.085892 -145.890559) (xy 305.133893 -145.916919) (xy 305.177632 -145.949872) (xy 305.197256 -145.968974)
			(xy 305.204656 -145.975814) (xy 305.223255 -145.983532) (xy 305.233324 -145.98396) (xy 309.69966 -145.98396)
			(xy 309.709724 -145.983525) (xy 309.728309 -145.97579) (xy 309.735728 -145.968974) (xy 309.755352 -145.949872)
			(xy 309.799091 -145.916919) (xy 309.847092 -145.890559) (xy 309.89837 -145.871333) (xy 309.95187 -145.859637)
			(xy 310.006492 -145.855712) (xy 310.061114 -145.859637) (xy 310.114614 -145.871333) (xy 310.165892 -145.890559)
			(xy 310.213893 -145.916919) (xy 310.257632 -145.949872) (xy 310.277256 -145.968974) (xy 310.284656 -145.975814)
			(xy 310.303255 -145.983532) (xy 310.313324 -145.98396) (xy 314.77966 -145.98396) (xy 314.789724 -145.983525)
			(xy 314.808309 -145.97579) (xy 314.815728 -145.968974) (xy 314.835352 -145.949872) (xy 314.879091 -145.916919)
			(xy 314.927092 -145.890559) (xy 314.97837 -145.871333) (xy 315.03187 -145.859637) (xy 315.086492 -145.855712)
			(xy 315.141114 -145.859637) (xy 315.194614 -145.871333) (xy 315.245892 -145.890559) (xy 315.293893 -145.916919)
			(xy 315.337632 -145.949872) (xy 315.357256 -145.968974) (xy 315.364656 -145.975814) (xy 315.383255 -145.983532)
			(xy 315.393324 -145.98396) (xy 319.85966 -145.98396) (xy 319.869724 -145.983525) (xy 319.888309 -145.97579)
			(xy 319.895728 -145.968974) (xy 319.915352 -145.949872) (xy 319.959091 -145.916919) (xy 320.007092 -145.890559)
			(xy 320.05837 -145.871333) (xy 320.11187 -145.859637) (xy 320.166492 -145.855712) (xy 320.221114 -145.859637)
			(xy 320.274614 -145.871333) (xy 320.325892 -145.890559) (xy 320.373893 -145.916919) (xy 320.417632 -145.949872)
			(xy 320.437256 -145.968974) (xy 320.444656 -145.975814) (xy 320.463255 -145.983532) (xy 320.473324 -145.98396)
			(xy 323.000116 -145.98396) (xy 323.090878 -145.983456) (xy 323.272215 -145.9752) (xy 323.452987 -145.958693)
			(xy 323.632819 -145.933967) (xy 323.811339 -145.901076) (xy 323.988175 -145.860086) (xy 324.16296 -145.811084)
			(xy 324.335332 -145.75417) (xy 324.504932 -145.689464) (xy 324.588378 -145.65376) (xy 324.597867 -145.649024)
			(xy 324.612172 -145.6334) (xy 324.616064 -145.623534) (xy 324.625004 -145.598756) (xy 324.648737 -145.55173)
			(xy 324.678708 -145.508412) (xy 324.714349 -145.469624) (xy 324.754982 -145.436103) (xy 324.799837 -145.408485)
			(xy 324.848062 -145.387294) (xy 324.898742 -145.372932) (xy 324.950914 -145.365672) (xy 324.977252 -145.365216)
			(xy 325.003105 -145.365667) (xy 325.054335 -145.37268) (xy 325.07936 -145.379186) (xy 325.089743 -145.381475)
			(xy 325.110745 -145.378323) (xy 325.12 -145.37309) (xy 325.196841 -145.324184) (xy 325.346483 -145.2203)
			(xy 325.491221 -145.109687) (xy 325.630752 -144.992575) (xy 325.764787 -144.869208) (xy 325.893043 -144.739846)
			(xy 326.015254 -144.604757) (xy 326.131164 -144.464225) (xy 326.240531 -144.318543) (xy 326.343126 -144.168015)
			(xy 326.438735 -144.012956) (xy 326.527158 -143.85369) (xy 326.608211 -143.690549) (xy 326.681723 -143.523875)
			(xy 326.71512 -143.439134) (xy 326.718374 -143.42906) (xy 326.717333 -143.407937) (xy 326.713088 -143.39824)
			(xy 326.700413 -143.371638) (xy 326.682512 -143.315497) (xy 326.673477 -143.257269) (xy 326.672956 -143.227806)
			(xy 326.67347 -143.199146) (xy 326.682044 -143.142469) (xy 326.699 -143.087714) (xy 326.723955 -143.03611)
			(xy 326.75635 -142.988821) (xy 326.795454 -142.946909) (xy 326.840387 -142.911319) (xy 326.86498 -142.89659)
			(xy 326.873993 -142.890942) (xy 326.886619 -142.873846) (xy 326.889364 -142.86357) (xy 326.907773 -142.778483)
			(xy 326.938051 -142.607027) (xy 326.960811 -142.434412) (xy 326.976012 -142.260967) (xy 326.983623 -142.087025)
			(xy 326.984106 -141.99997) (xy 326.984106 -140.252958) (xy 326.983658 -140.242802) (xy 326.975799 -140.224071)
			(xy 326.968866 -140.216636) (xy 326.949521 -140.196972) (xy 326.916123 -140.153071) (xy 326.889395 -140.104818)
			(xy 326.869893 -140.053219) (xy 326.858026 -139.99935) (xy 326.854039 -139.944334) (xy 326.858016 -139.889316)
			(xy 326.869874 -139.835445) (xy 326.889366 -139.783843) (xy 326.916086 -139.735586) (xy 326.949476 -139.691679)
			(xy 326.968866 -139.67206) (xy 326.97581 -139.664634) (xy 326.983658 -139.645897) (xy 326.984106 -139.635738)
			(xy 326.984106 -135.172958) (xy 326.983658 -135.162802) (xy 326.975799 -135.144071) (xy 326.968866 -135.136636)
			(xy 326.949521 -135.116972) (xy 326.916123 -135.073071) (xy 326.889395 -135.024818) (xy 326.869893 -134.973219)
			(xy 326.858026 -134.91935) (xy 326.854039 -134.864334) (xy 326.858016 -134.809316) (xy 326.869874 -134.755445)
			(xy 326.889366 -134.703843) (xy 326.916086 -134.655586) (xy 326.949476 -134.611679) (xy 326.968866 -134.59206)
			(xy 326.97581 -134.584634) (xy 326.983658 -134.565897) (xy 326.984106 -134.555738) (xy 326.984106 -130.092958)
			(xy 326.983658 -130.082802) (xy 326.975799 -130.064071) (xy 326.968866 -130.056636) (xy 326.949521 -130.036972)
			(xy 326.916123 -129.993071) (xy 326.889395 -129.944818) (xy 326.869893 -129.893219) (xy 326.858026 -129.83935)
			(xy 326.854039 -129.784334) (xy 326.858016 -129.729316) (xy 326.869874 -129.675445) (xy 326.889366 -129.623843)
			(xy 326.916086 -129.575586) (xy 326.949476 -129.531679) (xy 326.968866 -129.51206) (xy 326.97581 -129.504634)
			(xy 326.983658 -129.485897) (xy 326.984106 -129.475738) (xy 326.984106 -125.012958) (xy 326.983658 -125.002802)
			(xy 326.975799 -124.984071) (xy 326.968866 -124.976636) (xy 326.949521 -124.956972) (xy 326.916123 -124.913071)
			(xy 326.889395 -124.864818) (xy 326.869893 -124.813219) (xy 326.858026 -124.75935) (xy 326.854039 -124.704334)
			(xy 326.858016 -124.649316) (xy 326.869874 -124.595445) (xy 326.889366 -124.543843) (xy 326.916086 -124.495586)
			(xy 326.949476 -124.451679) (xy 326.968866 -124.43206) (xy 326.97581 -124.424634) (xy 326.983658 -124.405897)
			(xy 326.984106 -124.395738) (xy 326.984106 -119.932958) (xy 326.983658 -119.922802) (xy 326.975799 -119.904071)
			(xy 326.968866 -119.896636) (xy 326.949521 -119.876972) (xy 326.916123 -119.833071) (xy 326.889395 -119.784818)
			(xy 326.869893 -119.733219) (xy 326.858026 -119.67935) (xy 326.854039 -119.624334) (xy 326.858016 -119.569316)
			(xy 326.869874 -119.515445) (xy 326.889366 -119.463843) (xy 326.916086 -119.415586) (xy 326.949476 -119.371679)
			(xy 326.968866 -119.35206) (xy 326.97581 -119.344634) (xy 326.983658 -119.325897) (xy 326.984106 -119.315738)
			(xy 326.984106 -114.852958) (xy 326.983658 -114.842802) (xy 326.975799 -114.824071) (xy 326.968866 -114.816636)
			(xy 326.949521 -114.796972) (xy 326.916123 -114.753071) (xy 326.889395 -114.704818) (xy 326.869893 -114.653219)
			(xy 326.858026 -114.59935) (xy 326.854039 -114.544334) (xy 326.858016 -114.489316) (xy 326.869874 -114.435445)
			(xy 326.889366 -114.383843) (xy 326.916086 -114.335586) (xy 326.949476 -114.291679) (xy 326.968866 -114.27206)
			(xy 326.97581 -114.264634) (xy 326.983658 -114.245897) (xy 326.984106 -114.235738) (xy 326.984106 -109.772958)
			(xy 326.983658 -109.762802) (xy 326.975799 -109.744071) (xy 326.968866 -109.736636) (xy 326.949521 -109.716972)
			(xy 326.916123 -109.673071) (xy 326.889395 -109.624818) (xy 326.869893 -109.573219) (xy 326.858026 -109.51935)
			(xy 326.854039 -109.464334) (xy 326.858016 -109.409316) (xy 326.869874 -109.355445) (xy 326.889366 -109.303843)
			(xy 326.916086 -109.255586) (xy 326.949476 -109.211679) (xy 326.968866 -109.19206) (xy 326.97581 -109.184634)
			(xy 326.983658 -109.165897) (xy 326.984106 -109.155738) (xy 326.984106 -104.692958) (xy 326.983658 -104.682802)
			(xy 326.975799 -104.664071) (xy 326.968866 -104.656636) (xy 326.949521 -104.636972) (xy 326.916123 -104.593071)
			(xy 326.889395 -104.544818) (xy 326.869893 -104.493219) (xy 326.858026 -104.43935) (xy 326.854039 -104.384334)
			(xy 326.858016 -104.329316) (xy 326.869874 -104.275445) (xy 326.889366 -104.223843) (xy 326.916086 -104.175586)
			(xy 326.949476 -104.131679) (xy 326.968866 -104.11206) (xy 326.97581 -104.104634) (xy 326.983658 -104.085897)
			(xy 326.984106 -104.075738) (xy 326.984106 -99.612958) (xy 326.983658 -99.602802) (xy 326.975799 -99.584071)
			(xy 326.968866 -99.576636) (xy 326.949521 -99.556972) (xy 326.916123 -99.513071) (xy 326.889395 -99.464818)
			(xy 326.869893 -99.413219) (xy 326.858026 -99.35935) (xy 326.854039 -99.304334) (xy 326.858016 -99.249316)
			(xy 326.869874 -99.195445) (xy 326.889366 -99.143843) (xy 326.916086 -99.095586) (xy 326.949476 -99.051679)
			(xy 326.968866 -99.03206) (xy 326.97581 -99.024634) (xy 326.983658 -99.005897) (xy 326.984106 -98.995738)
			(xy 326.984106 -94.532958) (xy 326.983658 -94.522802) (xy 326.975799 -94.504071) (xy 326.968866 -94.496636)
			(xy 326.949521 -94.476972) (xy 326.916123 -94.433071) (xy 326.889395 -94.384818) (xy 326.869893 -94.333219)
			(xy 326.858026 -94.27935) (xy 326.854039 -94.224334) (xy 326.858016 -94.169316) (xy 326.869874 -94.115445)
			(xy 326.889366 -94.063843) (xy 326.916086 -94.015586) (xy 326.949476 -93.971679) (xy 326.968866 -93.95206)
			(xy 326.97581 -93.944634) (xy 326.983658 -93.925897) (xy 326.984106 -93.915738) (xy 326.984106 -89.452958)
			(xy 326.983658 -89.442802) (xy 326.975799 -89.424071) (xy 326.968866 -89.416636) (xy 326.949521 -89.396972)
			(xy 326.916123 -89.353071) (xy 326.889395 -89.304818) (xy 326.869893 -89.253219) (xy 326.858026 -89.19935)
			(xy 326.854039 -89.144334) (xy 326.858016 -89.089316) (xy 326.869874 -89.035445) (xy 326.889366 -88.983843)
			(xy 326.916086 -88.935586) (xy 326.949476 -88.891679) (xy 326.968866 -88.87206) (xy 326.97581 -88.864634)
			(xy 326.983658 -88.845897) (xy 326.984106 -88.835738) (xy 326.984106 -84.372958) (xy 326.983658 -84.362802)
			(xy 326.975799 -84.344071) (xy 326.968866 -84.336636) (xy 326.949521 -84.316972) (xy 326.916123 -84.273071)
			(xy 326.889395 -84.224818) (xy 326.869893 -84.173219) (xy 326.858026 -84.11935) (xy 326.854039 -84.064334)
			(xy 326.858016 -84.009316) (xy 326.869874 -83.955445) (xy 326.889366 -83.903843) (xy 326.916086 -83.855586)
			(xy 326.949476 -83.811679) (xy 326.968866 -83.79206) (xy 326.97581 -83.784634) (xy 326.983658 -83.765897)
			(xy 326.984106 -83.755738) (xy 326.984106 -79.292958) (xy 326.983658 -79.282802) (xy 326.975799 -79.264071)
			(xy 326.968866 -79.256636) (xy 326.949521 -79.236972) (xy 326.916123 -79.193071) (xy 326.889395 -79.144818)
			(xy 326.869893 -79.093219) (xy 326.858026 -79.03935) (xy 326.854039 -78.984334) (xy 326.858016 -78.929316)
			(xy 326.869874 -78.875445) (xy 326.889366 -78.823843) (xy 326.916086 -78.775586) (xy 326.949476 -78.731679)
			(xy 326.968866 -78.71206) (xy 326.97581 -78.704634) (xy 326.983658 -78.685897) (xy 326.984106 -78.675738)
			(xy 326.984106 -74.212958) (xy 326.983658 -74.202802) (xy 326.975799 -74.184071) (xy 326.968866 -74.176636)
			(xy 326.949521 -74.156972) (xy 326.916123 -74.113071) (xy 326.889395 -74.064818) (xy 326.869893 -74.013219)
			(xy 326.858026 -73.95935) (xy 326.854039 -73.904334) (xy 326.858016 -73.849316) (xy 326.869874 -73.795445)
			(xy 326.889366 -73.743843) (xy 326.916086 -73.695586) (xy 326.949476 -73.651679) (xy 326.968866 -73.63206)
			(xy 326.97581 -73.624634) (xy 326.983658 -73.605897) (xy 326.984106 -73.595738) (xy 326.984106 -69.132958)
			(xy 326.983658 -69.122802) (xy 326.975799 -69.104071) (xy 326.968866 -69.096636) (xy 326.949521 -69.076972)
			(xy 326.916123 -69.033071) (xy 326.889395 -68.984818) (xy 326.869893 -68.933219) (xy 326.858026 -68.87935)
			(xy 326.854039 -68.824334) (xy 326.858016 -68.769316) (xy 326.869874 -68.715445) (xy 326.889366 -68.663843)
			(xy 326.916086 -68.615586) (xy 326.949476 -68.571679) (xy 326.968866 -68.55206) (xy 326.97581 -68.544634)
			(xy 326.983658 -68.525897) (xy 326.984106 -68.515738) (xy 326.984106 -64.052958) (xy 326.983658 -64.042802)
			(xy 326.975799 -64.024071) (xy 326.968866 -64.016636) (xy 326.949521 -63.996972) (xy 326.916123 -63.953071)
			(xy 326.889395 -63.904818) (xy 326.869893 -63.853219) (xy 326.858026 -63.79935) (xy 326.854039 -63.744334)
			(xy 326.858016 -63.689316) (xy 326.869874 -63.635445) (xy 326.889366 -63.583843) (xy 326.916086 -63.535586)
			(xy 326.949476 -63.491679) (xy 326.968866 -63.47206) (xy 326.97581 -63.464634) (xy 326.983658 -63.445897)
			(xy 326.984106 -63.435738) (xy 326.984106 -58.972958) (xy 326.983658 -58.962802) (xy 326.975799 -58.944071)
			(xy 326.968866 -58.936636) (xy 326.949521 -58.916972) (xy 326.916123 -58.873071) (xy 326.889395 -58.824818)
			(xy 326.869893 -58.773219) (xy 326.858026 -58.71935) (xy 326.854039 -58.664334) (xy 326.858016 -58.609316)
			(xy 326.869874 -58.555445) (xy 326.889366 -58.503843) (xy 326.916086 -58.455586) (xy 326.949476 -58.411679)
			(xy 326.968866 -58.39206) (xy 326.97581 -58.384634) (xy 326.983658 -58.365897) (xy 326.984106 -58.355738)
			(xy 326.984106 -53.892958) (xy 326.983658 -53.882802) (xy 326.975799 -53.864071) (xy 326.968866 -53.856636)
			(xy 326.949521 -53.836972) (xy 326.916123 -53.793071) (xy 326.889395 -53.744818) (xy 326.869893 -53.693219)
			(xy 326.858026 -53.63935) (xy 326.854039 -53.584334) (xy 326.858016 -53.529316) (xy 326.869874 -53.475445)
			(xy 326.889366 -53.423843) (xy 326.916086 -53.375586) (xy 326.949476 -53.331679) (xy 326.968866 -53.31206)
			(xy 326.97581 -53.304634) (xy 326.983658 -53.285897) (xy 326.984106 -53.275738) (xy 326.984106 -48.812958)
			(xy 326.983658 -48.802802) (xy 326.975799 -48.784071) (xy 326.968866 -48.776636) (xy 326.949521 -48.756972)
			(xy 326.916123 -48.713071) (xy 326.889395 -48.664818) (xy 326.869893 -48.613219) (xy 326.858026 -48.55935)
			(xy 326.854039 -48.504334) (xy 326.858016 -48.449316) (xy 326.869874 -48.395445) (xy 326.889366 -48.343843)
			(xy 326.916086 -48.295586) (xy 326.949476 -48.251679) (xy 326.968866 -48.23206) (xy 326.97581 -48.224634)
			(xy 326.983658 -48.205897) (xy 326.984106 -48.195738) (xy 326.984106 -43.732958) (xy 326.983658 -43.722802)
			(xy 326.975799 -43.704071) (xy 326.968866 -43.696636) (xy 326.949521 -43.676972) (xy 326.916123 -43.633071)
			(xy 326.889395 -43.584818) (xy 326.869893 -43.533219) (xy 326.858026 -43.47935) (xy 326.854039 -43.424334)
			(xy 326.858016 -43.369316) (xy 326.869874 -43.315445) (xy 326.889366 -43.263843) (xy 326.916086 -43.215586)
			(xy 326.949476 -43.171679) (xy 326.968866 -43.15206) (xy 326.97581 -43.144634) (xy 326.983658 -43.125897)
			(xy 326.984106 -43.115738) (xy 326.984106 -38.652958) (xy 326.983658 -38.642802) (xy 326.975799 -38.624071)
			(xy 326.968866 -38.616636) (xy 326.949521 -38.596972) (xy 326.916123 -38.553071) (xy 326.889395 -38.504818)
			(xy 326.869893 -38.453219) (xy 326.858026 -38.39935) (xy 326.854039 -38.344334) (xy 326.858016 -38.289316)
			(xy 326.869874 -38.235445) (xy 326.889366 -38.183843) (xy 326.916086 -38.135586) (xy 326.949476 -38.091679)
			(xy 326.968866 -38.07206) (xy 326.97581 -38.064634) (xy 326.983658 -38.045897) (xy 326.984106 -38.035738)
			(xy 326.984106 -33.572958) (xy 326.983658 -33.562802) (xy 326.975799 -33.544071) (xy 326.968866 -33.536636)
			(xy 326.949521 -33.516972) (xy 326.916123 -33.473071) (xy 326.889395 -33.424818) (xy 326.869893 -33.373219)
			(xy 326.858026 -33.31935) (xy 326.854039 -33.264334) (xy 326.858016 -33.209316) (xy 326.869874 -33.155445)
			(xy 326.889366 -33.103843) (xy 326.916086 -33.055586) (xy 326.949476 -33.011679) (xy 326.968866 -32.99206)
			(xy 326.97581 -32.984634) (xy 326.983658 -32.965897) (xy 326.984106 -32.955738) (xy 326.984106 -28.492958)
			(xy 326.983658 -28.482802) (xy 326.975799 -28.464071) (xy 326.968866 -28.456636) (xy 326.949521 -28.436972)
			(xy 326.916123 -28.393071) (xy 326.889395 -28.344818) (xy 326.869893 -28.293219) (xy 326.858026 -28.23935)
			(xy 326.854039 -28.184334) (xy 326.858016 -28.129316) (xy 326.869874 -28.075445) (xy 326.889366 -28.023843)
			(xy 326.916086 -27.975586) (xy 326.949476 -27.931679) (xy 326.968866 -27.91206) (xy 326.97581 -27.904634)
			(xy 326.983658 -27.885897) (xy 326.984106 -27.875738) (xy 326.984106 -23.412958) (xy 326.983658 -23.402802)
			(xy 326.975799 -23.384071) (xy 326.968866 -23.376636) (xy 326.949521 -23.356972) (xy 326.916123 -23.313071)
			(xy 326.889395 -23.264818) (xy 326.869893 -23.213219) (xy 326.858026 -23.15935) (xy 326.854039 -23.104334)
			(xy 326.858016 -23.049316) (xy 326.869874 -22.995445) (xy 326.889366 -22.943843) (xy 326.916086 -22.895586)
			(xy 326.949476 -22.851679) (xy 326.968866 -22.83206) (xy 326.97581 -22.824634) (xy 326.983658 -22.805897)
			(xy 326.984106 -22.795738) (xy 326.984106 -18.332958) (xy 326.983658 -18.322802) (xy 326.975799 -18.304071)
			(xy 326.968866 -18.296636) (xy 326.949521 -18.276972) (xy 326.916123 -18.233071) (xy 326.889395 -18.184818)
			(xy 326.869893 -18.133219) (xy 326.858026 -18.07935) (xy 326.854039 -18.024334) (xy 326.858016 -17.969316)
			(xy 326.869874 -17.915445) (xy 326.889366 -17.863843) (xy 326.916086 -17.815586) (xy 326.949476 -17.771679)
			(xy 326.968866 -17.75206) (xy 326.97581 -17.744634) (xy 326.983658 -17.725897) (xy 326.984106 -17.715738)
			(xy 326.984106 -13.252958) (xy 326.983658 -13.242802) (xy 326.975799 -13.224071) (xy 326.968866 -13.216636)
			(xy 326.949521 -13.196972) (xy 326.916123 -13.153071) (xy 326.889395 -13.104818) (xy 326.869893 -13.053219)
			(xy 326.858026 -12.99935) (xy 326.854039 -12.944334) (xy 326.858016 -12.889316) (xy 326.869874 -12.835445)
			(xy 326.889366 -12.783843) (xy 326.916086 -12.735586) (xy 326.949476 -12.691679) (xy 326.968866 -12.67206)
			(xy 326.97581 -12.664634) (xy 326.983658 -12.645897) (xy 326.984106 -12.635738) (xy 326.984106 -8.172958)
			(xy 326.983658 -8.162802) (xy 326.975799 -8.144071) (xy 326.968866 -8.136636) (xy 326.949521 -8.116972)
			(xy 326.916123 -8.073071) (xy 326.889395 -8.024818) (xy 326.869893 -7.973219) (xy 326.858026 -7.91935)
			(xy 326.854039 -7.864334) (xy 326.858016 -7.809316) (xy 326.869874 -7.755445) (xy 326.889366 -7.703843)
			(xy 326.916086 -7.655586) (xy 326.949476 -7.611679) (xy 326.968866 -7.59206) (xy 326.97581 -7.584634)
			(xy 326.983658 -7.565897) (xy 326.984106 -7.555738) (xy 326.984106 -4.99999) (xy 326.98361 -4.910133)
			(xy 326.975521 -4.730602) (xy 326.959343 -4.551618) (xy 326.935107 -4.373545) (xy 326.902865 -4.196748)
			(xy 326.86268 -4.021584) (xy 326.814635 -3.848412) (xy 326.758828 -3.677583) (xy 326.727566 -3.593338)
			(xy 326.723304 -3.583534) (xy 326.708341 -3.5683) (xy 326.69861 -3.563874) (xy 326.67229 -3.552917)
			(xy 326.622964 -3.524333) (xy 326.578439 -3.488729) (xy 326.539706 -3.446898) (xy 326.507627 -3.399769)
			(xy 326.482916 -3.348393) (xy 326.466124 -3.293913) (xy 326.457622 -3.237541) (xy 326.457056 -3.209036)
			(xy 326.457672 -3.178331) (xy 326.467498 -3.117713) (xy 326.476614 -3.088386) (xy 326.479502 -3.078091)
			(xy 326.47754 -3.056824) (xy 326.472804 -3.047238) (xy 326.429529 -2.971254) (xy 326.337208 -2.822726)
			(xy 326.238457 -2.678392) (xy 326.133467 -2.538532) (xy 326.022439 -2.403414) (xy 325.905589 -2.273299)
			(xy 325.78314 -2.148438) (xy 325.655329 -2.029072) (xy 325.522403 -1.91543) (xy 325.384617 -1.807732)
			(xy 325.242237 -1.706184) (xy 325.095537 -1.610984) (xy 324.9448 -1.522313) (xy 324.790318 -1.440344)
			(xy 324.711568 -1.402334) (xy 324.701746 -1.398176) (xy 324.680442 -1.397665) (xy 324.67042 -1.401318)
			(xy 324.64725 -1.410425) (xy 324.59914 -1.423224) (xy 324.549771 -1.429638) (xy 324.524878 -1.43002)
			(xy 324.497978 -1.429558) (xy 324.444711 -1.421996) (xy 324.393034 -1.407026) (xy 324.343973 -1.384945)
			(xy 324.298501 -1.35619) (xy 324.25752 -1.321333) (xy 324.221842 -1.281063) (xy 324.192175 -1.236181)
			(xy 324.1802 -1.212088) (xy 324.175132 -1.2027) (xy 324.158992 -1.188788) (xy 324.148958 -1.185164)
			(xy 324.069123 -1.161579) (xy 323.907838 -1.120281) (xy 323.744967 -1.085757) (xy 323.580797 -1.058066)
			(xy 323.415613 -1.037258) (xy 323.249705 -1.023368) (xy 323.083361 -1.016421) (xy 323.000116 -1.016)
			(xy 318.971422 -1.016) (xy 318.961358 -1.016438) (xy 318.942774 -1.024172) (xy 318.935354 -1.030986)
			(xy 318.91571 -1.050208) (xy 318.871891 -1.083381) (xy 318.823765 -1.109922) (xy 318.772328 -1.129283)
			(xy 318.718645 -1.141062) (xy 318.663828 -1.145016) (xy 318.609011 -1.141062) (xy 318.555328 -1.129283)
			(xy 318.503891 -1.109922) (xy 318.455765 -1.083381) (xy 318.411946 -1.050208) (xy 318.392302 -1.030986)
			(xy 318.384908 -1.02413) (xy 318.366309 -1.016381) (xy 318.356234 -1.016) (xy 313.891422 -1.016)
			(xy 313.881358 -1.016438) (xy 313.862774 -1.024172) (xy 313.855354 -1.030986) (xy 313.83571 -1.050208)
			(xy 313.791891 -1.083381) (xy 313.743765 -1.109922) (xy 313.692328 -1.129283) (xy 313.638645 -1.141062)
			(xy 313.583828 -1.145016) (xy 313.529011 -1.141062) (xy 313.475328 -1.129283) (xy 313.423891 -1.109922)
			(xy 313.375765 -1.083381) (xy 313.331946 -1.050208) (xy 313.312302 -1.030986) (xy 313.304908 -1.02413)
			(xy 313.286309 -1.016381) (xy 313.276234 -1.016) (xy 308.811422 -1.016) (xy 308.801358 -1.016438)
			(xy 308.782774 -1.024172) (xy 308.775354 -1.030986) (xy 308.75571 -1.050208) (xy 308.711891 -1.083381)
			(xy 308.663765 -1.109922) (xy 308.612328 -1.129283) (xy 308.558645 -1.141062) (xy 308.503828 -1.145016)
			(xy 308.449011 -1.141062) (xy 308.395328 -1.129283) (xy 308.343891 -1.109922) (xy 308.295765 -1.083381)
			(xy 308.251946 -1.050208) (xy 308.232302 -1.030986) (xy 308.224908 -1.02413) (xy 308.206309 -1.016381)
			(xy 308.196234 -1.016) (xy 303.731422 -1.016) (xy 303.721358 -1.016438) (xy 303.702774 -1.024172)
			(xy 303.695354 -1.030986) (xy 303.67571 -1.050208) (xy 303.631891 -1.083381) (xy 303.583765 -1.109922)
			(xy 303.532328 -1.129283) (xy 303.478645 -1.141062) (xy 303.423828 -1.145016) (xy 303.369011 -1.141062)
			(xy 303.315328 -1.129283) (xy 303.263891 -1.109922) (xy 303.215765 -1.083381) (xy 303.171946 -1.050208)
			(xy 303.152302 -1.030986) (xy 303.144908 -1.02413) (xy 303.126309 -1.016381) (xy 303.116234 -1.016)
			(xy 298.651422 -1.016) (xy 298.641358 -1.016438) (xy 298.622774 -1.024172) (xy 298.615354 -1.030986)
			(xy 298.59571 -1.050208) (xy 298.551891 -1.083381) (xy 298.503765 -1.109922) (xy 298.452328 -1.129283)
			(xy 298.398645 -1.141062) (xy 298.343828 -1.145016) (xy 298.289011 -1.141062) (xy 298.235328 -1.129283)
			(xy 298.183891 -1.109922) (xy 298.135765 -1.083381) (xy 298.091946 -1.050208) (xy 298.072302 -1.030986)
			(xy 298.064908 -1.02413) (xy 298.046309 -1.016381) (xy 298.036234 -1.016) (xy 293.571422 -1.016)
			(xy 293.561358 -1.016438) (xy 293.542774 -1.024172) (xy 293.535354 -1.030986) (xy 293.51571 -1.050208)
			(xy 293.471891 -1.083381) (xy 293.423765 -1.109922) (xy 293.372328 -1.129283) (xy 293.318645 -1.141062)
			(xy 293.263828 -1.145016) (xy 293.209011 -1.141062) (xy 293.155328 -1.129283) (xy 293.103891 -1.109922)
			(xy 293.055765 -1.083381) (xy 293.011946 -1.050208) (xy 292.992302 -1.030986) (xy 292.984908 -1.02413)
			(xy 292.966309 -1.016381) (xy 292.956234 -1.016) (xy 288.491422 -1.016) (xy 288.481358 -1.016438)
			(xy 288.462774 -1.024172) (xy 288.455354 -1.030986) (xy 288.43571 -1.050208) (xy 288.391891 -1.083381)
			(xy 288.343765 -1.109922) (xy 288.292328 -1.129283) (xy 288.238645 -1.141062) (xy 288.183828 -1.145016)
			(xy 288.129011 -1.141062) (xy 288.075328 -1.129283) (xy 288.023891 -1.109922) (xy 287.975765 -1.083381)
			(xy 287.931946 -1.050208) (xy 287.912302 -1.030986) (xy 287.904908 -1.02413) (xy 287.886309 -1.016381)
			(xy 287.876234 -1.016) (xy 283.411422 -1.016) (xy 283.401358 -1.016438) (xy 283.382774 -1.024172)
			(xy 283.375354 -1.030986) (xy 283.35571 -1.050208) (xy 283.311891 -1.083381) (xy 283.263765 -1.109922)
			(xy 283.212328 -1.129283) (xy 283.158645 -1.141062) (xy 283.103828 -1.145016) (xy 283.049011 -1.141062)
			(xy 282.995328 -1.129283) (xy 282.943891 -1.109922) (xy 282.895765 -1.083381) (xy 282.851946 -1.050208)
			(xy 282.832302 -1.030986) (xy 282.824908 -1.02413) (xy 282.806309 -1.016381) (xy 282.796234 -1.016)
			(xy 278.331422 -1.016) (xy 278.321358 -1.016438) (xy 278.302774 -1.024172) (xy 278.295354 -1.030986)
			(xy 278.27571 -1.050208) (xy 278.231891 -1.083381) (xy 278.183765 -1.109922) (xy 278.132328 -1.129283)
			(xy 278.078645 -1.141062) (xy 278.023828 -1.145016) (xy 277.969011 -1.141062) (xy 277.915328 -1.129283)
			(xy 277.863891 -1.109922) (xy 277.815765 -1.083381) (xy 277.771946 -1.050208) (xy 277.752302 -1.030986)
			(xy 277.744908 -1.02413) (xy 277.726309 -1.016381) (xy 277.716234 -1.016) (xy 274.551394 -1.016)
			(xy 274.541324 -1.016424) (xy 274.522721 -1.02414) (xy 274.515326 -1.030986) (xy 273.826986 -1.719326)
			(xy 273.820134 -1.726722) (xy 273.812396 -1.745321) (xy 273.812 -1.755394) (xy 273.812 -20.32) (xy 273.811479 -20.35326)
			(xy 273.802791 -20.41921) (xy 273.785566 -20.483461) (xy 273.760097 -20.544912) (xy 273.726821 -20.602511)
			(xy 273.686308 -20.655271) (xy 273.663156 -20.679156) (xy 273.344951 -20.997361) (xy 276.478742 -20.997361)
			(xy 276.478742 -20.912639) (xy 276.486795 -20.828302) (xy 276.502829 -20.745112) (xy 276.526697 -20.663822)
			(xy 276.558185 -20.58517) (xy 276.597007 -20.509867) (xy 276.64281 -20.438595) (xy 276.695181 -20.371999)
			(xy 276.753646 -20.310684) (xy 276.817674 -20.255203) (xy 276.886686 -20.20606) (xy 276.960056 -20.1637)
			(xy 277.037121 -20.128505) (xy 277.117183 -20.100796) (xy 277.199516 -20.080822) (xy 277.283375 -20.068765)
			(xy 277.368 -20.064734) (xy 277.452625 -20.068765) (xy 277.536484 -20.080822) (xy 277.618817 -20.100796)
			(xy 277.698879 -20.128505) (xy 277.775944 -20.1637) (xy 277.849314 -20.20606) (xy 277.918326 -20.255203)
			(xy 277.982354 -20.310684) (xy 278.040819 -20.371999) (xy 278.09319 -20.438595) (xy 278.138993 -20.509867)
			(xy 278.177815 -20.58517) (xy 278.209303 -20.663822) (xy 278.233171 -20.745112) (xy 278.249205 -20.828302)
			(xy 278.257258 -20.912639) (xy 278.257762 -20.955) (xy 278.257258 -20.997361) (xy 278.249205 -21.081698)
			(xy 278.233171 -21.164888) (xy 278.209303 -21.246178) (xy 278.177815 -21.32483) (xy 278.138993 -21.400133)
			(xy 278.09319 -21.471405) (xy 278.040819 -21.538001) (xy 277.982354 -21.599316) (xy 277.918326 -21.654797)
			(xy 277.849314 -21.70394) (xy 277.775944 -21.7463) (xy 277.698879 -21.781495) (xy 277.618817 -21.809204)
			(xy 277.536484 -21.829178) (xy 277.452625 -21.841235) (xy 277.368 -21.845267) (xy 277.283375 -21.841235)
			(xy 277.199516 -21.829178) (xy 277.117183 -21.809204) (xy 277.037121 -21.781495) (xy 276.960056 -21.7463)
			(xy 276.886686 -21.70394) (xy 276.817674 -21.654797) (xy 276.753646 -21.599316) (xy 276.695181 -21.538001)
			(xy 276.64281 -21.471405) (xy 276.597007 -21.400133) (xy 276.558185 -21.32483) (xy 276.526697 -21.246178)
			(xy 276.502829 -21.164888) (xy 276.486795 -21.081698) (xy 276.478742 -20.997361) (xy 273.344951 -20.997361)
			(xy 272.266156 -22.076156) (xy 272.242276 -22.099312) (xy 272.189512 -22.139818) (xy 272.131911 -22.173089)
			(xy 272.07046 -22.198553) (xy 272.006209 -22.215775) (xy 271.940259 -22.224461) (xy 271.907 -22.225)
			(xy 216.410794 -22.225) (xy 216.400724 -22.225424) (xy 216.382121 -22.23314) (xy 216.374726 -22.239986)
			(xy 215.559386 -23.055326) (xy 215.552534 -23.062722) (xy 215.544796 -23.081321) (xy 215.54451 -23.0886)
			(xy 271.702788 -23.0886) (xy 271.706818 -23.003999) (xy 271.718871 -22.920164) (xy 271.738839 -22.837855)
			(xy 271.766541 -22.757816) (xy 271.801725 -22.680773) (xy 271.844074 -22.607423) (xy 271.893203 -22.538431)
			(xy 271.948668 -22.474421) (xy 272.009966 -22.415973) (xy 272.076542 -22.363617) (xy 272.147794 -22.317827)
			(xy 272.223075 -22.279016) (xy 272.301705 -22.247537) (xy 272.382972 -22.223676) (xy 272.466138 -22.207647)
			(xy 272.550452 -22.199596) (xy 272.5928 -22.199092) (xy 272.635108 -22.199589) (xy 272.719344 -22.207592)
			(xy 272.80244 -22.223553) (xy 272.883646 -22.24733) (xy 272.962229 -22.278706) (xy 273.037479 -22.317399)
			(xy 273.073368 -22.339808) (xy 273.081757 -22.344691) (xy 273.1008 -22.348362) (xy 273.119843 -22.344691)
			(xy 273.128232 -22.339808) (xy 273.164109 -22.317376) (xy 273.239354 -22.278665) (xy 273.317937 -22.247279)
			(xy 273.399147 -22.223503) (xy 273.482249 -22.20755) (xy 273.56649 -22.199566) (xy 273.6088 -22.199092)
			(xy 273.651148 -22.199596) (xy 273.735462 -22.207647) (xy 273.818628 -22.223676) (xy 273.899895 -22.247537)
			(xy 273.978525 -22.279016) (xy 274.053806 -22.317827) (xy 274.125058 -22.363617) (xy 274.191634 -22.415973)
			(xy 274.252932 -22.474421) (xy 274.308397 -22.538431) (xy 274.357526 -22.607423) (xy 274.399875 -22.680773)
			(xy 274.435059 -22.757816) (xy 274.462761 -22.837855) (xy 274.482729 -22.920164) (xy 274.494782 -23.003999)
			(xy 274.498813 -23.0886) (xy 274.494782 -23.173201) (xy 274.482729 -23.257036) (xy 274.462761 -23.339345)
			(xy 274.435059 -23.419384) (xy 274.399875 -23.496427) (xy 274.357526 -23.569777) (xy 274.308397 -23.638769)
			(xy 274.252932 -23.702779) (xy 274.191634 -23.761227) (xy 274.125058 -23.813583) (xy 274.053806 -23.859373)
			(xy 273.978525 -23.898184) (xy 273.899895 -23.929663) (xy 273.818628 -23.953524) (xy 273.735462 -23.969553)
			(xy 273.651148 -23.977604) (xy 273.6088 -23.978108) (xy 273.566492 -23.977611) (xy 273.482256 -23.969608)
			(xy 273.39916 -23.953647) (xy 273.317954 -23.92987) (xy 273.239371 -23.898494) (xy 273.164121 -23.859801)
			(xy 273.128232 -23.837392) (xy 273.119843 -23.832509) (xy 273.1008 -23.828838) (xy 273.081757 -23.832509)
			(xy 273.073368 -23.837392) (xy 273.037491 -23.859824) (xy 272.962246 -23.898535) (xy 272.883663 -23.929921)
			(xy 272.802453 -23.953697) (xy 272.719351 -23.96965) (xy 272.63511 -23.977634) (xy 272.5928 -23.978108)
			(xy 272.550452 -23.977604) (xy 272.466138 -23.969553) (xy 272.382972 -23.953524) (xy 272.301705 -23.929663)
			(xy 272.223075 -23.898184) (xy 272.147794 -23.859373) (xy 272.076542 -23.813583) (xy 272.009966 -23.761227)
			(xy 271.948668 -23.702779) (xy 271.893203 -23.638769) (xy 271.844074 -23.569777) (xy 271.801725 -23.496427)
			(xy 271.766541 -23.419384) (xy 271.738839 -23.339345) (xy 271.718871 -23.257036) (xy 271.706818 -23.173201)
			(xy 271.702788 -23.0886) (xy 215.54451 -23.0886) (xy 215.5444 -23.091394) (xy 215.5444 -38.249606)
			(xy 215.544824 -38.259676) (xy 215.55254 -38.278279) (xy 215.559386 -38.285674) (xy 216.120726 -38.847014)
			(xy 216.128122 -38.853866) (xy 216.146721 -38.861604) (xy 216.156794 -38.862) (xy 239.316006 -38.862)
			(xy 239.326076 -38.861576) (xy 239.344679 -38.85386) (xy 239.352074 -38.847014) (xy 246.554244 -31.644844)
			(xy 246.578124 -31.621688) (xy 246.630888 -31.581182) (xy 246.688489 -31.547911) (xy 246.74994 -31.522447)
			(xy 246.814191 -31.505225) (xy 246.880141 -31.496539) (xy 246.9134 -31.496) (xy 269.0114 -31.496)
			(xy 269.04466 -31.496521) (xy 269.11061 -31.505209) (xy 269.174861 -31.522434) (xy 269.236312 -31.547903)
			(xy 269.293911 -31.581179) (xy 269.346671 -31.621692) (xy 269.370556 -31.644844) (xy 270.603726 -32.878014)
			(xy 270.611122 -32.884866) (xy 270.629721 -32.892604) (xy 270.639794 -32.893) (xy 274.523708 -32.893)
			(xy 274.55114 -32.871664) (xy 274.555458 -32.854392) (xy 274.566141 -32.813623) (xy 274.594193 -32.734143)
			(xy 274.629637 -32.657672) (xy 274.672156 -32.584897) (xy 274.721367 -32.51647) (xy 274.776831 -32.453005)
			(xy 274.838049 -32.39507) (xy 274.904472 -32.343186) (xy 274.975505 -32.297818) (xy 275.050512 -32.259372)
			(xy 275.128818 -32.228193) (xy 275.209723 -32.20456) (xy 275.2925 -32.188687) (xy 275.376407 -32.180714)
			(xy 275.460693 -32.180714) (xy 275.5446 -32.188687) (xy 275.627377 -32.20456) (xy 275.708282 -32.228193)
			(xy 275.786588 -32.259372) (xy 275.861595 -32.297818) (xy 275.932628 -32.343186) (xy 275.999051 -32.39507)
			(xy 276.060269 -32.453005) (xy 276.115733 -32.51647) (xy 276.164944 -32.584897) (xy 276.207463 -32.657672)
			(xy 276.242907 -32.734143) (xy 276.270959 -32.813623) (xy 276.281642 -32.854392) (xy 276.28596 -32.871664)
			(xy 276.313392 -32.893) (xy 282.369006 -32.893) (xy 282.379076 -32.892576) (xy 282.397679 -32.88486)
			(xy 282.405074 -32.878014) (xy 282.641802 -32.641286) (xy 282.646374 -32.607504) (xy 282.637992 -32.592518)
			(xy 282.616135 -32.552502) (xy 282.579779 -32.468878) (xy 282.55217 -32.381972) (xy 282.533597 -32.292698)
			(xy 282.524257 -32.201993) (xy 282.523692 -32.1564) (xy 282.52419 -32.113834) (xy 282.532324 -32.029091)
			(xy 282.548517 -31.945512) (xy 282.572621 -31.863864) (xy 282.604416 -31.784891) (xy 282.643611 -31.709318)
			(xy 282.689847 -31.637835) (xy 282.7427 -31.571097) (xy 282.801689 -31.509713) (xy 282.866272 -31.454246)
			(xy 282.935859 -31.405204) (xy 283.009814 -31.363034) (xy 283.087459 -31.328123) (xy 283.168084 -31.30079)
			(xy 283.250952 -31.281285) (xy 283.293058 -31.27502) (xy 283.312108 -31.27248) (xy 283.337 -31.244032)
			(xy 283.337 -30.099) (xy 283.337521 -30.06574) (xy 283.346209 -29.99979) (xy 283.363434 -29.935539)
			(xy 283.388903 -29.874088) (xy 283.422179 -29.816489) (xy 283.462692 -29.763729) (xy 283.485844 -29.739844)
			(xy 283.993844 -29.231844) (xy 284.017724 -29.208688) (xy 284.070488 -29.168182) (xy 284.128089 -29.134911)
			(xy 284.18954 -29.109447) (xy 284.253791 -29.092225) (xy 284.319741 -29.083539) (xy 284.353 -29.083)
			(xy 289.296856 -29.083) (xy 289.330117 -29.083519) (xy 289.39607 -29.092201) (xy 289.460325 -29.109422)
			(xy 289.52178 -29.134887) (xy 289.579382 -29.16816) (xy 289.632147 -29.208671) (xy 289.656012 -29.231844)
			(xy 290.046156 -29.621988) (xy 290.069315 -29.645867) (xy 290.109828 -29.698629) (xy 290.143104 -29.756229)
			(xy 290.168575 -29.817681) (xy 290.185804 -29.881932) (xy 290.194497 -29.947883) (xy 290.195 -29.981144)
			(xy 290.195 -30.300422) (xy 290.195427 -30.31049) (xy 290.203147 -30.329089) (xy 290.209986 -30.33649)
			(xy 290.229048 -30.356107) (xy 290.261928 -30.399819) (xy 290.288228 -30.447779) (xy 290.307409 -30.499004)
			(xy 290.319077 -30.552443) (xy 290.322993 -30.607) (xy 290.319077 -30.661557) (xy 290.307409 -30.714996)
			(xy 290.288228 -30.766221) (xy 290.261928 -30.814181) (xy 290.229048 -30.857893) (xy 290.209986 -30.87751)
			(xy 290.203132 -30.884905) (xy 290.195387 -30.903504) (xy 290.195 -30.913578) (xy 290.195 -31.297372)
			(xy 290.195436 -31.307436) (xy 290.203169 -31.326022) (xy 290.209986 -31.33344) (xy 290.229051 -31.353057)
			(xy 290.261939 -31.39677) (xy 290.288246 -31.444732) (xy 290.307433 -31.49596) (xy 290.319107 -31.549402)
			(xy 290.323029 -31.603965) (xy 290.319117 -31.658528) (xy 290.307453 -31.711973) (xy 290.288275 -31.763204)
			(xy 290.261977 -31.811171) (xy 290.229098 -31.85489) (xy 290.209986 -31.87446) (xy 290.20314 -31.881858)
			(xy 290.195414 -31.900457) (xy 290.195 -31.910528) (xy 290.195 -33.875472) (xy 290.195436 -33.885536)
			(xy 290.203169 -33.904122) (xy 290.209986 -33.91154) (xy 290.229051 -33.931157) (xy 290.261939 -33.97487)
			(xy 290.288246 -34.022832) (xy 290.307433 -34.07406) (xy 290.319107 -34.127502) (xy 290.323029 -34.182065)
			(xy 290.319117 -34.236628) (xy 290.307453 -34.290073) (xy 290.288275 -34.341304) (xy 290.261977 -34.389271)
			(xy 290.229098 -34.43299) (xy 290.209986 -34.45256) (xy 290.20314 -34.459958) (xy 290.195414 -34.478557)
			(xy 290.195 -34.488628) (xy 290.195 -35.018161) (xy 293.293542 -35.018161) (xy 293.293542 -34.933439)
			(xy 293.301595 -34.849102) (xy 293.317629 -34.765912) (xy 293.341497 -34.684622) (xy 293.372985 -34.60597)
			(xy 293.411807 -34.530667) (xy 293.45761 -34.459395) (xy 293.509981 -34.392799) (xy 293.568446 -34.331484)
			(xy 293.632474 -34.276003) (xy 293.701486 -34.22686) (xy 293.774856 -34.1845) (xy 293.851921 -34.149305)
			(xy 293.931983 -34.121596) (xy 294.014316 -34.101622) (xy 294.098175 -34.089565) (xy 294.1828 -34.085534)
			(xy 294.267425 -34.089565) (xy 294.351284 -34.101622) (xy 294.433617 -34.121596) (xy 294.513679 -34.149305)
			(xy 294.590744 -34.1845) (xy 294.664114 -34.22686) (xy 294.733126 -34.276003) (xy 294.797154 -34.331484)
			(xy 294.855619 -34.392799) (xy 294.90799 -34.459395) (xy 294.953793 -34.530667) (xy 294.992615 -34.60597)
			(xy 295.024103 -34.684622) (xy 295.047971 -34.765912) (xy 295.064005 -34.849102) (xy 295.072058 -34.933439)
			(xy 295.072562 -34.9758) (xy 295.072058 -35.018161) (xy 295.064005 -35.102498) (xy 295.047971 -35.185688)
			(xy 295.024103 -35.266978) (xy 294.992615 -35.34563) (xy 294.953793 -35.420933) (xy 294.90799 -35.492205)
			(xy 294.855619 -35.558801) (xy 294.797154 -35.620116) (xy 294.733126 -35.675597) (xy 294.664114 -35.72474)
			(xy 294.590744 -35.7671) (xy 294.513679 -35.802295) (xy 294.433617 -35.830004) (xy 294.351284 -35.849978)
			(xy 294.267425 -35.862035) (xy 294.1828 -35.866067) (xy 294.098175 -35.862035) (xy 294.014316 -35.849978)
			(xy 293.931983 -35.830004) (xy 293.851921 -35.802295) (xy 293.774856 -35.7671) (xy 293.701486 -35.72474)
			(xy 293.632474 -35.675597) (xy 293.568446 -35.620116) (xy 293.509981 -35.558801) (xy 293.45761 -35.492205)
			(xy 293.411807 -35.420933) (xy 293.372985 -35.34563) (xy 293.341497 -35.266978) (xy 293.317629 -35.185688)
			(xy 293.301595 -35.102498) (xy 293.293542 -35.018161) (xy 290.195 -35.018161) (xy 290.195 -39.900606)
			(xy 290.195424 -39.910676) (xy 290.20314 -39.929279) (xy 290.209986 -39.936674) (xy 290.644326 -40.371014)
			(xy 290.651722 -40.377866) (xy 290.670321 -40.385604) (xy 290.680394 -40.386) (xy 294.767 -40.386)
			(xy 294.80026 -40.386521) (xy 294.86621 -40.395209) (xy 294.930461 -40.412434) (xy 294.991912 -40.437903)
			(xy 295.049511 -40.471179) (xy 295.102271 -40.511692) (xy 295.126156 -40.534844) (xy 296.446956 -41.855644)
			(xy 296.470112 -41.879524) (xy 296.510618 -41.932288) (xy 296.543889 -41.989889) (xy 296.569353 -42.05134)
			(xy 296.586575 -42.115591) (xy 296.591345 -42.151808) (xy 298.200572 -42.151808) (xy 298.201202 -42.105406)
			(xy 298.210891 -42.013109) (xy 298.230144 -41.922323) (xy 298.258751 -41.834038) (xy 298.277026 -41.791382)
			(xy 298.280825 -41.781438) (xy 298.280828 -41.760177) (xy 298.277026 -41.750234) (xy 298.258766 -41.707572)
			(xy 298.230172 -41.619284) (xy 298.210915 -41.528502) (xy 298.201201 -41.436209) (xy 298.200572 -41.389808)
			(xy 298.20106 -41.348698) (xy 298.208647 -41.266829) (xy 298.223757 -41.18601) (xy 298.24626 -41.106929)
			(xy 298.275966 -41.030263) (xy 298.312619 -40.956666) (xy 298.355909 -40.886765) (xy 298.405464 -40.821157)
			(xy 298.460862 -40.760402) (xy 298.521631 -40.705019) (xy 298.587251 -40.655481) (xy 298.657163 -40.612209)
			(xy 298.73077 -40.575574) (xy 298.807444 -40.545888) (xy 298.88653 -40.523405) (xy 298.967353 -40.508316)
			(xy 299.049224 -40.50075) (xy 299.090334 -40.5003) (xy 299.136729 -40.500905) (xy 299.229017 -40.510544)
			(xy 299.319801 -40.529733) (xy 299.408095 -40.558265) (xy 299.45076 -40.5765) (xy 299.460702 -40.580306)
			(xy 299.481966 -40.580306) (xy 299.491908 -40.5765) (xy 299.534566 -40.558244) (xy 299.62286 -40.529703)
			(xy 299.713646 -40.510513) (xy 299.805938 -40.500883) (xy 299.852334 -40.5003) (xy 299.890619 -40.500677)
			(xy 299.966907 -40.507219) (xy 300.04235 -40.520304) (xy 300.116386 -40.539833) (xy 300.152562 -40.55237)
			(xy 300.160999 -40.555021) (xy 300.178669 -40.555021) (xy 300.187106 -40.55237) (xy 300.223291 -40.539863)
			(xy 300.297328 -40.520351) (xy 300.372767 -40.507266) (xy 300.449051 -40.500704) (xy 300.487334 -40.5003)
			(xy 300.525619 -40.500677) (xy 300.601907 -40.507219) (xy 300.67735 -40.520304) (xy 300.751386 -40.539833)
			(xy 300.787562 -40.55237) (xy 300.795999 -40.555021) (xy 300.813669 -40.555021) (xy 300.822106 -40.55237)
			(xy 300.858291 -40.539863) (xy 300.932328 -40.520351) (xy 301.007767 -40.507266) (xy 301.084051 -40.500704)
			(xy 301.122334 -40.5003) (xy 301.164317 -40.500787) (xy 301.247912 -40.508666) (xy 301.330395 -40.524379)
			(xy 301.411032 -40.547787) (xy 301.450248 -40.562784) (xy 301.460692 -40.566294) (xy 301.482669 -40.565127)
			(xy 301.492666 -40.560498) (xy 301.531214 -40.540705) (xy 301.611385 -40.507804) (xy 301.694374 -40.482849)
			(xy 301.779394 -40.466076) (xy 301.865642 -40.457644) (xy 301.908972 -40.45712) (xy 301.950076 -40.457579)
			(xy 302.031932 -40.465162) (xy 302.11274 -40.480265) (xy 302.191809 -40.502761) (xy 302.268465 -40.532456)
			(xy 302.342055 -40.569098) (xy 302.411949 -40.612374) (xy 302.477552 -40.661914) (xy 302.538303 -40.717297)
			(xy 302.593686 -40.778048) (xy 302.643226 -40.843651) (xy 302.686502 -40.913545) (xy 302.723144 -40.987135)
			(xy 302.752839 -41.063791) (xy 302.775335 -41.14286) (xy 302.790438 -41.223668) (xy 302.798021 -41.305524)
			(xy 302.79848 -41.346628) (xy 302.798042 -41.387131) (xy 302.7907 -41.467804) (xy 302.776059 -41.547476)
			(xy 302.754242 -41.625489) (xy 302.725429 -41.701197) (xy 302.708056 -41.737788) (xy 302.703447 -41.748346)
			(xy 302.703335 -41.771364) (xy 302.707802 -41.781984) (xy 302.724373 -41.817832) (xy 302.751818 -41.891892)
			(xy 302.772586 -41.968094) (xy 302.786514 -42.045837) (xy 302.793492 -42.124509) (xy 302.793908 -42.164)
			(xy 302.793433 -42.205102) (xy 302.785848 -42.286957) (xy 302.770743 -42.367762) (xy 302.748247 -42.446829)
			(xy 302.718551 -42.523483) (xy 302.681909 -42.59707) (xy 302.638634 -42.666962) (xy 302.589094 -42.732563)
			(xy 302.533713 -42.793313) (xy 302.472963 -42.848694) (xy 302.407362 -42.898234) (xy 302.33747 -42.941509)
			(xy 302.263883 -42.978151) (xy 302.187229 -43.007847) (xy 302.108162 -43.030343) (xy 302.027357 -43.045448)
			(xy 301.945502 -43.053033) (xy 301.9044 -43.053508) (xy 301.864854 -43.053073) (xy 301.786073 -43.046064)
			(xy 301.708224 -43.032091) (xy 301.631923 -43.011266) (xy 301.55777 -42.983752) (xy 301.521876 -42.967148)
			(xy 301.511763 -42.962977) (xy 301.489915 -42.962698) (xy 301.479712 -42.96664) (xy 301.437359 -42.984532)
			(xy 301.349773 -43.012514) (xy 301.25977 -43.031323) (xy 301.168308 -43.040759) (xy 301.122334 -43.041316)
			(xy 301.084049 -43.040947) (xy 301.00776 -43.034403) (xy 300.932318 -43.021316) (xy 300.858282 -43.001784)
			(xy 300.822106 -42.989246) (xy 300.813669 -42.986595) (xy 300.795999 -42.986595) (xy 300.787562 -42.989246)
			(xy 300.751381 -43.001762) (xy 300.677342 -43.021272) (xy 300.601902 -43.034355) (xy 300.525617 -43.040913)
			(xy 300.487334 -43.041316) (xy 300.449049 -43.040947) (xy 300.37276 -43.034403) (xy 300.297318 -43.021316)
			(xy 300.223282 -43.001784) (xy 300.187106 -42.989246) (xy 300.178669 -42.986595) (xy 300.160999 -42.986595)
			(xy 300.152562 -42.989246) (xy 300.116381 -43.001762) (xy 300.042342 -43.021272) (xy 299.966902 -43.034355)
			(xy 299.890617 -43.040913) (xy 299.852334 -43.041316) (xy 299.805939 -43.04072) (xy 299.713651 -43.031079)
			(xy 299.622867 -43.011887) (xy 299.534573 -42.983352) (xy 299.491908 -42.965116) (xy 299.481966 -42.96131)
			(xy 299.460702 -42.96131) (xy 299.45076 -42.965116) (xy 299.408093 -42.98335) (xy 299.319803 -43.011897)
			(xy 299.229019 -43.031093) (xy 299.13673 -43.040729) (xy 299.090334 -43.041316) (xy 299.049226 -43.040855)
			(xy 298.967362 -43.033273) (xy 298.886546 -43.018171) (xy 298.807467 -42.995678) (xy 298.730802 -42.965985)
			(xy 298.657202 -42.929345) (xy 298.587297 -42.886072) (xy 298.521682 -42.836534) (xy 298.460917 -42.781154)
			(xy 298.40552 -42.720404) (xy 298.355965 -42.654803) (xy 298.312673 -42.584909) (xy 298.276013 -42.51132)
			(xy 298.246299 -42.434662) (xy 298.223784 -42.35559) (xy 298.20866 -42.274778) (xy 298.201056 -42.192915)
			(xy 298.200572 -42.151808) (xy 296.591345 -42.151808) (xy 296.595261 -42.181541) (xy 296.5958 -42.2148)
			(xy 296.5958 -44.390144) (xy 307.777633 -44.390144) (xy 307.777633 -44.219788) (xy 307.785618 -44.04962)
			(xy 307.80157 -43.880013) (xy 307.825455 -43.711341) (xy 307.857219 -43.543973) (xy 307.896794 -43.378278)
			(xy 307.944091 -43.21462) (xy 307.999008 -43.053359) (xy 308.061423 -42.894849) (xy 308.131199 -42.739439)
			(xy 308.208182 -42.587471) (xy 308.292204 -42.439277) (xy 308.38308 -42.295185) (xy 308.48061 -42.155511)
			(xy 308.58458 -42.020562) (xy 308.694761 -41.890634) (xy 308.81091 -41.766014) (xy 308.932774 -41.646975)
			(xy 309.060082 -41.533779) (xy 309.192557 -41.426674) (xy 309.329907 -41.325897) (xy 309.471829 -41.231668)
			(xy 309.618011 -41.144195) (xy 309.768134 -41.06367) (xy 309.921865 -40.99027) (xy 310.078868 -40.924156)
			(xy 310.238798 -40.865474) (xy 310.401302 -40.814353) (xy 310.566023 -40.770905) (xy 310.732601 -40.735226)
			(xy 310.900667 -40.707394) (xy 311.069853 -40.68747) (xy 311.239787 -40.675498) (xy 311.410096 -40.671505)
			(xy 311.580405 -40.675498) (xy 311.750339 -40.68747) (xy 311.919525 -40.707394) (xy 312.087591 -40.735226)
			(xy 312.254169 -40.770905) (xy 312.41889 -40.814353) (xy 312.581394 -40.865474) (xy 312.741324 -40.924156)
			(xy 312.898327 -40.99027) (xy 313.052058 -41.06367) (xy 313.202181 -41.144195) (xy 313.348363 -41.231668)
			(xy 313.490285 -41.325897) (xy 313.627635 -41.426674) (xy 313.76011 -41.533779) (xy 313.887418 -41.646975)
			(xy 314.009282 -41.766014) (xy 314.125431 -41.890634) (xy 314.235612 -42.020562) (xy 314.339582 -42.155511)
			(xy 314.437112 -42.295185) (xy 314.527988 -42.439277) (xy 314.61201 -42.587471) (xy 314.688993 -42.739439)
			(xy 314.758769 -42.894849) (xy 314.821184 -43.053359) (xy 314.876101 -43.21462) (xy 314.923398 -43.378278)
			(xy 314.962973 -43.543973) (xy 314.994737 -43.711341) (xy 315.018622 -43.880013) (xy 315.034574 -44.04962)
			(xy 315.042559 -44.219788) (xy 315.043058 -44.304966) (xy 315.042559 -44.390144) (xy 315.034574 -44.560312)
			(xy 315.018622 -44.729919) (xy 314.994737 -44.898591) (xy 314.962973 -45.065959) (xy 314.923398 -45.231654)
			(xy 314.876101 -45.395312) (xy 314.821184 -45.556573) (xy 314.758769 -45.715083) (xy 314.688993 -45.870493)
			(xy 314.61201 -46.022461) (xy 314.527988 -46.170655) (xy 314.437112 -46.314747) (xy 314.339582 -46.454421)
			(xy 314.235612 -46.58937) (xy 314.125431 -46.719298) (xy 314.009282 -46.843918) (xy 313.887418 -46.962957)
			(xy 313.76011 -47.076153) (xy 313.627635 -47.183258) (xy 313.490285 -47.284035) (xy 313.348363 -47.378264)
			(xy 313.202181 -47.465737) (xy 313.052058 -47.546262) (xy 312.898327 -47.619662) (xy 312.741324 -47.685776)
			(xy 312.581394 -47.744458) (xy 312.41889 -47.795579) (xy 312.254169 -47.839027) (xy 312.087591 -47.874706)
			(xy 311.919525 -47.902538) (xy 311.750339 -47.922462) (xy 311.580405 -47.934434) (xy 311.410096 -47.938428)
			(xy 311.239787 -47.934434) (xy 311.069853 -47.922462) (xy 310.900667 -47.902538) (xy 310.732601 -47.874706)
			(xy 310.566023 -47.839027) (xy 310.401302 -47.795579) (xy 310.238798 -47.744458) (xy 310.078868 -47.685776)
			(xy 309.921865 -47.619662) (xy 309.768134 -47.546262) (xy 309.618011 -47.465737) (xy 309.471829 -47.378264)
			(xy 309.329907 -47.284035) (xy 309.192557 -47.183258) (xy 309.060082 -47.076153) (xy 308.932774 -46.962957)
			(xy 308.81091 -46.843918) (xy 308.694761 -46.719298) (xy 308.58458 -46.58937) (xy 308.48061 -46.454421)
			(xy 308.38308 -46.314747) (xy 308.292204 -46.170655) (xy 308.208182 -46.022461) (xy 308.131199 -45.870493)
			(xy 308.061423 -45.715083) (xy 307.999008 -45.556573) (xy 307.944091 -45.395312) (xy 307.896794 -45.231654)
			(xy 307.857219 -45.065959) (xy 307.825455 -44.898591) (xy 307.80157 -44.729919) (xy 307.785618 -44.560312)
			(xy 307.777633 -44.390144) (xy 296.5958 -44.390144) (xy 296.5958 -44.90974) (xy 296.596209 -44.919247)
			(xy 296.603146 -44.936953) (xy 296.616025 -44.950944) (xy 296.633097 -44.95932) (xy 296.642536 -44.96054)
			(xy 296.683779 -44.964355) (xy 296.765362 -44.978688) (xy 296.845259 -45.000546) (xy 296.922776 -45.029741)
			(xy 296.997242 -45.066018) (xy 297.068011 -45.109065) (xy 297.13447 -45.158506) (xy 297.196043 -45.213914)
			(xy 297.252195 -45.274809) (xy 297.30244 -45.340662) (xy 297.346343 -45.410903) (xy 297.383522 -45.484923)
			(xy 297.413657 -45.56208) (xy 297.436484 -45.641705) (xy 297.451807 -45.723108) (xy 297.459492 -45.805584)
			(xy 297.459908 -45.847) (xy 297.459406 -45.889315) (xy 297.45137 -45.973562) (xy 297.43537 -46.056665)
			(xy 297.411551 -46.137874) (xy 297.380127 -46.216453) (xy 297.341384 -46.291694) (xy 297.318938 -46.327568)
			(xy 297.314055 -46.335957) (xy 297.310383 -46.355) (xy 297.314055 -46.374043) (xy 297.318938 -46.382432)
			(xy 297.341377 -46.418311) (xy 297.380128 -46.493548) (xy 297.411555 -46.572125) (xy 297.435376 -46.653334)
			(xy 297.451374 -46.736437) (xy 297.459405 -46.820685) (xy 297.459908 -46.863) (xy 297.459456 -46.903901)
			(xy 297.451969 -46.985358) (xy 297.43703 -47.065783) (xy 297.414766 -47.144496) (xy 297.385364 -47.22083)
			(xy 297.349075 -47.294141) (xy 297.306204 -47.363808) (xy 297.257115 -47.429241) (xy 297.230038 -47.4599)
			(xy 297.222672 -47.467774) (xy 297.216068 -47.488094) (xy 297.225212 -47.584106) (xy 297.235626 -47.602648)
			(xy 297.244262 -47.609252) (xy 297.255736 -47.618434) (xy 297.274517 -47.641028) (xy 297.287636 -47.667317)
			(xy 297.294398 -47.695908) (xy 297.294808 -47.710598) (xy 297.294808 -50.488088) (xy 297.294315 -50.504744)
			(xy 297.285696 -50.536922) (xy 297.269042 -50.565773) (xy 297.245489 -50.58933) (xy 297.216641 -50.605988)
			(xy 297.184464 -50.614612) (xy 297.167808 -50.615088) (xy 295.953434 -50.615088) (xy 295.936777 -50.614597)
			(xy 295.904596 -50.605982) (xy 295.875743 -50.589329) (xy 295.852184 -50.565775) (xy 295.835527 -50.536924)
			(xy 295.826905 -50.504745) (xy 295.826434 -50.488088) (xy 295.826434 -49.56556) (xy 295.825947 -49.554055)
			(xy 295.816017 -49.533304) (xy 295.807384 -49.525682) (xy 295.73601 -49.468786) (xy 295.713658 -49.463706)
			(xy 295.702228 -49.4665) (xy 295.674286 -49.47245) (xy 295.61751 -49.47882) (xy 295.588944 -49.4792)
			(xy 288.472372 -49.4792) (xy 288.462293 -49.479626) (xy 288.443695 -49.4874) (xy 288.429555 -49.501764)
			(xy 288.425382 -49.51095) (xy 288.38398 -49.61255) (xy 288.39033 -49.642776) (xy 288.40176 -49.653698)
			(xy 288.433303 -49.685089) (xy 288.490633 -49.75316) (xy 288.540879 -49.826616) (xy 288.583539 -49.904722)
			(xy 288.618185 -49.986697) (xy 288.644473 -50.071723) (xy 288.662139 -50.158948) (xy 288.671006 -50.247502)
			(xy 288.671508 -50.292) (xy 288.671033 -50.333102) (xy 288.663448 -50.414957) (xy 288.648343 -50.495762)
			(xy 288.625847 -50.574829) (xy 288.596151 -50.651483) (xy 288.559509 -50.72507) (xy 288.516234 -50.794962)
			(xy 288.466694 -50.860563) (xy 288.411313 -50.921313) (xy 288.350563 -50.976694) (xy 288.284962 -51.026234)
			(xy 288.21507 -51.069509) (xy 288.141483 -51.106151) (xy 288.064829 -51.135847) (xy 287.985762 -51.158343)
			(xy 287.904957 -51.173448) (xy 287.823102 -51.181033) (xy 287.782 -51.181508) (xy 287.739334 -51.181005)
			(xy 287.654395 -51.172835) (xy 287.570627 -51.15657) (xy 287.488802 -51.13236) (xy 287.409671 -51.100427)
			(xy 287.333961 -51.061064) (xy 287.262367 -51.014633) (xy 287.195548 -50.961561) (xy 287.134116 -50.902335)
			(xy 287.078638 -50.837499) (xy 287.029622 -50.76765) (xy 286.987519 -50.693429) (xy 286.952715 -50.615517)
			(xy 286.93872 -50.57521) (xy 286.934484 -50.564368) (xy 286.918161 -50.547809) (xy 286.896226 -50.540092)
			(xy 286.884618 -50.54092) (xy 286.859367 -50.543582) (xy 286.808663 -50.546375) (xy 286.783272 -50.546508)
			(xy 286.74186 -50.546042) (xy 286.659394 -50.538364) (xy 286.577998 -50.523059) (xy 286.498375 -50.500258)
			(xy 286.421215 -50.470159) (xy 286.383984 -50.45202) (xy 286.373668 -50.44741) (xy 286.351111 -50.446737)
			(xy 286.34055 -50.45075) (xy 286.298209 -50.468691) (xy 286.21063 -50.496748) (xy 286.120625 -50.515623)
			(xy 286.029153 -50.525114) (xy 285.983172 -50.52568) (xy 285.942071 -50.525204) (xy 285.860219 -50.517617)
			(xy 285.779417 -50.50251) (xy 285.700353 -50.480011) (xy 285.623703 -50.450314) (xy 285.550119 -50.413671)
			(xy 285.480231 -50.370395) (xy 285.414634 -50.320855) (xy 285.353887 -50.265473) (xy 285.298509 -50.204723)
			(xy 285.248974 -50.139123) (xy 285.205702 -50.069232) (xy 285.169063 -49.995646) (xy 285.139371 -49.918994)
			(xy 285.116878 -49.839928) (xy 285.101775 -49.759125) (xy 285.094193 -49.677273) (xy 285.093664 -49.636172)
			(xy 285.094934 -49.586388) (xy 285.095442 -49.57572) (xy 285.088584 -49.556416) (xy 285.030418 -49.495202)
			(xy 285.022973 -49.487966) (xy 285.003957 -49.479689) (xy 284.993588 -49.4792) (xy 283.365194 -49.4792)
			(xy 283.355124 -49.479624) (xy 283.336521 -49.48734) (xy 283.329126 -49.494186) (xy 278.722836 -54.100476)
			(xy 278.715998 -54.107877) (xy 278.708285 -54.126476) (xy 278.70785 -54.136544) (xy 278.70785 -54.356)
			(xy 296.671492 -54.356) (xy 296.672075 -54.309604) (xy 296.68172 -54.217316) (xy 296.700916 -54.126532)
			(xy 296.729454 -54.038239) (xy 296.747692 -53.995574) (xy 296.751498 -53.985632) (xy 296.751498 -53.964368)
			(xy 296.747692 -53.954426) (xy 296.729447 -53.911764) (xy 296.700903 -53.823471) (xy 296.68171 -53.732686)
			(xy 296.672077 -53.640396) (xy 296.671492 -53.594) (xy 296.672075 -53.547604) (xy 296.68172 -53.455316)
			(xy 296.700916 -53.364532) (xy 296.729454 -53.276239) (xy 296.747692 -53.233574) (xy 296.751498 -53.223632)
			(xy 296.751498 -53.202368) (xy 296.747692 -53.192426) (xy 296.729447 -53.149764) (xy 296.700903 -53.061471)
			(xy 296.68171 -52.970686) (xy 296.672077 -52.878396) (xy 296.671492 -52.832) (xy 296.672075 -52.785604)
			(xy 296.68172 -52.693316) (xy 296.700916 -52.602532) (xy 296.729454 -52.514239) (xy 296.747692 -52.471574)
			(xy 296.751498 -52.461632) (xy 296.751498 -52.440368) (xy 296.747692 -52.430426) (xy 296.729447 -52.387764)
			(xy 296.700903 -52.299471) (xy 296.68171 -52.208686) (xy 296.672077 -52.116396) (xy 296.671492 -52.07)
			(xy 296.671967 -52.028898) (xy 296.679552 -51.947043) (xy 296.694657 -51.866238) (xy 296.717153 -51.787171)
			(xy 296.746849 -51.710517) (xy 296.783491 -51.63693) (xy 296.826766 -51.567038) (xy 296.876306 -51.501437)
			(xy 296.931687 -51.440687) (xy 296.992437 -51.385306) (xy 297.058038 -51.335766) (xy 297.12793 -51.292491)
			(xy 297.201517 -51.255849) (xy 297.278171 -51.226153) (xy 297.357238 -51.203657) (xy 297.438043 -51.188552)
			(xy 297.519898 -51.180967) (xy 297.561 -51.180492) (xy 297.607396 -51.181075) (xy 297.699684 -51.19072)
			(xy 297.790468 -51.209916) (xy 297.878761 -51.238454) (xy 297.921426 -51.256692) (xy 297.931368 -51.260498)
			(xy 297.952632 -51.260498) (xy 297.962574 -51.256692) (xy 298.005236 -51.238447) (xy 298.093529 -51.209903)
			(xy 298.184314 -51.19071) (xy 298.276604 -51.181077) (xy 298.323 -51.180492) (xy 298.364102 -51.180967)
			(xy 298.445957 -51.188552) (xy 298.526762 -51.203657) (xy 298.605829 -51.226153) (xy 298.682483 -51.255849)
			(xy 298.75607 -51.292491) (xy 298.825962 -51.335766) (xy 298.891563 -51.385306) (xy 298.952313 -51.440687)
			(xy 299.007694 -51.501437) (xy 299.057234 -51.567038) (xy 299.100509 -51.63693) (xy 299.137151 -51.710517)
			(xy 299.166847 -51.787171) (xy 299.189343 -51.866238) (xy 299.204448 -51.947043) (xy 299.212033 -52.028898)
			(xy 299.212508 -52.07) (xy 299.211925 -52.116396) (xy 299.20228 -52.208684) (xy 299.183084 -52.299468)
			(xy 299.154546 -52.387761) (xy 299.136308 -52.430426) (xy 299.132502 -52.440368) (xy 299.132502 -52.461632)
			(xy 299.136308 -52.471574) (xy 299.154553 -52.514236) (xy 299.183097 -52.602529) (xy 299.20229 -52.693314)
			(xy 299.211923 -52.785604) (xy 299.212508 -52.832) (xy 299.211925 -52.878396) (xy 299.20228 -52.970684)
			(xy 299.183084 -53.061468) (xy 299.154546 -53.149761) (xy 299.136308 -53.192426) (xy 299.132502 -53.202368)
			(xy 299.132502 -53.223632) (xy 299.136308 -53.233574) (xy 299.154553 -53.276236) (xy 299.183097 -53.364529)
			(xy 299.20229 -53.455314) (xy 299.211923 -53.547604) (xy 299.212508 -53.594) (xy 299.211925 -53.640396)
			(xy 299.20228 -53.732684) (xy 299.183084 -53.823468) (xy 299.154546 -53.911761) (xy 299.136308 -53.954426)
			(xy 299.132502 -53.964368) (xy 299.132502 -53.985632) (xy 299.136308 -53.995574) (xy 299.154553 -54.038236)
			(xy 299.183097 -54.126529) (xy 299.20229 -54.217314) (xy 299.211923 -54.309604) (xy 299.212508 -54.356)
			(xy 299.212033 -54.397102) (xy 299.204448 -54.478957) (xy 299.189343 -54.559762) (xy 299.166847 -54.638829)
			(xy 299.137151 -54.715483) (xy 299.100509 -54.78907) (xy 299.057234 -54.858962) (xy 299.007694 -54.924563)
			(xy 298.952313 -54.985313) (xy 298.891563 -55.040694) (xy 298.825962 -55.090234) (xy 298.75607 -55.133509)
			(xy 298.682483 -55.170151) (xy 298.605829 -55.199847) (xy 298.526762 -55.222343) (xy 298.445957 -55.237448)
			(xy 298.364102 -55.245033) (xy 298.323 -55.245508) (xy 298.276604 -55.244925) (xy 298.184316 -55.23528)
			(xy 298.093532 -55.216084) (xy 298.005239 -55.187546) (xy 297.962574 -55.169308) (xy 297.952632 -55.165502)
			(xy 297.931368 -55.165502) (xy 297.921426 -55.169308) (xy 297.878764 -55.187553) (xy 297.790471 -55.216097)
			(xy 297.699686 -55.23529) (xy 297.607396 -55.244923) (xy 297.561 -55.245508) (xy 297.519898 -55.245033)
			(xy 297.438043 -55.237448) (xy 297.357238 -55.222343) (xy 297.278171 -55.199847) (xy 297.201517 -55.170151)
			(xy 297.12793 -55.133509) (xy 297.058038 -55.090234) (xy 296.992437 -55.040694) (xy 296.931687 -54.985313)
			(xy 296.876306 -54.924563) (xy 296.826766 -54.858962) (xy 296.783491 -54.78907) (xy 296.746849 -54.715483)
			(xy 296.717153 -54.638829) (xy 296.694657 -54.559762) (xy 296.679552 -54.478957) (xy 296.671967 -54.397102)
			(xy 296.671492 -54.356) (xy 278.70785 -54.356) (xy 278.70785 -58.036714) (xy 278.708277 -58.046782)
			(xy 278.716001 -58.065378) (xy 278.722836 -58.072782) (xy 279.843992 -59.193938) (xy 279.851387 -59.200792)
			(xy 279.869986 -59.20854) (xy 279.88006 -59.208924) (xy 298.525184 -59.208924) (xy 298.558445 -59.209444)
			(xy 298.624397 -59.218129) (xy 298.688651 -59.23535) (xy 298.750106 -59.260815) (xy 298.807709 -59.294087)
			(xy 298.860475 -59.334595) (xy 298.88434 -59.357768) (xy 300.12259 -60.596018) (xy 300.14575 -60.619896)
			(xy 300.186264 -60.672657) (xy 300.219542 -60.730257) (xy 300.245012 -60.791709) (xy 300.26224 -60.855962)
			(xy 300.270931 -60.921913) (xy 300.271434 -60.955174) (xy 300.271434 -72.642476) (xy 300.271872 -72.652539)
			(xy 300.279609 -72.671121) (xy 300.28642 -72.678544) (xy 300.487842 -72.879966) (xy 310.009801 -72.879966)
			(xy 310.013811 -72.774063) (xy 310.025819 -72.668767) (xy 310.045756 -72.564681) (xy 310.073508 -72.462401)
			(xy 310.108916 -72.362512) (xy 310.151777 -72.265588) (xy 310.201845 -72.172182) (xy 310.258835 -72.082831)
			(xy 310.322418 -71.998045) (xy 310.392232 -71.918311) (xy 310.467876 -71.844086) (xy 310.548916 -71.775793)
			(xy 310.63489 -71.713826) (xy 310.725304 -71.658538) (xy 310.81964 -71.610246) (xy 310.917359 -71.569227)
			(xy 311.017899 -71.535716) (xy 311.120687 -71.509904) (xy 311.225131 -71.49194) (xy 311.330636 -71.481927)
			(xy 311.436595 -71.479921) (xy 311.542403 -71.485935) (xy 311.647453 -71.499934) (xy 311.751143 -71.521837)
			(xy 311.85288 -71.55152) (xy 311.952081 -71.588811) (xy 312.048177 -71.633499) (xy 312.140618 -71.685326)
			(xy 312.228875 -71.743996) (xy 312.312442 -71.809173) (xy 312.390841 -71.880483) (xy 312.463622 -71.957517)
			(xy 312.530368 -72.039836) (xy 312.590698 -72.126967) (xy 312.644265 -72.218411) (xy 312.690763 -72.313644)
			(xy 312.729925 -72.412121) (xy 312.761528 -72.513278) (xy 312.785389 -72.616536) (xy 312.801374 -72.721302)
			(xy 312.809389 -72.826977) (xy 312.80989 -72.879966) (xy 312.809389 -72.932955) (xy 312.801374 -73.03863)
			(xy 312.785389 -73.143396) (xy 312.761528 -73.246654) (xy 312.729925 -73.347811) (xy 312.690763 -73.446288)
			(xy 312.644265 -73.541521) (xy 312.590698 -73.632965) (xy 312.530368 -73.720096) (xy 312.463622 -73.802415)
			(xy 312.390841 -73.879449) (xy 312.312442 -73.950759) (xy 312.228875 -74.015936) (xy 312.140618 -74.074606)
			(xy 312.048177 -74.126433) (xy 311.952081 -74.171121) (xy 311.85288 -74.208412) (xy 311.751143 -74.238095)
			(xy 311.647453 -74.259998) (xy 311.542403 -74.273997) (xy 311.436595 -74.280011) (xy 311.330636 -74.278005)
			(xy 311.225131 -74.267992) (xy 311.120687 -74.250028) (xy 311.017899 -74.224216) (xy 310.917359 -74.190705)
			(xy 310.81964 -74.149686) (xy 310.725304 -74.101394) (xy 310.63489 -74.046106) (xy 310.548916 -73.984139)
			(xy 310.467876 -73.915846) (xy 310.392232 -73.841621) (xy 310.322418 -73.761887) (xy 310.258835 -73.677101)
			(xy 310.201845 -73.58775) (xy 310.151777 -73.494344) (xy 310.108916 -73.39742) (xy 310.073508 -73.297531)
			(xy 310.045756 -73.195251) (xy 310.025819 -73.091165) (xy 310.013811 -72.985869) (xy 310.009801 -72.879966)
			(xy 300.487842 -72.879966) (xy 300.69409 -73.086214) (xy 300.701484 -73.093071) (xy 300.720083 -73.100823)
			(xy 300.730158 -73.1012) (xy 306.451 -73.1012) (xy 306.48426 -73.101721) (xy 306.55021 -73.110409)
			(xy 306.614461 -73.127634) (xy 306.675912 -73.153103) (xy 306.733511 -73.186379) (xy 306.786271 -73.226892)
			(xy 306.810156 -73.250044) (xy 308.856126 -75.296014) (xy 308.863522 -75.302866) (xy 308.882121 -75.310604)
			(xy 308.892194 -75.311) (xy 319.8876 -75.311) (xy 319.92086 -75.311521) (xy 319.98681 -75.320209)
			(xy 320.051061 -75.337434) (xy 320.112512 -75.362903) (xy 320.170111 -75.396179) (xy 320.222871 -75.436692)
			(xy 320.246756 -75.459844) (xy 321.288156 -76.501244) (xy 321.311312 -76.525124) (xy 321.351818 -76.577888)
			(xy 321.385089 -76.635489) (xy 321.410553 -76.69694) (xy 321.427775 -76.761191) (xy 321.436461 -76.827141)
			(xy 321.437 -76.8604) (xy 321.437 -120.904) (xy 321.436479 -120.93726) (xy 321.427791 -121.00321)
			(xy 321.410566 -121.067461) (xy 321.385097 -121.128912) (xy 321.351821 -121.186511) (xy 321.311308 -121.239271)
			(xy 321.288156 -121.263156) (xy 319.992756 -122.558556) (xy 319.968876 -122.581712) (xy 319.916112 -122.622218)
			(xy 319.858511 -122.655489) (xy 319.79706 -122.680953) (xy 319.732809 -122.698175) (xy 319.666859 -122.706861)
			(xy 319.6336 -122.7074) (xy 304.015394 -122.7074) (xy 304.005324 -122.707824) (xy 303.986721 -122.71554)
			(xy 303.979326 -122.722386) (xy 300.28642 -126.415292) (xy 300.27957 -126.422689) (xy 300.27183 -126.441287)
			(xy 300.271434 -126.45136) (xy 300.271434 -131.730242) (xy 300.27091 -131.763501) (xy 300.262218 -131.829449)
			(xy 300.244989 -131.893698) (xy 300.219518 -131.955146) (xy 300.186241 -132.012742) (xy 300.145728 -132.0655)
			(xy 300.12259 -132.089398) (xy 298.892722 -133.319266) (xy 298.868843 -133.342424) (xy 298.816081 -133.382934)
			(xy 298.758481 -133.416206) (xy 298.697028 -133.441671) (xy 298.632776 -133.458892) (xy 298.566826 -133.467575)
			(xy 298.533566 -133.46811) (xy 279.797256 -133.46811) (xy 279.78719 -133.468541) (xy 279.768598 -133.476268)
			(xy 279.761188 -133.483096) (xy 278.722836 -134.521448) (xy 278.715993 -134.528847) (xy 278.708271 -134.547446)
			(xy 278.70785 -134.557516) (xy 278.70785 -145.276824) (xy 278.708279 -145.286891) (xy 278.716005 -145.305485)
			(xy 278.722836 -145.312892) (xy 279.308814 -145.89887) (xy 279.340818 -145.90395) (xy 279.355804 -145.896584)
			(xy 279.382437 -145.883855) (xy 279.438656 -145.865864) (xy 279.496978 -145.856767) (xy 279.526492 -145.856198)
			(xy 279.556616 -145.856767) (xy 279.616113 -145.86624) (xy 279.673381 -145.884951) (xy 279.726993 -145.912436)
			(xy 279.775617 -145.948009) (xy 279.797256 -145.968974) (xy 279.804656 -145.975814) (xy 279.823255 -145.983532)
			(xy 279.833324 -145.98396)
		)
		(stroke
			(width 0)
			(type solid)
		)
		(fill yes)
		(layer "In4.Cu")
		(net "GND")
	)
	(gr_poly
		(pts
			(xy 9.97966 -145.98396) (xy 9.989724 -145.983525) (xy 10.008309 -145.97579) (xy 10.015728 -145.968974)
			(xy 10.035352 -145.949872) (xy 10.079091 -145.916919) (xy 10.127092 -145.890559) (xy 10.17837 -145.871333)
			(xy 10.23187 -145.859637) (xy 10.286492 -145.855712) (xy 10.341114 -145.859637) (xy 10.394614 -145.871333)
			(xy 10.445892 -145.890559) (xy 10.493893 -145.916919) (xy 10.537632 -145.949872) (xy 10.557256 -145.968974)
			(xy 10.564656 -145.975814) (xy 10.583255 -145.983532) (xy 10.593324 -145.98396) (xy 15.05966 -145.98396)
			(xy 15.069724 -145.983525) (xy 15.088309 -145.97579) (xy 15.095728 -145.968974) (xy 15.115352 -145.949872)
			(xy 15.159091 -145.916919) (xy 15.207092 -145.890559) (xy 15.25837 -145.871333) (xy 15.31187 -145.859637)
			(xy 15.366492 -145.855712) (xy 15.421114 -145.859637) (xy 15.474614 -145.871333) (xy 15.525892 -145.890559)
			(xy 15.573893 -145.916919) (xy 15.617632 -145.949872) (xy 15.637256 -145.968974) (xy 15.644656 -145.975814)
			(xy 15.663255 -145.983532) (xy 15.673324 -145.98396) (xy 20.13966 -145.98396) (xy 20.149724 -145.983525)
			(xy 20.168309 -145.97579) (xy 20.175728 -145.968974) (xy 20.195352 -145.949872) (xy 20.239091 -145.916919)
			(xy 20.287092 -145.890559) (xy 20.33837 -145.871333) (xy 20.39187 -145.859637) (xy 20.446492 -145.855712)
			(xy 20.501114 -145.859637) (xy 20.554614 -145.871333) (xy 20.605892 -145.890559) (xy 20.653893 -145.916919)
			(xy 20.697632 -145.949872) (xy 20.717256 -145.968974) (xy 20.724656 -145.975814) (xy 20.743255 -145.983532)
			(xy 20.753324 -145.98396) (xy 25.21966 -145.98396) (xy 25.229724 -145.983525) (xy 25.248309 -145.97579)
			(xy 25.255728 -145.968974) (xy 25.275352 -145.949872) (xy 25.319091 -145.916919) (xy 25.367092 -145.890559)
			(xy 25.41837 -145.871333) (xy 25.47187 -145.859637) (xy 25.526492 -145.855712) (xy 25.581114 -145.859637)
			(xy 25.634614 -145.871333) (xy 25.685892 -145.890559) (xy 25.733893 -145.916919) (xy 25.777632 -145.949872)
			(xy 25.797256 -145.968974) (xy 25.804656 -145.975814) (xy 25.823255 -145.983532) (xy 25.833324 -145.98396)
			(xy 30.29966 -145.98396) (xy 30.309724 -145.983525) (xy 30.328309 -145.97579) (xy 30.335728 -145.968974)
			(xy 30.355352 -145.949872) (xy 30.399091 -145.916919) (xy 30.447092 -145.890559) (xy 30.49837 -145.871333)
			(xy 30.55187 -145.859637) (xy 30.606492 -145.855712) (xy 30.661114 -145.859637) (xy 30.714614 -145.871333)
			(xy 30.765892 -145.890559) (xy 30.813893 -145.916919) (xy 30.857632 -145.949872) (xy 30.877256 -145.968974)
			(xy 30.884656 -145.975814) (xy 30.903255 -145.983532) (xy 30.913324 -145.98396) (xy 35.37966 -145.98396)
			(xy 35.389724 -145.983525) (xy 35.408309 -145.97579) (xy 35.415728 -145.968974) (xy 35.435352 -145.949872)
			(xy 35.479091 -145.916919) (xy 35.527092 -145.890559) (xy 35.57837 -145.871333) (xy 35.63187 -145.859637)
			(xy 35.686492 -145.855712) (xy 35.741114 -145.859637) (xy 35.794614 -145.871333) (xy 35.845892 -145.890559)
			(xy 35.893893 -145.916919) (xy 35.937632 -145.949872) (xy 35.957256 -145.968974) (xy 35.964656 -145.975814)
			(xy 35.983255 -145.983532) (xy 35.993324 -145.98396) (xy 37.86759 -145.98396) (xy 37.87766 -145.983537)
			(xy 37.896263 -145.975821) (xy 37.903658 -145.968974) (xy 38.974014 -144.898618) (xy 38.980857 -144.891219)
			(xy 38.988575 -144.87262) (xy 38.989 -144.86255) (xy 38.989 -120.754394) (xy 38.988576 -120.744324)
			(xy 38.98086 -120.725721) (xy 38.974014 -120.718326) (xy 37.696648 -119.44096) (xy 37.68925 -119.434115)
			(xy 37.670651 -119.42639) (xy 37.66058 -119.425974) (xy 23.896828 -119.425974) (xy 23.886741 -119.426389)
			(xy 23.868123 -119.434149) (xy 23.853959 -119.44851) (xy 23.849838 -119.457724) (xy 23.808436 -119.559324)
			(xy 23.814786 -119.58955) (xy 23.826216 -119.600472) (xy 23.889876 -119.662972) (xy 24.012235 -119.792829)
			(xy 24.128703 -119.927994) (xy 24.239049 -120.068202) (xy 24.343055 -120.213175) (xy 24.440517 -120.362626)
			(xy 24.531242 -120.51626) (xy 24.61505 -120.673774) (xy 24.691776 -120.834857) (xy 24.761268 -120.99919)
			(xy 24.823389 -121.166448) (xy 24.878016 -121.336302) (xy 24.925042 -121.508416) (xy 24.964373 -121.682449)
			(xy 24.995931 -121.858058) (xy 25.019655 -122.034896) (xy 25.035498 -122.212613) (xy 25.043428 -122.390859)
			(xy 25.043892 -122.48007) (xy 25.159471 -122.48007) (xy 25.16346 -122.339172) (xy 25.175414 -122.198725)
			(xy 25.195294 -122.05918) (xy 25.223037 -121.920983) (xy 25.258555 -121.784577) (xy 25.301732 -121.650398)
			(xy 25.352432 -121.518878) (xy 25.410492 -121.390436) (xy 25.475724 -121.265485) (xy 25.547922 -121.144424)
			(xy 25.626853 -121.027642) (xy 25.712264 -120.915513) (xy 25.803883 -120.808395) (xy 25.901415 -120.706632)
			(xy 26.004547 -120.61055) (xy 26.112951 -120.520457) (xy 26.226278 -120.43664) (xy 26.344165 -120.35937)
			(xy 26.466235 -120.288893) (xy 26.592097 -120.225434) (xy 26.721347 -120.169199) (xy 26.853572 -120.120365)
			(xy 26.988348 -120.07909) (xy 27.125243 -120.045507) (xy 27.263819 -120.019722) (xy 27.403632 -120.001818)
			(xy 27.544234 -119.991853) (xy 27.685174 -119.989858) (xy 27.826002 -119.995841) (xy 27.966265 -120.009781)
			(xy 28.105515 -120.031634) (xy 28.243306 -120.06133) (xy 28.379196 -120.098774) (xy 28.51275 -120.143846)
			(xy 28.64354 -120.196402) (xy 28.771147 -120.256273) (xy 28.895163 -120.323268) (xy 29.015189 -120.397171)
			(xy 29.130843 -120.477747) (xy 29.241752 -120.564736) (xy 29.347563 -120.657861) (xy 29.447935 -120.756823)
			(xy 29.542548 -120.861305) (xy 29.631099 -120.970973) (xy 29.713303 -121.085475) (xy 29.788897 -121.204444)
			(xy 29.85764 -121.327499) (xy 29.919311 -121.454246) (xy 29.973712 -121.584279) (xy 30.02067 -121.717182)
			(xy 30.060033 -121.852528) (xy 30.091676 -121.989885) (xy 30.115498 -122.128812) (xy 30.131421 -122.268864)
			(xy 30.139396 -122.409593) (xy 30.139894 -122.48007) (xy 30.139396 -122.550547) (xy 30.131421 -122.691276)
			(xy 30.115498 -122.831328) (xy 30.091676 -122.970255) (xy 30.060033 -123.107612) (xy 30.02067 -123.242958)
			(xy 29.973712 -123.375861) (xy 29.919311 -123.505894) (xy 29.85764 -123.632641) (xy 29.788897 -123.755696)
			(xy 29.713303 -123.874665) (xy 29.631099 -123.989167) (xy 29.542548 -124.098835) (xy 29.447935 -124.203317)
			(xy 29.347563 -124.302279) (xy 29.241752 -124.395404) (xy 29.130843 -124.482393) (xy 29.015189 -124.562969)
			(xy 28.895163 -124.636872) (xy 28.771147 -124.703867) (xy 28.64354 -124.763738) (xy 28.51275 -124.816294)
			(xy 28.379196 -124.861366) (xy 28.243306 -124.89881) (xy 28.105515 -124.928506) (xy 27.966265 -124.950359)
			(xy 27.826002 -124.964299) (xy 27.685174 -124.970282) (xy 27.544234 -124.968287) (xy 27.403632 -124.958322)
			(xy 27.263819 -124.940418) (xy 27.125243 -124.914633) (xy 26.988348 -124.88105) (xy 26.853572 -124.839775)
			(xy 26.721347 -124.790941) (xy 26.592097 -124.734706) (xy 26.466235 -124.671247) (xy 26.344165 -124.60077)
			(xy 26.226278 -124.5235) (xy 26.112951 -124.439683) (xy 26.004547 -124.34959) (xy 25.901415 -124.253508)
			(xy 25.803883 -124.151745) (xy 25.712264 -124.044627) (xy 25.626853 -123.932498) (xy 25.547922 -123.815716)
			(xy 25.475724 -123.694655) (xy 25.410492 -123.569704) (xy 25.352432 -123.441262) (xy 25.301732 -123.309742)
			(xy 25.258555 -123.175563) (xy 25.223037 -123.039157) (xy 25.195294 -122.90096) (xy 25.175414 -122.761415)
			(xy 25.16346 -122.620968) (xy 25.159471 -122.48007) (xy 25.043892 -122.48007) (xy 25.043387 -122.570147)
			(xy 25.035304 -122.750119) (xy 25.019155 -122.929548) (xy 24.994973 -123.108071) (xy 24.962805 -123.28533)
			(xy 24.922717 -123.460967) (xy 24.87479 -123.634628) (xy 24.819119 -123.805965) (xy 24.755817 -123.974631)
			(xy 24.685013 -124.140287) (xy 24.606847 -124.3026) (xy 24.521478 -124.461243) (xy 24.429077 -124.615895)
			(xy 24.329831 -124.766247) (xy 24.223939 -124.911994) (xy 24.111615 -125.052844) (xy 23.993085 -125.188513)
			(xy 23.868587 -125.318727) (xy 23.738373 -125.443225) (xy 23.602704 -125.561755) (xy 23.461854 -125.674079)
			(xy 23.316107 -125.779971) (xy 23.165755 -125.879217) (xy 23.011103 -125.971618) (xy 22.85246 -126.056987)
			(xy 22.690147 -126.135153) (xy 22.524491 -126.205957) (xy 22.355825 -126.269259) (xy 22.184488 -126.32493)
			(xy 22.010827 -126.372857) (xy 21.83519 -126.412945) (xy 21.657931 -126.445113) (xy 21.479408 -126.469295)
			(xy 21.299979 -126.485444) (xy 21.120007 -126.493527) (xy 21.02993 -126.494032) (xy 20.93918 -126.493526)
			(xy 20.757864 -126.485322) (xy 20.577105 -126.468931) (xy 20.397272 -126.444387) (xy 20.218732 -126.411739)
			(xy 20.04185 -126.371054) (xy 19.866987 -126.322416) (xy 19.694502 -126.265924) (xy 19.524747 -126.201693)
			(xy 19.358068 -126.129855) (xy 19.194807 -126.050556) (xy 19.035297 -125.963959) (xy 18.879864 -125.870241)
			(xy 18.728826 -125.769592) (xy 18.582492 -125.66222) (xy 18.441161 -125.548343) (xy 18.305121 -125.428195)
			(xy 18.174651 -125.30202) (xy 18.050018 -125.170076) (xy 17.931475 -125.032635) (xy 17.819267 -124.889975)
			(xy 17.713621 -124.74239) (xy 17.614754 -124.59018) (xy 17.522868 -124.433657) (xy 17.438151 -124.27314)
			(xy 17.399 -124.191268) (xy 17.393666 -124.179584) (xy 17.3736 -124.164598) (xy 17.264888 -124.148088)
			(xy 17.241266 -124.156216) (xy 17.232376 -124.165868) (xy 17.184455 -124.217229) (xy 17.083658 -124.315088)
			(xy 16.977503 -124.407108) (xy 16.866328 -124.492995) (xy 16.750487 -124.572477) (xy 16.630349 -124.6453)
			(xy 16.506295 -124.711232) (xy 16.37872 -124.770064) (xy 16.248031 -124.821609) (xy 16.114643 -124.865702)
			(xy 15.978981 -124.902204) (xy 15.841477 -124.930997) (xy 15.702568 -124.951991) (xy 15.562696 -124.965118)
			(xy 15.422307 -124.970337) (xy 15.281846 -124.967632) (xy 15.141762 -124.95701) (xy 15.002499 -124.938506)
			(xy 14.864501 -124.912178) (xy 14.728208 -124.87811) (xy 14.594052 -124.836411) (xy 14.462462 -124.787214)
			(xy 14.333855 -124.730674) (xy 14.208641 -124.666973) (xy 14.087218 -124.596312) (xy 13.969973 -124.518916)
			(xy 13.857279 -124.435032) (xy 13.749494 -124.344927) (xy 13.646962 -124.248887) (xy 13.550008 -124.147219)
			(xy 13.458942 -124.040245) (xy 13.374053 -123.928306) (xy 13.295611 -123.811758) (xy 13.223867 -123.690972)
			(xy 13.159047 -123.566333) (xy 13.101359 -123.438237) (xy 13.050986 -123.307092) (xy 13.008088 -123.173315)
			(xy 12.972802 -123.037332) (xy 12.94524 -122.899576) (xy 12.92549 -122.760485) (xy 12.913615 -122.620501)
			(xy 12.909653 -122.48007) (xy 12.913615 -122.339639) (xy 12.92549 -122.199655) (xy 12.94524 -122.060564)
			(xy 12.972802 -121.922808) (xy 13.008088 -121.786825) (xy 13.050986 -121.653048) (xy 13.101359 -121.521903)
			(xy 13.159047 -121.393807) (xy 13.223867 -121.269168) (xy 13.295611 -121.148382) (xy 13.374053 -121.031834)
			(xy 13.458942 -120.919895) (xy 13.550008 -120.812921) (xy 13.646962 -120.711253) (xy 13.749494 -120.615213)
			(xy 13.857279 -120.525108) (xy 13.969973 -120.441224) (xy 14.087218 -120.363828) (xy 14.208641 -120.293167)
			(xy 14.333855 -120.229466) (xy 14.462462 -120.172926) (xy 14.594052 -120.123729) (xy 14.728208 -120.08203)
			(xy 14.864501 -120.047962) (xy 15.002499 -120.021634) (xy 15.141762 -120.00313) (xy 15.281846 -119.992508)
			(xy 15.422307 -119.989803) (xy 15.562696 -119.995022) (xy 15.702568 -120.008149) (xy 15.841477 -120.029143)
			(xy 15.978981 -120.057936) (xy 16.114643 -120.094438) (xy 16.248031 -120.138531) (xy 16.37872 -120.190076)
			(xy 16.506295 -120.248908) (xy 16.630349 -120.31484) (xy 16.750487 -120.387663) (xy 16.866328 -120.467145)
			(xy 16.977503 -120.553032) (xy 17.083658 -120.645052) (xy 17.184455 -120.742911) (xy 17.232376 -120.794272)
			(xy 17.241266 -120.803924) (xy 17.264888 -120.812052) (xy 17.3736 -120.795542) (xy 17.393666 -120.780556)
			(xy 17.399 -120.768872) (xy 17.43793 -120.687468) (xy 17.522139 -120.527855) (xy 17.613434 -120.372186)
			(xy 17.71163 -120.220775) (xy 17.816529 -120.073929) (xy 17.927918 -119.931944) (xy 18.045574 -119.795106)
			(xy 18.169259 -119.663691) (xy 18.233644 -119.600472) (xy 18.245074 -119.58955) (xy 18.251424 -119.559324)
			(xy 18.210022 -119.457724) (xy 18.205826 -119.448564) (xy 18.191661 -119.434257) (xy 18.173097 -119.426464)
			(xy 18.163032 -119.425974) (xy 16.247364 -119.425974) (xy 16.214104 -119.42545) (xy 16.148155 -119.41676)
			(xy 16.083906 -119.399533) (xy 16.022456 -119.374064) (xy 15.964857 -119.340789) (xy 15.912097 -119.300278)
			(xy 15.888208 -119.27713) (xy 14.880844 -118.269766) (xy 14.857687 -118.245886) (xy 14.81718 -118.193123)
			(xy 14.783909 -118.135522) (xy 14.758443 -118.07407) (xy 14.74122 -118.009819) (xy 14.732533 -117.94387)
			(xy 14.732 -117.91061) (xy 14.732 -78.5114) (xy 14.731512 -78.501392) (xy 14.723852 -78.482901) (xy 14.709699 -78.468748)
			(xy 14.691208 -78.461088) (xy 14.6812 -78.4606) (xy 8.9154 -78.4606) (xy 8.88214 -78.460079) (xy 8.81619 -78.451391)
			(xy 8.751939 -78.434166) (xy 8.690488 -78.408697) (xy 8.632889 -78.375421) (xy 8.580129 -78.334908)
			(xy 8.556244 -78.311756) (xy 7.794244 -77.549756) (xy 7.771088 -77.525876) (xy 7.730582 -77.473112)
			(xy 7.697311 -77.415511) (xy 7.671847 -77.35406) (xy 7.654625 -77.289809) (xy 7.645939 -77.223859)
			(xy 7.6454 -77.1906) (xy 7.6454 -68.5546) (xy 7.645921 -68.52134) (xy 7.654609 -68.45539) (xy 7.671834 -68.391139)
			(xy 7.697303 -68.329688) (xy 7.730579 -68.272089) (xy 7.771092 -68.219329) (xy 7.794244 -68.195444)
			(xy 8.759444 -67.230244) (xy 8.783324 -67.207088) (xy 8.836088 -67.166582) (xy 8.893689 -67.133311)
			(xy 8.95514 -67.107847) (xy 9.019391 -67.090625) (xy 9.085341 -67.081939) (xy 9.1186 -67.0814) (xy 26.755598 -67.0814)
			(xy 26.764737 -67.081019) (xy 26.781852 -67.074604) (xy 26.795626 -67.062591) (xy 26.800302 -67.05473)
			(xy 26.849324 -66.963798) (xy 26.848054 -66.935858) (xy 26.840434 -66.924174) (xy 26.817257 -66.8879)
			(xy 26.777238 -66.811682) (xy 26.744774 -66.731953) (xy 26.72017 -66.649458) (xy 26.703657 -66.564971)
			(xy 26.695389 -66.479283) (xy 26.694892 -66.43624) (xy 26.695475 -66.389843) (xy 26.705104 -66.297552)
			(xy 26.724293 -66.206765) (xy 26.752834 -66.118471) (xy 26.771092 -66.075814) (xy 26.774906 -66.065871)
			(xy 26.774921 -66.044601) (xy 26.771092 -66.034666) (xy 26.752857 -65.992001) (xy 26.724325 -65.903707)
			(xy 26.705135 -65.812923) (xy 26.695496 -65.720635) (xy 26.694892 -65.67424) (xy 26.695475 -65.627843)
			(xy 26.705104 -65.535552) (xy 26.724293 -65.444765) (xy 26.752834 -65.356471) (xy 26.771092 -65.313814)
			(xy 26.774906 -65.303871) (xy 26.774921 -65.282601) (xy 26.771092 -65.272666) (xy 26.752857 -65.230001)
			(xy 26.724325 -65.141707) (xy 26.705135 -65.050923) (xy 26.695496 -64.958635) (xy 26.694892 -64.91224)
			(xy 26.69535 -64.871136) (xy 26.702932 -64.789277) (xy 26.718035 -64.708468) (xy 26.740529 -64.629397)
			(xy 26.770224 -64.552738) (xy 26.806865 -64.479147) (xy 26.85014 -64.40925) (xy 26.89968 -64.343645)
			(xy 26.955063 -64.282891) (xy 27.015814 -64.227506) (xy 27.081417 -64.177963) (xy 27.151312 -64.134685)
			(xy 27.224902 -64.09804) (xy 27.301559 -64.068342) (xy 27.380629 -64.045844) (xy 27.461438 -64.030738)
			(xy 27.543296 -64.023152) (xy 27.5844 -64.022732) (xy 27.630796 -64.023317) (xy 27.723086 -64.032951)
			(xy 27.813871 -64.052144) (xy 27.902163 -64.08069) (xy 27.944826 -64.098932) (xy 27.954768 -64.102738)
			(xy 27.976032 -64.102738) (xy 27.985974 -64.098932) (xy 28.028639 -64.080693) (xy 28.116932 -64.052154)
			(xy 28.207716 -64.032957) (xy 28.300004 -64.023311) (xy 28.3464 -64.022732) (xy 28.387502 -64.023192)
			(xy 28.469357 -64.030777) (xy 28.550162 -64.045883) (xy 28.629229 -64.06838) (xy 28.705882 -64.098077)
			(xy 28.779469 -64.13472) (xy 28.84936 -64.177996) (xy 28.91496 -64.227537) (xy 28.975709 -64.282919)
			(xy 29.031089 -64.343671) (xy 29.080627 -64.409273) (xy 29.1239 -64.479166) (xy 29.16054 -64.552754)
			(xy 29.190233 -64.629409) (xy 29.212726 -64.708477) (xy 29.227828 -64.789283) (xy 29.23541 -64.871137)
			(xy 29.235908 -64.91224) (xy 29.235321 -64.958636) (xy 29.225684 -65.050925) (xy 29.206487 -65.141708)
			(xy 29.17794 -65.229998) (xy 29.159708 -65.272666) (xy 29.155911 -65.282608) (xy 29.155926 -65.303864)
			(xy 29.159708 -65.313814) (xy 29.177944 -65.356479) (xy 29.206478 -65.444773) (xy 29.22567 -65.535557)
			(xy 29.235311 -65.627845) (xy 29.235908 -65.67424) (xy 29.235321 -65.720636) (xy 29.225684 -65.812925)
			(xy 29.206487 -65.903708) (xy 29.17794 -65.991998) (xy 29.159708 -66.034666) (xy 29.155911 -66.044608)
			(xy 29.155926 -66.065864) (xy 29.159708 -66.075814) (xy 29.177944 -66.118479) (xy 29.206478 -66.206773)
			(xy 29.22567 -66.297557) (xy 29.235311 -66.389845) (xy 29.235908 -66.43624) (xy 29.235412 -66.479282)
			(xy 29.227117 -66.564964) (xy 29.210589 -66.649445) (xy 29.185982 -66.731936) (xy 29.153527 -66.811667)
			(xy 29.113526 -66.887891) (xy 29.090366 -66.924174) (xy 29.082746 -66.935858) (xy 29.081476 -66.963798)
			(xy 29.130498 -67.05473) (xy 29.135175 -67.06259) (xy 29.148949 -67.074604) (xy 29.166063 -67.081018)
			(xy 29.175202 -67.0814) (xy 38.706806 -67.0814) (xy 38.716876 -67.080976) (xy 38.735479 -67.07326)
			(xy 38.742874 -67.066414) (xy 39.107872 -66.701416) (xy 39.114708 -66.694014) (xy 39.122417 -66.675416)
			(xy 39.122858 -66.665348) (xy 39.122858 -63.048896) (xy 39.102284 -63.021718) (xy 39.086028 -63.017146)
			(xy 39.04662 -63.005433) (xy 38.969959 -62.975721) (xy 38.896366 -62.939064) (xy 38.826468 -62.895774)
			(xy 38.760861 -62.846221) (xy 38.700105 -62.790827) (xy 38.644718 -62.730065) (xy 38.595172 -62.664453)
			(xy 38.55189 -62.59455) (xy 38.51524 -62.520953) (xy 38.485536 -62.444289) (xy 38.463031 -62.365211)
			(xy 38.447916 -62.284395) (xy 38.440321 -62.202529) (xy 38.439852 -62.16142) (xy 38.4403 -62.120284)
			(xy 38.447872 -62.03836) (xy 38.46298 -61.957487) (xy 38.485495 -61.878355) (xy 38.515225 -61.801642)
			(xy 38.551916 -61.728004) (xy 38.595253 -61.658071) (xy 38.619684 -61.624972) (xy 38.624902 -61.617469)
			(xy 38.630135 -61.599972) (xy 38.628887 -61.581752) (xy 38.621319 -61.565132) (xy 38.615112 -61.558424)
			(xy 34.565844 -57.509156) (xy 34.542688 -57.485276) (xy 34.502182 -57.432512) (xy 34.468911 -57.374911)
			(xy 34.443447 -57.31346) (xy 34.426225 -57.249209) (xy 34.417539 -57.183259) (xy 34.417 -57.15) (xy 34.417 -46.433994)
			(xy 34.417522 -46.400734) (xy 34.42621 -46.334784) (xy 34.443436 -46.270534) (xy 34.468905 -46.209083)
			(xy 34.502182 -46.151485) (xy 34.542695 -46.098726) (xy 34.565844 -46.074838) (xy 57.171844 -23.468838)
			(xy 57.195722 -23.445678) (xy 57.248483 -23.405165) (xy 57.306083 -23.371888) (xy 57.367536 -23.346419)
			(xy 57.431788 -23.329193) (xy 57.497739 -23.320506) (xy 57.531 -23.319994) (xy 147.898612 -23.319994)
			(xy 147.908681 -23.319568) (xy 147.927282 -23.31185) (xy 147.93468 -23.305008) (xy 148.702014 -22.537674)
			(xy 148.708866 -22.530278) (xy 148.716604 -22.511679) (xy 148.717 -22.501606) (xy 148.717 -1.866138)
			(xy 148.716565 -1.856073) (xy 148.708835 -1.837485) (xy 148.702014 -1.83007) (xy 147.90293 -1.030986)
			(xy 147.895532 -1.024141) (xy 147.876933 -1.016419) (xy 147.866862 -1.016) (xy 146.251422 -1.016)
			(xy 146.241358 -1.016438) (xy 146.222774 -1.024172) (xy 146.215354 -1.030986) (xy 146.19571 -1.050208)
			(xy 146.151891 -1.083381) (xy 146.103765 -1.109922) (xy 146.052328 -1.129283) (xy 145.998645 -1.141062)
			(xy 145.943828 -1.145016) (xy 145.889011 -1.141062) (xy 145.835328 -1.129283) (xy 145.783891 -1.109922)
			(xy 145.735765 -1.083381) (xy 145.691946 -1.050208) (xy 145.672302 -1.030986) (xy 145.664908 -1.02413)
			(xy 145.646309 -1.016381) (xy 145.636234 -1.016) (xy 141.171422 -1.016) (xy 141.161358 -1.016438)
			(xy 141.142774 -1.024172) (xy 141.135354 -1.030986) (xy 141.11571 -1.050208) (xy 141.071891 -1.083381)
			(xy 141.023765 -1.109922) (xy 140.972328 -1.129283) (xy 140.918645 -1.141062) (xy 140.863828 -1.145016)
			(xy 140.809011 -1.141062) (xy 140.755328 -1.129283) (xy 140.703891 -1.109922) (xy 140.655765 -1.083381)
			(xy 140.611946 -1.050208) (xy 140.592302 -1.030986) (xy 140.584908 -1.02413) (xy 140.566309 -1.016381)
			(xy 140.556234 -1.016) (xy 136.091422 -1.016) (xy 136.081358 -1.016438) (xy 136.062774 -1.024172)
			(xy 136.055354 -1.030986) (xy 136.03571 -1.050208) (xy 135.991891 -1.083381) (xy 135.943765 -1.109922)
			(xy 135.892328 -1.129283) (xy 135.838645 -1.141062) (xy 135.783828 -1.145016) (xy 135.729011 -1.141062)
			(xy 135.675328 -1.129283) (xy 135.623891 -1.109922) (xy 135.575765 -1.083381) (xy 135.531946 -1.050208)
			(xy 135.512302 -1.030986) (xy 135.504908 -1.02413) (xy 135.486309 -1.016381) (xy 135.476234 -1.016)
			(xy 131.011422 -1.016) (xy 131.001358 -1.016438) (xy 130.982774 -1.024172) (xy 130.975354 -1.030986)
			(xy 130.95571 -1.050208) (xy 130.911891 -1.083381) (xy 130.863765 -1.109922) (xy 130.812328 -1.129283)
			(xy 130.758645 -1.141062) (xy 130.703828 -1.145016) (xy 130.649011 -1.141062) (xy 130.595328 -1.129283)
			(xy 130.543891 -1.109922) (xy 130.495765 -1.083381) (xy 130.451946 -1.050208) (xy 130.432302 -1.030986)
			(xy 130.424908 -1.02413) (xy 130.406309 -1.016381) (xy 130.396234 -1.016) (xy 125.931422 -1.016)
			(xy 125.921358 -1.016438) (xy 125.902774 -1.024172) (xy 125.895354 -1.030986) (xy 125.87571 -1.050208)
			(xy 125.831891 -1.083381) (xy 125.783765 -1.109922) (xy 125.732328 -1.129283) (xy 125.678645 -1.141062)
			(xy 125.623828 -1.145016) (xy 125.569011 -1.141062) (xy 125.515328 -1.129283) (xy 125.463891 -1.109922)
			(xy 125.415765 -1.083381) (xy 125.371946 -1.050208) (xy 125.352302 -1.030986) (xy 125.344908 -1.02413)
			(xy 125.326309 -1.016381) (xy 125.316234 -1.016) (xy 120.851422 -1.016) (xy 120.841358 -1.016438)
			(xy 120.822774 -1.024172) (xy 120.815354 -1.030986) (xy 120.79571 -1.050208) (xy 120.751891 -1.083381)
			(xy 120.703765 -1.109922) (xy 120.652328 -1.129283) (xy 120.598645 -1.141062) (xy 120.543828 -1.145016)
			(xy 120.489011 -1.141062) (xy 120.435328 -1.129283) (xy 120.383891 -1.109922) (xy 120.335765 -1.083381)
			(xy 120.291946 -1.050208) (xy 120.272302 -1.030986) (xy 120.264908 -1.02413) (xy 120.246309 -1.016381)
			(xy 120.236234 -1.016) (xy 115.771422 -1.016) (xy 115.761358 -1.016438) (xy 115.742774 -1.024172)
			(xy 115.735354 -1.030986) (xy 115.71571 -1.050208) (xy 115.671891 -1.083381) (xy 115.623765 -1.109922)
			(xy 115.572328 -1.129283) (xy 115.518645 -1.141062) (xy 115.463828 -1.145016) (xy 115.409011 -1.141062)
			(xy 115.355328 -1.129283) (xy 115.303891 -1.109922) (xy 115.255765 -1.083381) (xy 115.211946 -1.050208)
			(xy 115.192302 -1.030986) (xy 115.184908 -1.02413) (xy 115.166309 -1.016381) (xy 115.156234 -1.016)
			(xy 110.691422 -1.016) (xy 110.681358 -1.016438) (xy 110.662774 -1.024172) (xy 110.655354 -1.030986)
			(xy 110.63571 -1.050208) (xy 110.591891 -1.083381) (xy 110.543765 -1.109922) (xy 110.492328 -1.129283)
			(xy 110.438645 -1.141062) (xy 110.383828 -1.145016) (xy 110.329011 -1.141062) (xy 110.275328 -1.129283)
			(xy 110.223891 -1.109922) (xy 110.175765 -1.083381) (xy 110.131946 -1.050208) (xy 110.112302 -1.030986)
			(xy 110.104908 -1.02413) (xy 110.086309 -1.016381) (xy 110.076234 -1.016) (xy 105.611422 -1.016)
			(xy 105.601358 -1.016438) (xy 105.582774 -1.024172) (xy 105.575354 -1.030986) (xy 105.55571 -1.050208)
			(xy 105.511891 -1.083381) (xy 105.463765 -1.109922) (xy 105.412328 -1.129283) (xy 105.358645 -1.141062)
			(xy 105.303828 -1.145016) (xy 105.249011 -1.141062) (xy 105.195328 -1.129283) (xy 105.143891 -1.109922)
			(xy 105.095765 -1.083381) (xy 105.051946 -1.050208) (xy 105.032302 -1.030986) (xy 105.024908 -1.02413)
			(xy 105.006309 -1.016381) (xy 104.996234 -1.016) (xy 100.531422 -1.016) (xy 100.521358 -1.016438)
			(xy 100.502774 -1.024172) (xy 100.495354 -1.030986) (xy 100.47571 -1.050208) (xy 100.431891 -1.083381)
			(xy 100.383765 -1.109922) (xy 100.332328 -1.129283) (xy 100.278645 -1.141062) (xy 100.223828 -1.145016)
			(xy 100.169011 -1.141062) (xy 100.115328 -1.129283) (xy 100.063891 -1.109922) (xy 100.015765 -1.083381)
			(xy 99.971946 -1.050208) (xy 99.952302 -1.030986) (xy 99.944908 -1.02413) (xy 99.926309 -1.016381)
			(xy 99.916234 -1.016) (xy 95.451422 -1.016) (xy 95.441358 -1.016438) (xy 95.422774 -1.024172) (xy 95.415354 -1.030986)
			(xy 95.39571 -1.050208) (xy 95.351891 -1.083381) (xy 95.303765 -1.109922) (xy 95.252328 -1.129283)
			(xy 95.198645 -1.141062) (xy 95.143828 -1.145016) (xy 95.089011 -1.141062) (xy 95.035328 -1.129283)
			(xy 94.983891 -1.109922) (xy 94.935765 -1.083381) (xy 94.891946 -1.050208) (xy 94.872302 -1.030986)
			(xy 94.864908 -1.02413) (xy 94.846309 -1.016381) (xy 94.836234 -1.016) (xy 90.371422 -1.016) (xy 90.361358 -1.016438)
			(xy 90.342774 -1.024172) (xy 90.335354 -1.030986) (xy 90.31571 -1.050208) (xy 90.271891 -1.083381)
			(xy 90.223765 -1.109922) (xy 90.172328 -1.129283) (xy 90.118645 -1.141062) (xy 90.063828 -1.145016)
			(xy 90.009011 -1.141062) (xy 89.955328 -1.129283) (xy 89.903891 -1.109922) (xy 89.855765 -1.083381)
			(xy 89.811946 -1.050208) (xy 89.792302 -1.030986) (xy 89.784908 -1.02413) (xy 89.766309 -1.016381)
			(xy 89.756234 -1.016) (xy 85.291422 -1.016) (xy 85.281358 -1.016438) (xy 85.262774 -1.024172) (xy 85.255354 -1.030986)
			(xy 85.23571 -1.050208) (xy 85.191891 -1.083381) (xy 85.143765 -1.109922) (xy 85.092328 -1.129283)
			(xy 85.038645 -1.141062) (xy 84.983828 -1.145016) (xy 84.929011 -1.141062) (xy 84.875328 -1.129283)
			(xy 84.823891 -1.109922) (xy 84.775765 -1.083381) (xy 84.731946 -1.050208) (xy 84.712302 -1.030986)
			(xy 84.704908 -1.02413) (xy 84.686309 -1.016381) (xy 84.676234 -1.016) (xy 80.211422 -1.016) (xy 80.201358 -1.016438)
			(xy 80.182774 -1.024172) (xy 80.175354 -1.030986) (xy 80.15571 -1.050208) (xy 80.111891 -1.083381)
			(xy 80.063765 -1.109922) (xy 80.012328 -1.129283) (xy 79.958645 -1.141062) (xy 79.903828 -1.145016)
			(xy 79.849011 -1.141062) (xy 79.795328 -1.129283) (xy 79.743891 -1.109922) (xy 79.695765 -1.083381)
			(xy 79.651946 -1.050208) (xy 79.632302 -1.030986) (xy 79.624908 -1.02413) (xy 79.606309 -1.016381)
			(xy 79.596234 -1.016) (xy 75.131422 -1.016) (xy 75.121358 -1.016438) (xy 75.102774 -1.024172) (xy 75.095354 -1.030986)
			(xy 75.07571 -1.050208) (xy 75.031891 -1.083381) (xy 74.983765 -1.109922) (xy 74.932328 -1.129283)
			(xy 74.878645 -1.141062) (xy 74.823828 -1.145016) (xy 74.769011 -1.141062) (xy 74.715328 -1.129283)
			(xy 74.663891 -1.109922) (xy 74.615765 -1.083381) (xy 74.571946 -1.050208) (xy 74.552302 -1.030986)
			(xy 74.544908 -1.02413) (xy 74.526309 -1.016381) (xy 74.516234 -1.016) (xy 70.051422 -1.016) (xy 70.041358 -1.016438)
			(xy 70.022774 -1.024172) (xy 70.015354 -1.030986) (xy 69.99571 -1.050208) (xy 69.951891 -1.083381)
			(xy 69.903765 -1.109922) (xy 69.852328 -1.129283) (xy 69.798645 -1.141062) (xy 69.743828 -1.145016)
			(xy 69.689011 -1.141062) (xy 69.635328 -1.129283) (xy 69.583891 -1.109922) (xy 69.535765 -1.083381)
			(xy 69.491946 -1.050208) (xy 69.472302 -1.030986) (xy 69.464908 -1.02413) (xy 69.446309 -1.016381)
			(xy 69.436234 -1.016) (xy 64.971422 -1.016) (xy 64.961358 -1.016438) (xy 64.942774 -1.024172) (xy 64.935354 -1.030986)
			(xy 64.91571 -1.050208) (xy 64.871891 -1.083381) (xy 64.823765 -1.109922) (xy 64.772328 -1.129283)
			(xy 64.718645 -1.141062) (xy 64.663828 -1.145016) (xy 64.609011 -1.141062) (xy 64.555328 -1.129283)
			(xy 64.503891 -1.109922) (xy 64.455765 -1.083381) (xy 64.411946 -1.050208) (xy 64.392302 -1.030986)
			(xy 64.384908 -1.02413) (xy 64.366309 -1.016381) (xy 64.356234 -1.016) (xy 59.891422 -1.016) (xy 59.881358 -1.016438)
			(xy 59.862774 -1.024172) (xy 59.855354 -1.030986) (xy 59.83571 -1.050208) (xy 59.791891 -1.083381)
			(xy 59.743765 -1.109922) (xy 59.692328 -1.129283) (xy 59.638645 -1.141062) (xy 59.583828 -1.145016)
			(xy 59.529011 -1.141062) (xy 59.475328 -1.129283) (xy 59.423891 -1.109922) (xy 59.375765 -1.083381)
			(xy 59.331946 -1.050208) (xy 59.312302 -1.030986) (xy 59.304908 -1.02413) (xy 59.286309 -1.016381)
			(xy 59.276234 -1.016) (xy 54.811422 -1.016) (xy 54.801358 -1.016438) (xy 54.782774 -1.024172) (xy 54.775354 -1.030986)
			(xy 54.75571 -1.050208) (xy 54.711891 -1.083381) (xy 54.663765 -1.109922) (xy 54.612328 -1.129283)
			(xy 54.558645 -1.141062) (xy 54.503828 -1.145016) (xy 54.449011 -1.141062) (xy 54.395328 -1.129283)
			(xy 54.343891 -1.109922) (xy 54.295765 -1.083381) (xy 54.251946 -1.050208) (xy 54.232302 -1.030986)
			(xy 54.224908 -1.02413) (xy 54.206309 -1.016381) (xy 54.196234 -1.016) (xy 49.731422 -1.016) (xy 49.721358 -1.016438)
			(xy 49.702774 -1.024172) (xy 49.695354 -1.030986) (xy 49.67571 -1.050208) (xy 49.631891 -1.083381)
			(xy 49.583765 -1.109922) (xy 49.532328 -1.129283) (xy 49.478645 -1.141062) (xy 49.423828 -1.145016)
			(xy 49.369011 -1.141062) (xy 49.315328 -1.129283) (xy 49.263891 -1.109922) (xy 49.215765 -1.083381)
			(xy 49.171946 -1.050208) (xy 49.152302 -1.030986) (xy 49.144908 -1.02413) (xy 49.126309 -1.016381)
			(xy 49.116234 -1.016) (xy 44.651422 -1.016) (xy 44.641358 -1.016438) (xy 44.622774 -1.024172) (xy 44.615354 -1.030986)
			(xy 44.59571 -1.050208) (xy 44.551891 -1.083381) (xy 44.503765 -1.109922) (xy 44.452328 -1.129283)
			(xy 44.398645 -1.141062) (xy 44.343828 -1.145016) (xy 44.289011 -1.141062) (xy 44.235328 -1.129283)
			(xy 44.183891 -1.109922) (xy 44.135765 -1.083381) (xy 44.091946 -1.050208) (xy 44.072302 -1.030986)
			(xy 44.064908 -1.02413) (xy 44.046309 -1.016381) (xy 44.036234 -1.016) (xy 39.571422 -1.016) (xy 39.561358 -1.016438)
			(xy 39.542774 -1.024172) (xy 39.535354 -1.030986) (xy 39.51571 -1.050208) (xy 39.471891 -1.083381)
			(xy 39.423765 -1.109922) (xy 39.372328 -1.129283) (xy 39.318645 -1.141062) (xy 39.263828 -1.145016)
			(xy 39.209011 -1.141062) (xy 39.155328 -1.129283) (xy 39.103891 -1.109922) (xy 39.055765 -1.083381)
			(xy 39.011946 -1.050208) (xy 38.992302 -1.030986) (xy 38.984908 -1.02413) (xy 38.966309 -1.016381)
			(xy 38.956234 -1.016) (xy 34.491422 -1.016) (xy 34.481358 -1.016438) (xy 34.462774 -1.024172) (xy 34.455354 -1.030986)
			(xy 34.43571 -1.050208) (xy 34.391891 -1.083381) (xy 34.343765 -1.109922) (xy 34.292328 -1.129283)
			(xy 34.238645 -1.141062) (xy 34.183828 -1.145016) (xy 34.129011 -1.141062) (xy 34.075328 -1.129283)
			(xy 34.023891 -1.109922) (xy 33.975765 -1.083381) (xy 33.931946 -1.050208) (xy 33.912302 -1.030986)
			(xy 33.904908 -1.02413) (xy 33.886309 -1.016381) (xy 33.876234 -1.016) (xy 29.411422 -1.016) (xy 29.401358 -1.016438)
			(xy 29.382774 -1.024172) (xy 29.375354 -1.030986) (xy 29.35571 -1.050208) (xy 29.311891 -1.083381)
			(xy 29.263765 -1.109922) (xy 29.212328 -1.129283) (xy 29.158645 -1.141062) (xy 29.103828 -1.145016)
			(xy 29.049011 -1.141062) (xy 28.995328 -1.129283) (xy 28.943891 -1.109922) (xy 28.895765 -1.083381)
			(xy 28.851946 -1.050208) (xy 28.832302 -1.030986) (xy 28.824908 -1.02413) (xy 28.806309 -1.016381)
			(xy 28.796234 -1.016) (xy 24.331422 -1.016) (xy 24.321358 -1.016438) (xy 24.302774 -1.024172) (xy 24.295354 -1.030986)
			(xy 24.27571 -1.050208) (xy 24.231891 -1.083381) (xy 24.183765 -1.109922) (xy 24.132328 -1.129283)
			(xy 24.078645 -1.141062) (xy 24.023828 -1.145016) (xy 23.969011 -1.141062) (xy 23.915328 -1.129283)
			(xy 23.863891 -1.109922) (xy 23.815765 -1.083381) (xy 23.771946 -1.050208) (xy 23.752302 -1.030986)
			(xy 23.744908 -1.02413) (xy 23.726309 -1.016381) (xy 23.716234 -1.016) (xy 19.251422 -1.016) (xy 19.241358 -1.016438)
			(xy 19.222774 -1.024172) (xy 19.215354 -1.030986) (xy 19.19571 -1.050208) (xy 19.151891 -1.083381)
			(xy 19.103765 -1.109922) (xy 19.052328 -1.129283) (xy 18.998645 -1.141062) (xy 18.943828 -1.145016)
			(xy 18.889011 -1.141062) (xy 18.835328 -1.129283) (xy 18.783891 -1.109922) (xy 18.735765 -1.083381)
			(xy 18.691946 -1.050208) (xy 18.672302 -1.030986) (xy 18.664908 -1.02413) (xy 18.646309 -1.016381)
			(xy 18.636234 -1.016) (xy 14.171422 -1.016) (xy 14.161358 -1.016438) (xy 14.142774 -1.024172) (xy 14.135354 -1.030986)
			(xy 14.11571 -1.050208) (xy 14.071891 -1.083381) (xy 14.023765 -1.109922) (xy 13.972328 -1.129283)
			(xy 13.918645 -1.141062) (xy 13.863828 -1.145016) (xy 13.809011 -1.141062) (xy 13.755328 -1.129283)
			(xy 13.703891 -1.109922) (xy 13.655765 -1.083381) (xy 13.611946 -1.050208) (xy 13.592302 -1.030986)
			(xy 13.584908 -1.02413) (xy 13.566309 -1.016381) (xy 13.556234 -1.016) (xy 9.091422 -1.016) (xy 9.081358 -1.016438)
			(xy 9.062774 -1.024172) (xy 9.055354 -1.030986) (xy 9.03571 -1.050208) (xy 8.991891 -1.083381) (xy 8.943765 -1.109922)
			(xy 8.892328 -1.129283) (xy 8.838645 -1.141062) (xy 8.783828 -1.145016) (xy 8.729011 -1.141062) (xy 8.675328 -1.129283)
			(xy 8.623891 -1.109922) (xy 8.575765 -1.083381) (xy 8.531946 -1.050208) (xy 8.512302 -1.030986) (xy 8.504908 -1.02413)
			(xy 8.486309 -1.016381) (xy 8.476234 -1.016) (xy 4.99999 -1.016) (xy 4.911869 -1.016489) (xy 4.735799 -1.024283)
			(xy 4.560245 -1.039852) (xy 4.385551 -1.063166) (xy 4.212059 -1.094177) (xy 4.125976 -1.113028) (xy 4.11582 -1.115919)
			(xy 4.0989 -1.128516) (xy 4.09321 -1.137412) (xy 4.078515 -1.162024) (xy 4.042904 -1.206939) (xy 4.00098 -1.246029)
			(xy 3.953685 -1.278413) (xy 3.902081 -1.303366) (xy 3.847327 -1.320326) (xy 3.790654 -1.328912) (xy 3.761994 -1.329436)
			(xy 3.73286 -1.328887) (xy 3.675272 -1.320014) (xy 3.61971 -1.30246) (xy 3.593338 -1.290066) (xy 3.583614 -1.285902)
			(xy 3.562501 -1.285002) (xy 3.552444 -1.288288) (xy 3.46867 -1.321501) (xy 3.303889 -1.394516) (xy 3.142578 -1.474907)
			(xy 2.985068 -1.562511) (xy 2.83168 -1.657147) (xy 2.682728 -1.758623) (xy 2.538518 -1.86673) (xy 2.399343 -1.981248)
			(xy 2.265489 -2.101942) (xy 2.13723 -2.228565) (xy 2.014828 -2.360859) (xy 1.898533 -2.498552) (xy 1.788584 -2.641363)
			(xy 1.685205 -2.789) (xy 1.588607 -2.941161) (xy 1.498989 -3.097534) (xy 1.416534 -3.257799) (xy 1.34141 -3.421629)
			(xy 1.273772 -3.588689) (xy 1.213756 -3.758636) (xy 1.161488 -3.931123) (xy 1.117072 -4.105798) (xy 1.0806 -4.282302)
			(xy 1.052147 -4.460275) (xy 1.031771 -4.639352) (xy 1.025144 -4.729226) (xy 1.024848 -4.739861) (xy 1.03208 -4.759851)
			(xy 1.039114 -4.767834) (xy 1.058824 -4.789242) (xy 1.092179 -4.836924) (xy 1.117897 -4.889122) (xy 1.135381 -4.944623)
			(xy 1.144222 -5.002137) (xy 1.144778 -5.031232) (xy 1.14422 -5.06149) (xy 1.134708 -5.121253) (xy 1.115877 -5.178764)
			(xy 1.088201 -5.23258) (xy 1.052374 -5.281351) (xy 1.03124 -5.303012) (xy 1.024327 -5.310384) (xy 1.01647 -5.328985)
			(xy 1.016 -5.33908) (xy 1.016 -8.533384) (xy 1.016484 -8.543476) (xy 1.024338 -8.562074) (xy 1.03124 -8.569452)
			(xy 1.052367 -8.591119) (xy 1.088186 -8.639892) (xy 1.115859 -8.693708) (xy 1.134692 -8.751216) (xy 1.144214 -8.810975)
			(xy 1.144778 -8.841232) (xy 1.14422 -8.87149) (xy 1.134708 -8.931253) (xy 1.115877 -8.988764) (xy 1.088201 -9.04258)
			(xy 1.052374 -9.091351) (xy 1.03124 -9.113012) (xy 1.024327 -9.120384) (xy 1.01647 -9.138985) (xy 1.016 -9.14908)
			(xy 1.016 -14.883384) (xy 1.016484 -14.893476) (xy 1.024338 -14.912074) (xy 1.03124 -14.919452) (xy 1.052367 -14.941119)
			(xy 1.088186 -14.989892) (xy 1.115859 -15.043708) (xy 1.134692 -15.101216) (xy 1.144214 -15.160975)
			(xy 1.144778 -15.191232) (xy 1.14422 -15.22149) (xy 1.134708 -15.281253) (xy 1.115877 -15.338764)
			(xy 1.088201 -15.39258) (xy 1.052374 -15.441351) (xy 1.03124 -15.463012) (xy 1.024327 -15.470384)
			(xy 1.01647 -15.488985) (xy 1.016 -15.49908) (xy 1.016 -16.070072) (xy 1.01651 -16.133628) (xy 1.024651 -16.260479)
			(xy 1.040895 -16.386548) (xy 1.065177 -16.511319) (xy 1.097396 -16.63428) (xy 1.13742 -16.754926)
			(xy 1.185085 -16.872762) (xy 1.240196 -16.987306) (xy 1.302526 -17.098087) (xy 1.37182 -17.20465)
			(xy 1.447793 -17.306559) (xy 1.530134 -17.403396) (xy 1.618505 -17.494763) (xy 1.712544 -17.580285)
			(xy 1.811864 -17.659613) (xy 1.916059 -17.732419) (xy 2.024701 -17.798407) (xy 2.137345 -17.857304)
			(xy 2.253527 -17.90887) (xy 2.372772 -17.952892) (xy 2.494591 -17.989191) (xy 2.618483 -18.017617)
			(xy 2.743942 -18.038054) (xy 2.870451 -18.050418) (xy 2.933954 -18.05305) (xy 2.944435 -18.052797)
			(xy 2.963841 -18.044921) (xy 2.971546 -18.03781) (xy 2.993199 -18.016773) (xy 3.041911 -17.981118)
			(xy 3.095629 -17.953576) (xy 3.153014 -17.934837) (xy 3.212634 -17.925366) (xy 3.242818 -17.92478)
			(xy 3.273121 -17.925365) (xy 3.332964 -17.934952) (xy 3.390538 -17.953881) (xy 3.444394 -17.981678)
			(xy 3.493177 -18.017641) (xy 3.514852 -18.038826) (xy 3.522277 -18.045777) (xy 3.541012 -18.053648)
			(xy 3.551174 -18.054066) (xy 9.600184 -18.054066) (xy 9.653964 -18.054536) (xy 9.761254 -18.062158)
			(xy 9.867733 -18.077366) (xy 9.972867 -18.100082) (xy 10.076127 -18.130192) (xy 10.176992 -18.167546)
			(xy 10.274957 -18.211954) (xy 10.369527 -18.263194) (xy 10.460228 -18.321008) (xy 10.546604 -18.385106)
			(xy 10.628219 -18.455164) (xy 10.704663 -18.53083) (xy 10.775552 -18.611724) (xy 10.84053 -18.69744)
			(xy 10.899269 -18.787545) (xy 10.951473 -18.881586) (xy 10.996881 -18.979091) (xy 11.016488 -19.029172)
			(xy 11.020555 -19.038569) (xy 11.03471 -19.053339) (xy 11.053506 -19.061418) (xy 11.063732 -19.061938)
			(xy 31.253938 -19.061938) (xy 31.287197 -19.062462) (xy 31.353146 -19.071153) (xy 31.417395 -19.08838)
			(xy 31.478845 -19.11385) (xy 31.536443 -19.147126) (xy 31.589202 -19.187637) (xy 31.613094 -19.210782)
			(xy 32.236156 -19.833844) (xy 32.259312 -19.857724) (xy 32.299818 -19.910488) (xy 32.333089 -19.968089)
			(xy 32.358553 -20.02954) (xy 32.375775 -20.093791) (xy 32.384461 -20.159741) (xy 32.385 -20.193)
			(xy 32.385 -25.59157) (xy 42.354235 -25.59157) (xy 42.354235 -25.46243) (xy 42.362185 -25.333535)
			(xy 42.378055 -25.205375) (xy 42.401784 -25.078434) (xy 42.433283 -24.953195) (xy 42.472432 -24.830132)
			(xy 42.519083 -24.709713) (xy 42.573058 -24.592394) (xy 42.634153 -24.47862) (xy 42.702136 -24.368823)
			(xy 42.77675 -24.26342) (xy 42.857711 -24.16281) (xy 42.944711 -24.067375) (xy 43.037422 -23.977476)
			(xy 43.135492 -23.893455) (xy 43.238547 -23.815631) (xy 43.346198 -23.744299) (xy 43.458037 -23.679729)
			(xy 43.573638 -23.622167) (xy 43.692563 -23.57183) (xy 43.814362 -23.52891) (xy 43.938572 -23.493569)
			(xy 44.064721 -23.465942) (xy 44.192333 -23.446133) (xy 44.320922 -23.434217) (xy 44.45 -23.430241)
			(xy 44.579078 -23.434217) (xy 44.707667 -23.446133) (xy 44.835279 -23.465942) (xy 44.961428 -23.493569)
			(xy 45.085638 -23.52891) (xy 45.207437 -23.57183) (xy 45.326362 -23.622167) (xy 45.441963 -23.679729)
			(xy 45.553802 -23.744299) (xy 45.661453 -23.815631) (xy 45.764508 -23.893455) (xy 45.862578 -23.977476)
			(xy 45.955289 -24.067375) (xy 46.042289 -24.16281) (xy 46.12325 -24.26342) (xy 46.197864 -24.368823)
			(xy 46.265847 -24.47862) (xy 46.326942 -24.592394) (xy 46.380917 -24.709713) (xy 46.427568 -24.830132)
			(xy 46.466717 -24.953195) (xy 46.498216 -25.078434) (xy 46.521945 -25.205375) (xy 46.537815 -25.333535)
			(xy 46.545765 -25.46243) (xy 46.546262 -25.527) (xy 46.545765 -25.59157) (xy 46.537815 -25.720465)
			(xy 46.521945 -25.848625) (xy 46.498216 -25.975566) (xy 46.466717 -26.100805) (xy 46.427568 -26.223868)
			(xy 46.380917 -26.344287) (xy 46.326942 -26.461606) (xy 46.265847 -26.57538) (xy 46.197864 -26.685177)
			(xy 46.12325 -26.79058) (xy 46.042289 -26.89119) (xy 45.955289 -26.986625) (xy 45.862578 -27.076524)
			(xy 45.764508 -27.160545) (xy 45.661453 -27.238369) (xy 45.553802 -27.309701) (xy 45.441963 -27.374271)
			(xy 45.326362 -27.431833) (xy 45.207437 -27.48217) (xy 45.085638 -27.52509) (xy 44.961428 -27.560431)
			(xy 44.835279 -27.588058) (xy 44.707667 -27.607867) (xy 44.579078 -27.619783) (xy 44.45 -27.62376)
			(xy 44.320922 -27.619783) (xy 44.192333 -27.607867) (xy 44.064721 -27.588058) (xy 43.938572 -27.560431)
			(xy 43.814362 -27.52509) (xy 43.692563 -27.48217) (xy 43.573638 -27.431833) (xy 43.458037 -27.374271)
			(xy 43.346198 -27.309701) (xy 43.238547 -27.238369) (xy 43.135492 -27.160545) (xy 43.037422 -27.076524)
			(xy 42.944711 -26.986625) (xy 42.857711 -26.89119) (xy 42.77675 -26.79058) (xy 42.702136 -26.685177)
			(xy 42.634153 -26.57538) (xy 42.573058 -26.461606) (xy 42.519083 -26.344287) (xy 42.472432 -26.223868)
			(xy 42.433283 -26.100805) (xy 42.401784 -25.975566) (xy 42.378055 -25.848625) (xy 42.362185 -25.720465)
			(xy 42.354235 -25.59157) (xy 32.385 -25.59157) (xy 32.385 -30.607) (xy 32.384479 -30.64026) (xy 32.375791 -30.70621)
			(xy 32.358566 -30.770461) (xy 32.333097 -30.831912) (xy 32.299821 -30.889511) (xy 32.259308 -30.942271)
			(xy 32.236156 -30.966156) (xy 31.773114 -31.429198) (xy 31.749234 -31.452354) (xy 31.696471 -31.492861)
			(xy 31.63887 -31.52613) (xy 31.577418 -31.551592) (xy 31.513167 -31.568811) (xy 31.447217 -31.577493)
			(xy 31.413958 -31.578042) (xy 11.063732 -31.578042) (xy 11.053503 -31.578556) (xy 11.034703 -31.586634)
			(xy 11.020541 -31.601404) (xy 11.016488 -31.610808) (xy 10.996858 -31.660879) (xy 10.951451 -31.758384)
			(xy 10.899247 -31.852425) (xy 10.84051 -31.942529) (xy 10.775534 -32.028245) (xy 10.704646 -32.109139)
			(xy 10.628203 -32.184805) (xy 10.54659 -32.254864) (xy 10.460216 -32.318962) (xy 10.369517 -32.376777)
			(xy 10.274948 -32.428018) (xy 10.176985 -32.472427) (xy 10.076121 -32.509782) (xy 9.972863 -32.539894)
			(xy 9.86773 -32.562611) (xy 9.761252 -32.577821) (xy 9.653964 -32.585445) (xy 9.600184 -32.585914)
			(xy 7.23519 -32.585914) (xy 7.225032 -32.586357) (xy 7.206294 -32.59421) (xy 7.198868 -32.601154)
			(xy 7.179211 -32.620456) (xy 7.135338 -32.653776) (xy 7.087129 -32.680439) (xy 7.035586 -32.69989)
			(xy 6.981782 -32.711725) (xy 6.926834 -32.715697) (xy 6.871886 -32.711725) (xy 6.818082 -32.69989)
			(xy 6.766539 -32.680439) (xy 6.71833 -32.653776) (xy 6.674457 -32.620456) (xy 6.6548 -32.601154)
			(xy 6.647377 -32.594201) (xy 6.62864 -32.586336) (xy 6.618478 -32.585914) (xy 2.999994 -32.585914)
			(xy 2.941974 -32.586335) (xy 2.826132 -32.593118) (xy 2.710885 -32.606662) (xy 2.596627 -32.626918)
			(xy 2.483748 -32.653819) (xy 2.372634 -32.687272) (xy 2.318004 -32.706818) (xy 2.307685 -32.711166)
			(xy 2.29187 -32.726979) (xy 2.287524 -32.737298) (xy 2.27703 -32.764482) (xy 2.248986 -32.815559)
			(xy 2.213504 -32.861779) (xy 2.171408 -32.902068) (xy 2.123677 -32.935489) (xy 2.07142 -32.961267)
			(xy 2.015852 -32.978801) (xy 1.958264 -32.987684) (xy 1.92913 -32.98825) (xy 1.907867 -32.987973)
			(xy 1.865604 -32.983261) (xy 1.844802 -32.978852) (xy 1.83385 -32.976902) (xy 1.812117 -32.981524)
			(xy 1.802892 -32.987742) (xy 1.754489 -33.024952) (xy 1.661833 -33.104473) (xy 1.574243 -33.189542)
			(xy 1.492051 -33.279838) (xy 1.415567 -33.375017) (xy 1.345082 -33.474719) (xy 1.280862 -33.578569)
			(xy 1.223151 -33.686171) (xy 1.172167 -33.797118) (xy 1.128102 -33.910992) (xy 1.091125 -34.027359)
			(xy 1.061374 -34.145781) (xy 1.038963 -34.265808) (xy 1.023976 -34.386987) (xy 1.01647 -34.508857)
			(xy 1.016 -34.569908) (xy 1.016 -36.582604) (xy 1.016488 -36.592694) (xy 1.024347 -36.611287) (xy 1.03124 -36.618672)
			(xy 1.052367 -36.640339) (xy 1.088186 -36.689112) (xy 1.115859 -36.742928) (xy 1.134692 -36.800436)
			(xy 1.144214 -36.860195) (xy 1.144778 -36.890452) (xy 1.14422 -36.92071) (xy 1.134708 -36.980473)
			(xy 1.115877 -37.037984) (xy 1.088201 -37.0918) (xy 1.052374 -37.140571) (xy 1.03124 -37.162232)
			(xy 1.02433 -37.169605) (xy 1.01648 -37.188206) (xy 1.016 -37.1983) (xy 1.016 -41.662604) (xy 1.016488 -41.672694)
			(xy 1.024347 -41.691287) (xy 1.03124 -41.698672) (xy 1.052367 -41.720339) (xy 1.088186 -41.769112)
			(xy 1.115859 -41.822928) (xy 1.134692 -41.880436) (xy 1.144214 -41.940195) (xy 1.144778 -41.970452)
			(xy 1.14422 -42.00071) (xy 1.134708 -42.060473) (xy 1.115877 -42.117984) (xy 1.088201 -42.1718) (xy 1.052374 -42.220571)
			(xy 1.03124 -42.242232) (xy 1.02433 -42.249605) (xy 1.01648 -42.268206) (xy 1.016 -42.2783) (xy 1.016 -46.742604)
			(xy 1.016488 -46.752694) (xy 1.024347 -46.771287) (xy 1.03124 -46.778672) (xy 1.052367 -46.800339)
			(xy 1.088186 -46.849112) (xy 1.115859 -46.902928) (xy 1.134692 -46.960436) (xy 1.144214 -47.020195)
			(xy 1.144778 -47.050452) (xy 1.14422 -47.08071) (xy 1.134708 -47.140473) (xy 1.115877 -47.197984)
			(xy 1.088201 -47.2518) (xy 1.052374 -47.300571) (xy 1.03124 -47.322232) (xy 1.02433 -47.329605) (xy 1.01648 -47.348206)
			(xy 1.016 -47.3583) (xy 1.016 -51.822604) (xy 1.016488 -51.832694) (xy 1.024347 -51.851287) (xy 1.03124 -51.858672)
			(xy 1.052367 -51.880339) (xy 1.088186 -51.929112) (xy 1.115859 -51.982928) (xy 1.134692 -52.040436)
			(xy 1.144214 -52.100195) (xy 1.144778 -52.130452) (xy 1.14422 -52.16071) (xy 1.134708 -52.220473)
			(xy 1.115877 -52.277984) (xy 1.088201 -52.3318) (xy 1.052374 -52.380571) (xy 1.03124 -52.402232)
			(xy 1.02433 -52.409605) (xy 1.01648 -52.428206) (xy 1.016 -52.4383) (xy 1.016 -54.399942) (xy 3.446023 -54.399942)
			(xy 3.450044 -54.28608) (xy 3.462086 -54.172786) (xy 3.482091 -54.060624) (xy 3.509957 -53.950152)
			(xy 3.545546 -53.84192) (xy 3.588681 -53.736469) (xy 3.639147 -53.634323) (xy 3.696693 -53.535992)
			(xy 3.761032 -53.441964) (xy 3.831843 -53.352709) (xy 3.908773 -53.268672) (xy 3.99144 -53.19027)
			(xy 4.079431 -53.117895) (xy 4.172308 -53.051907) (xy 4.269609 -52.992635) (xy 4.370848 -52.940374)
			(xy 4.475522 -52.895384) (xy 4.583108 -52.85789) (xy 4.693071 -52.828079) (xy 4.804864 -52.806098)
			(xy 4.917928 -52.792058) (xy 5.0317 -52.786028) (xy 5.145615 -52.788039) (xy 5.259104 -52.79808)
			(xy 5.371603 -52.816102) (xy 5.482549 -52.842014) (xy 5.591392 -52.875688) (xy 5.697588 -52.916955)
			(xy 5.800608 -52.965611) (xy 5.89994 -53.021412) (xy 5.995089 -53.084081) (xy 6.085579 -53.153306)
			(xy 6.170961 -53.228741) (xy 6.25081 -53.310012) (xy 6.324727 -53.396712) (xy 6.392343 -53.48841)
			(xy 6.453324 -53.584649) (xy 6.507363 -53.684951) (xy 6.554193 -53.788814) (xy 6.59358 -53.895722)
			(xy 6.625327 -54.005142) (xy 6.649277 -54.116528) (xy 6.665311 -54.229327) (xy 6.673347 -54.342976)
			(xy 6.67385 -54.399942) (xy 6.673347 -54.456908) (xy 6.665311 -54.570557) (xy 6.649277 -54.683356)
			(xy 6.625327 -54.794742) (xy 6.59358 -54.904162) (xy 6.554193 -55.01107) (xy 6.507363 -55.114933)
			(xy 6.453324 -55.215235) (xy 6.392343 -55.311474) (xy 6.324727 -55.403172) (xy 6.25081 -55.489872)
			(xy 6.170961 -55.571143) (xy 6.085579 -55.646578) (xy 5.995089 -55.715803) (xy 5.89994 -55.778472)
			(xy 5.800608 -55.834273) (xy 5.697588 -55.882929) (xy 5.591392 -55.924196) (xy 5.482549 -55.95787)
			(xy 5.371603 -55.983782) (xy 5.259104 -56.001804) (xy 5.145615 -56.011845) (xy 5.0317 -56.013856)
			(xy 4.917928 -56.007826) (xy 4.804864 -55.993786) (xy 4.693071 -55.971805) (xy 4.583108 -55.941994)
			(xy 4.475522 -55.9045) (xy 4.370848 -55.85951) (xy 4.269609 -55.807249) (xy 4.172308 -55.747977)
			(xy 4.079431 -55.681989) (xy 3.99144 -55.609614) (xy 3.908773 -55.531212) (xy 3.831843 -55.447175)
			(xy 3.761032 -55.35792) (xy 3.696693 -55.263892) (xy 3.639147 -55.165561) (xy 3.588681 -55.063415)
			(xy 3.545546 -54.957964) (xy 3.509957 -54.849732) (xy 3.482091 -54.73926) (xy 3.462086 -54.627098)
			(xy 3.450044 -54.513804) (xy 3.446023 -54.399942) (xy 1.016 -54.399942) (xy 1.016 -56.902604) (xy 1.016488 -56.912694)
			(xy 1.024347 -56.931287) (xy 1.03124 -56.938672) (xy 1.052367 -56.960339) (xy 1.088186 -57.009112)
			(xy 1.115859 -57.062928) (xy 1.134692 -57.120436) (xy 1.144214 -57.180195) (xy 1.144778 -57.210452)
			(xy 1.14422 -57.24071) (xy 1.134708 -57.300473) (xy 1.115877 -57.357984) (xy 1.088201 -57.4118) (xy 1.052374 -57.460571)
			(xy 1.03124 -57.482232) (xy 1.02433 -57.489605) (xy 1.01648 -57.508206) (xy 1.016 -57.5183) (xy 1.016 -61.982604)
			(xy 1.016488 -61.992694) (xy 1.024347 -62.011287) (xy 1.03124 -62.018672) (xy 1.052367 -62.040339)
			(xy 1.088186 -62.089112) (xy 1.115859 -62.142928) (xy 1.134692 -62.200436) (xy 1.144214 -62.260195)
			(xy 1.144778 -62.290452) (xy 1.14422 -62.32071) (xy 1.134708 -62.380473) (xy 1.115877 -62.437984)
			(xy 1.088201 -62.4918) (xy 1.052374 -62.540571) (xy 1.03124 -62.562232) (xy 1.02433 -62.569605) (xy 1.01648 -62.588206)
			(xy 1.016 -62.5983) (xy 1.016 -67.062604) (xy 1.016488 -67.072694) (xy 1.024347 -67.091287) (xy 1.03124 -67.098672)
			(xy 1.052367 -67.120339) (xy 1.088186 -67.169112) (xy 1.115859 -67.222928) (xy 1.134692 -67.280436)
			(xy 1.144214 -67.340195) (xy 1.144778 -67.370452) (xy 1.14422 -67.40071) (xy 1.134708 -67.460473)
			(xy 1.115877 -67.517984) (xy 1.088201 -67.5718) (xy 1.052374 -67.620571) (xy 1.03124 -67.642232)
			(xy 1.02433 -67.649605) (xy 1.01648 -67.668206) (xy 1.016 -67.6783) (xy 1.016 -72.142604) (xy 1.016488 -72.152694)
			(xy 1.024347 -72.171287) (xy 1.03124 -72.178672) (xy 1.052367 -72.200339) (xy 1.088186 -72.249112)
			(xy 1.115859 -72.302928) (xy 1.134692 -72.360436) (xy 1.144214 -72.420195) (xy 1.144778 -72.450452)
			(xy 1.14422 -72.48071) (xy 1.134708 -72.540473) (xy 1.115877 -72.597984) (xy 1.088201 -72.6518) (xy 1.052374 -72.700571)
			(xy 1.03124 -72.722232) (xy 1.02433 -72.729605) (xy 1.01648 -72.748206) (xy 1.016 -72.7583) (xy 1.016 -77.222604)
			(xy 1.016488 -77.232694) (xy 1.024347 -77.251287) (xy 1.03124 -77.258672) (xy 1.052367 -77.280339)
			(xy 1.088186 -77.329112) (xy 1.115859 -77.382928) (xy 1.134692 -77.440436) (xy 1.144214 -77.500195)
			(xy 1.144778 -77.530452) (xy 1.14422 -77.56071) (xy 1.134708 -77.620473) (xy 1.115877 -77.677984)
			(xy 1.088201 -77.7318) (xy 1.052374 -77.780571) (xy 1.03124 -77.802232) (xy 1.02433 -77.809605) (xy 1.01648 -77.828206)
			(xy 1.016 -77.8383) (xy 1.016 -82.302604) (xy 1.016488 -82.312694) (xy 1.024347 -82.331287) (xy 1.03124 -82.338672)
			(xy 1.052367 -82.360339) (xy 1.088186 -82.409112) (xy 1.115859 -82.462928) (xy 1.134692 -82.520436)
			(xy 1.144214 -82.580195) (xy 1.144778 -82.610452) (xy 1.14422 -82.64071) (xy 1.134708 -82.700473)
			(xy 1.115877 -82.757984) (xy 1.088201 -82.8118) (xy 1.052374 -82.860571) (xy 1.03124 -82.882232)
			(xy 1.02433 -82.889605) (xy 1.01648 -82.908206) (xy 1.016 -82.9183) (xy 1.016 -83.749896) (xy 11.118856 -83.749896)
			(xy 11.122874 -83.648894) (xy 11.134905 -83.54853) (xy 11.154871 -83.44944) (xy 11.182647 -83.352249)
			(xy 11.218058 -83.257572) (xy 11.260878 -83.166008) (xy 11.310838 -83.078135) (xy 11.367621 -82.994509)
			(xy 11.430869 -82.91566) (xy 11.500181 -82.842084) (xy 11.57512 -82.774248) (xy 11.655212 -82.71258)
			(xy 11.73995 -82.657471) (xy 11.828799 -82.609268) (xy 11.921196 -82.568277) (xy 12.016559 -82.534756)
			(xy 12.114283 -82.508918) (xy 12.21375 -82.490925) (xy 12.314333 -82.480893) (xy 12.415396 -82.478883)
			(xy 12.516298 -82.484909) (xy 12.616402 -82.498932) (xy 12.715076 -82.520865) (xy 12.811696 -82.550568)
			(xy 12.90565 -82.587854) (xy 12.996345 -82.632486) (xy 13.083207 -82.684183) (xy 13.165687 -82.742618)
			(xy 13.243264 -82.807421) (xy 13.315446 -82.878183) (xy 13.381779 -82.954456) (xy 13.441842 -83.035758)
			(xy 13.495256 -83.121575) (xy 13.541683 -83.211364) (xy 13.580829 -83.304558) (xy 13.612447 -83.400568)
			(xy 13.636337 -83.498786) (xy 13.652348 -83.598592) (xy 13.660379 -83.699355) (xy 13.660882 -83.749896)
			(xy 13.660379 -83.800437) (xy 13.652348 -83.9012) (xy 13.636337 -84.001006) (xy 13.612447 -84.099224)
			(xy 13.580829 -84.195234) (xy 13.541683 -84.288428) (xy 13.495256 -84.378217) (xy 13.441842 -84.464034)
			(xy 13.381779 -84.545336) (xy 13.315446 -84.621609) (xy 13.243264 -84.692371) (xy 13.165687 -84.757174)
			(xy 13.083207 -84.815609) (xy 12.996345 -84.867306) (xy 12.90565 -84.911938) (xy 12.811696 -84.949224)
			(xy 12.715076 -84.978927) (xy 12.616402 -85.00086) (xy 12.516298 -85.014883) (xy 12.415396 -85.020909)
			(xy 12.314333 -85.018899) (xy 12.21375 -85.008867) (xy 12.114283 -84.990874) (xy 12.016559 -84.965036)
			(xy 11.921196 -84.931515) (xy 11.828799 -84.890524) (xy 11.73995 -84.842321) (xy 11.655212 -84.787212)
			(xy 11.57512 -84.725544) (xy 11.500181 -84.657708) (xy 11.430869 -84.584132) (xy 11.367621 -84.505283)
			(xy 11.310838 -84.421657) (xy 11.260878 -84.333784) (xy 11.218058 -84.24222) (xy 11.182647 -84.147543)
			(xy 11.154871 -84.050352) (xy 11.134905 -83.951262) (xy 11.122874 -83.850898) (xy 11.118856 -83.749896)
			(xy 1.016 -83.749896) (xy 1.016 -87.382604) (xy 1.016488 -87.392694) (xy 1.024347 -87.411287) (xy 1.03124 -87.418672)
			(xy 1.052367 -87.440339) (xy 1.088186 -87.489112) (xy 1.115859 -87.542928) (xy 1.121416 -87.559896)
			(xy 9.849612 -87.559896) (xy 9.850066 -87.509996) (xy 9.857896 -87.410503) (xy 9.873509 -87.311931)
			(xy 9.896807 -87.214889) (xy 9.927648 -87.119973) (xy 9.96584 -87.02777) (xy 10.011149 -86.938847)
			(xy 10.063296 -86.853754) (xy 10.121957 -86.773014) (xy 10.186773 -86.697126) (xy 10.257344 -86.626557)
			(xy 10.333233 -86.561743) (xy 10.413974 -86.503082) (xy 10.499068 -86.450938) (xy 10.587992 -86.40563)
			(xy 10.680196 -86.36744) (xy 10.775112 -86.336601) (xy 10.872155 -86.313304) (xy 10.970727 -86.297693)
			(xy 11.07022 -86.289865) (xy 11.12012 -86.289388) (xy 11.17137 -86.289896) (xy 11.273537 -86.298164)
			(xy 11.374705 -86.314636) (xy 11.474217 -86.339204) (xy 11.571427 -86.371709) (xy 11.665703 -86.411939)
			(xy 11.756431 -86.459633) (xy 11.843023 -86.514481) (xy 11.924914 -86.576126) (xy 12.001573 -86.644168)
			(xy 12.072502 -86.718164) (xy 12.13724 -86.797634) (xy 12.195365 -86.88206) (xy 12.2465 -86.970895)
			(xy 12.290312 -87.06356) (xy 12.326518 -87.159453) (xy 12.35488 -87.257951) (xy 12.375216 -87.358414)
			(xy 12.387393 -87.460189) (xy 12.389866 -87.511382) (xy 12.390707 -87.520861) (xy 12.398315 -87.538282)
			(xy 12.411745 -87.551735) (xy 12.429153 -87.559373) (xy 12.438634 -87.56015) (xy 12.489829 -87.562618)
			(xy 12.59161 -87.574781) (xy 12.692079 -87.595106) (xy 12.790584 -87.623459) (xy 12.886484 -87.659657)
			(xy 12.979156 -87.703465) (xy 13.067997 -87.754597) (xy 13.152429 -87.812721) (xy 13.231903 -87.877459)
			(xy 13.305903 -87.94839) (xy 13.373947 -88.025052) (xy 13.435592 -88.106949) (xy 13.490439 -88.193546)
			(xy 13.53813 -88.28428) (xy 13.578355 -88.378562) (xy 13.610852 -88.475779) (xy 13.635411 -88.575298)
			(xy 13.651871 -88.676472) (xy 13.660126 -88.778644) (xy 13.660628 -88.829896) (xy 13.660114 -88.879795)
			(xy 13.652285 -88.979284) (xy 13.636673 -89.077853) (xy 13.613377 -89.174893) (xy 13.582538 -89.269806)
			(xy 13.544348 -89.362006) (xy 13.499042 -89.450927) (xy 13.446898 -89.536018) (xy 13.38824 -89.616756)
			(xy 13.323427 -89.692643) (xy 13.252861 -89.763211) (xy 13.176975 -89.828025) (xy 13.096238 -89.886685)
			(xy 13.011148 -89.93883) (xy 12.922228 -89.984138) (xy 12.830028 -90.02233) (xy 12.735116 -90.05317)
			(xy 12.638076 -90.076469) (xy 12.539508 -90.092082) (xy 12.440019 -90.099913) (xy 12.39012 -90.100404)
			(xy 12.33887 -90.099894) (xy 12.236704 -90.091626) (xy 12.135535 -90.075154) (xy 12.036023 -90.050586)
			(xy 11.938813 -90.018081) (xy 11.844537 -89.977851) (xy 11.753809 -89.930157) (xy 11.667218 -89.875309)
			(xy 11.585327 -89.813664) (xy 11.508667 -89.745623) (xy 11.437738 -89.671626) (xy 11.373001 -89.592157)
			(xy 11.314876 -89.507731) (xy 11.263741 -89.418896) (xy 11.219928 -89.326232) (xy 11.183723 -89.230338)
			(xy 11.15536 -89.13184) (xy 11.135024 -89.031377) (xy 11.122847 -88.929603) (xy 11.120374 -88.87841)
			(xy 11.119594 -88.868921) (xy 11.111973 -88.851491) (xy 11.098523 -88.838037) (xy 11.081095 -88.830409)
			(xy 11.071606 -88.829642) (xy 11.020411 -88.827172) (xy 10.918631 -88.815009) (xy 10.818161 -88.794684)
			(xy 10.719656 -88.766331) (xy 10.623756 -88.730133) (xy 10.531084 -88.686326) (xy 10.442244 -88.635194)
			(xy 10.357812 -88.57707) (xy 10.278337 -88.512332) (xy 10.204338 -88.441401) (xy 10.136294 -88.364738)
			(xy 10.074648 -88.282842) (xy 10.019802 -88.196246) (xy 9.972111 -88.105511) (xy 9.931886 -88.011229)
			(xy 9.899388 -87.914013) (xy 9.87483 -87.814494) (xy 9.858369 -87.71332) (xy 9.850114 -87.611148)
			(xy 9.849612 -87.559896) (xy 1.121416 -87.559896) (xy 1.134692 -87.600436) (xy 1.144214 -87.660195)
			(xy 1.144778 -87.690452) (xy 1.14422 -87.72071) (xy 1.134708 -87.780473) (xy 1.115877 -87.837984)
			(xy 1.088201 -87.8918) (xy 1.052374 -87.940571) (xy 1.03124 -87.962232) (xy 1.02433 -87.969605) (xy 1.01648 -87.988206)
			(xy 1.016 -87.9983) (xy 1.016 -92.462604) (xy 1.016488 -92.472694) (xy 1.024347 -92.491287) (xy 1.03124 -92.498672)
			(xy 1.052367 -92.520339) (xy 1.088186 -92.569112) (xy 1.115859 -92.622928) (xy 1.134692 -92.680436)
			(xy 1.144214 -92.740195) (xy 1.144778 -92.770452) (xy 1.14422 -92.80071) (xy 1.134708 -92.860473)
			(xy 1.115877 -92.917984) (xy 1.088201 -92.9718) (xy 1.052374 -93.020571) (xy 1.03124 -93.042232)
			(xy 1.02433 -93.049605) (xy 1.01648 -93.068206) (xy 1.016 -93.0783) (xy 1.016 -93.399864) (xy 3.446023 -93.399864)
			(xy 3.450044 -93.286002) (xy 3.462086 -93.172708) (xy 3.482091 -93.060546) (xy 3.509957 -92.950074)
			(xy 3.545546 -92.841842) (xy 3.588681 -92.736391) (xy 3.639147 -92.634245) (xy 3.696693 -92.535914)
			(xy 3.761032 -92.441886) (xy 3.831843 -92.352631) (xy 3.908773 -92.268594) (xy 3.99144 -92.190192)
			(xy 4.079431 -92.117817) (xy 4.172308 -92.051829) (xy 4.269609 -91.992557) (xy 4.370848 -91.940296)
			(xy 4.475522 -91.895306) (xy 4.583108 -91.857812) (xy 4.693071 -91.828001) (xy 4.804864 -91.80602)
			(xy 4.917928 -91.79198) (xy 5.0317 -91.78595) (xy 5.145615 -91.787961) (xy 5.259104 -91.798002) (xy 5.371603 -91.816024)
			(xy 5.482549 -91.841936) (xy 5.591392 -91.87561) (xy 5.697588 -91.916877) (xy 5.800608 -91.965533)
			(xy 5.89994 -92.021334) (xy 5.995089 -92.084003) (xy 6.085579 -92.153228) (xy 6.170961 -92.228663)
			(xy 6.25081 -92.309934) (xy 6.324727 -92.396634) (xy 6.392343 -92.488332) (xy 6.453324 -92.584571)
			(xy 6.507363 -92.684873) (xy 6.554193 -92.788736) (xy 6.59358 -92.895644) (xy 6.625327 -93.005064)
			(xy 6.649277 -93.11645) (xy 6.665311 -93.229249) (xy 6.673347 -93.342898) (xy 6.67385 -93.399864)
			(xy 6.673347 -93.45683) (xy 6.665311 -93.570479) (xy 6.649277 -93.683278) (xy 6.625327 -93.794664)
			(xy 6.59358 -93.904084) (xy 6.554193 -94.010992) (xy 6.507363 -94.114855) (xy 6.453324 -94.215157)
			(xy 6.392343 -94.311396) (xy 6.324727 -94.403094) (xy 6.25081 -94.489794) (xy 6.170961 -94.571065)
			(xy 6.085579 -94.6465) (xy 5.995089 -94.715725) (xy 5.89994 -94.778394) (xy 5.800608 -94.834195)
			(xy 5.697588 -94.882851) (xy 5.591392 -94.924118) (xy 5.482549 -94.957792) (xy 5.371603 -94.983704)
			(xy 5.259104 -95.001726) (xy 5.145615 -95.011767) (xy 5.0317 -95.013778) (xy 4.917928 -95.007748)
			(xy 4.804864 -94.993708) (xy 4.693071 -94.971727) (xy 4.583108 -94.941916) (xy 4.475522 -94.904422)
			(xy 4.370848 -94.859432) (xy 4.269609 -94.807171) (xy 4.172308 -94.747899) (xy 4.079431 -94.681911)
			(xy 3.99144 -94.609536) (xy 3.908773 -94.531134) (xy 3.831843 -94.447097) (xy 3.761032 -94.357842)
			(xy 3.696693 -94.263814) (xy 3.639147 -94.165483) (xy 3.588681 -94.063337) (xy 3.545546 -93.957886)
			(xy 3.509957 -93.849654) (xy 3.482091 -93.739182) (xy 3.462086 -93.62702) (xy 3.450044 -93.513726)
			(xy 3.446023 -93.399864) (xy 1.016 -93.399864) (xy 1.016 -97.542604) (xy 1.016488 -97.552694) (xy 1.024347 -97.571287)
			(xy 1.03124 -97.578672) (xy 1.052367 -97.600339) (xy 1.088186 -97.649112) (xy 1.115859 -97.702928)
			(xy 1.134692 -97.760436) (xy 1.144214 -97.820195) (xy 1.144778 -97.850452) (xy 1.14422 -97.88071)
			(xy 1.134708 -97.940473) (xy 1.115877 -97.997984) (xy 1.088201 -98.0518) (xy 1.052374 -98.100571)
			(xy 1.03124 -98.122232) (xy 1.02433 -98.129605) (xy 1.01648 -98.148206) (xy 1.016 -98.1583) (xy 1.016 -102.622604)
			(xy 1.016488 -102.632694) (xy 1.024347 -102.651287) (xy 1.03124 -102.658672) (xy 1.052367 -102.680339)
			(xy 1.088186 -102.729112) (xy 1.115859 -102.782928) (xy 1.134692 -102.840436) (xy 1.144214 -102.900195)
			(xy 1.144778 -102.930452) (xy 1.14422 -102.96071) (xy 1.134708 -103.020473) (xy 1.115877 -103.077984)
			(xy 1.088201 -103.1318) (xy 1.052374 -103.180571) (xy 1.03124 -103.202232) (xy 1.02433 -103.209605)
			(xy 1.01648 -103.228206) (xy 1.016 -103.2383) (xy 1.016 -107.702604) (xy 1.016488 -107.712694) (xy 1.024347 -107.731287)
			(xy 1.03124 -107.738672) (xy 1.052367 -107.760339) (xy 1.088186 -107.809112) (xy 1.115859 -107.862928)
			(xy 1.134692 -107.920436) (xy 1.144214 -107.980195) (xy 1.144778 -108.010452) (xy 1.14422 -108.04071)
			(xy 1.134708 -108.100473) (xy 1.115877 -108.157984) (xy 1.088201 -108.2118) (xy 1.052374 -108.260571)
			(xy 1.03124 -108.282232) (xy 1.02433 -108.289605) (xy 1.01648 -108.308206) (xy 1.016 -108.3183) (xy 1.016 -112.782604)
			(xy 1.016488 -112.792694) (xy 1.024347 -112.811287) (xy 1.03124 -112.818672) (xy 1.052367 -112.840339)
			(xy 1.088186 -112.889112) (xy 1.115859 -112.942928) (xy 1.134692 -113.000436) (xy 1.144214 -113.060195)
			(xy 1.144778 -113.090452) (xy 1.144233 -113.119857) (xy 1.135208 -113.177971) (xy 1.117373 -113.234013)
			(xy 1.091152 -113.286655) (xy 1.057166 -113.334651) (xy 1.037082 -113.356136) (xy 1.029812 -113.364294)
			(xy 1.022446 -113.38484) (xy 1.022858 -113.39576) (xy 1.028733 -113.45964) (xy 1.047693 -113.586525)
			(xy 1.074811 -113.711921) (xy 1.109976 -113.835302) (xy 1.153039 -113.956152) (xy 1.203822 -114.073968)
			(xy 1.262111 -114.188256) (xy 1.327664 -114.298539) (xy 1.400205 -114.404356) (xy 1.479432 -114.505264)
			(xy 1.565014 -114.600842) (xy 1.656593 -114.69069) (xy 1.753787 -114.774433) (xy 1.856188 -114.851721)
			(xy 1.96337 -114.92223) (xy 2.074883 -114.985666) (xy 2.190263 -115.041764) (xy 2.309026 -115.09029)
			(xy 2.430676 -115.131039) (xy 2.554706 -115.163844) (xy 2.680596 -115.188565) (xy 2.80782 -115.2051)
			(xy 2.935847 -115.21338) (xy 2.999994 -115.213892) (xy 4.658868 -115.213892) (xy 4.669021 -115.213438)
			(xy 4.687744 -115.205571) (xy 4.69519 -115.198652) (xy 4.71486 -115.179269) (xy 4.758786 -115.145802)
			(xy 4.807078 -115.119018) (xy 4.858727 -115.099476) (xy 4.912654 -115.087585) (xy 4.967732 -115.083594)
			(xy 5.02281 -115.087585) (xy 5.076737 -115.099476) (xy 5.128386 -115.119018) (xy 5.176678 -115.145802)
			(xy 5.220604 -115.179269) (xy 5.240274 -115.198652) (xy 5.247696 -115.205608) (xy 5.266433 -115.213483)
			(xy 5.276596 -115.213892) (xy 9.59993 -115.213892) (xy 9.65371 -115.214361) (xy 9.761 -115.221987)
			(xy 9.814306 -115.229132) (xy 9.823018 -115.229996) (xy 9.840158 -115.226485) (xy 9.847834 -115.222274)
			(xy 9.870283 -115.209203) (xy 9.917966 -115.188588) (xy 9.968004 -115.174632) (xy 10.019472 -115.167592)
			(xy 10.045446 -115.167156) (xy 10.072291 -115.167616) (xy 10.12545 -115.175145) (xy 10.177029 -115.190048)
			(xy 10.226012 -115.212032) (xy 10.271431 -115.240662) (xy 10.31239 -115.275373) (xy 10.348082 -115.315481)
			(xy 10.377802 -115.360195) (xy 10.400964 -115.408631) (xy 10.409428 -115.43411) (xy 10.412375 -115.442322)
			(xy 10.422897 -115.456224) (xy 10.430002 -115.461288) (xy 10.474676 -115.491073) (xy 10.560151 -115.556071)
			(xy 10.640813 -115.626955) (xy 10.716256 -115.703369) (xy 10.786103 -115.784929) (xy 10.850004 -115.871228)
			(xy 10.907638 -115.961832) (xy 10.958716 -116.056287) (xy 11.002983 -116.15412) (xy 11.040216 -116.254839)
			(xy 11.070229 -116.357941) (xy 11.09287 -116.462909) (xy 11.108028 -116.569215) (xy 11.115625 -116.676327)
			(xy 11.116056 -116.730018) (xy 11.116056 -128.230376) (xy 11.115549 -128.284488) (xy 11.107784 -128.392434)
			(xy 11.09234 -128.499551) (xy 11.069298 -128.605294) (xy 11.038775 -128.709125) (xy 11.000925 -128.810515)
			(xy 10.955943 -128.908949) (xy 10.904055 -129.003924) (xy 10.845528 -129.094958) (xy 10.780658 -129.181586)
			(xy 10.709777 -129.263369) (xy 10.633244 -129.339889) (xy 10.55145 -129.410757) (xy 10.464811 -129.475612)
			(xy 10.373767 -129.534124) (xy 10.278783 -129.585995) (xy 10.180343 -129.630962) (xy 10.078946 -129.668795)
			(xy 9.97511 -129.699301) (xy 9.869363 -129.722325) (xy 9.762243 -129.737751) (xy 9.654296 -129.745499)
			(xy 9.600184 -129.745994) (xy 2.999994 -129.745994) (xy 2.965868 -129.746109) (xy 2.897653 -129.748394)
			(xy 2.863596 -129.750566) (xy 2.852512 -129.7519) (xy 2.833 -129.762695) (xy 2.826004 -129.771394)
			(xy 2.807914 -129.795223) (xy 2.765561 -129.837473) (xy 2.717128 -129.87259) (xy 2.663806 -129.899713)
			(xy 2.606903 -129.918175) (xy 2.547814 -129.927524) (xy 2.517902 -129.928112) (xy 2.485712 -129.92744)
			(xy 2.422243 -129.916639) (xy 2.36148 -129.895361) (xy 2.33299 -129.88036) (xy 2.323018 -129.87547)
			(xy 2.300888 -129.873898) (xy 2.290318 -129.877312) (xy 2.231743 -129.900284) (xy 2.117325 -129.952655)
			(xy 2.006457 -130.012171) (xy 1.899583 -130.078594) (xy 1.797133 -130.151656) (xy 1.699519 -130.231064)
			(xy 1.607134 -130.316498) (xy 1.520349 -130.407616) (xy 1.439513 -130.50405) (xy 1.364951 -130.605413)
			(xy 1.296962 -130.711298) (xy 1.23582 -130.821279) (xy 1.181771 -130.934913) (xy 1.135033 -131.051745)
			(xy 1.095792 -131.171303) (xy 1.064207 -131.293108) (xy 1.040404 -131.41667) (xy 1.02448 -131.541491)
			(xy 1.016499 -131.667071) (xy 1.016 -131.729988) (xy 1.016 -132.863082) (xy 1.016518 -132.873354)
			(xy 1.024631 -132.892234) (xy 1.031748 -132.899658) (xy 1.051625 -132.919393) (xy 1.085964 -132.963644)
			(xy 1.113467 -133.012437) (xy 1.133546 -133.064726) (xy 1.145768 -133.119388) (xy 1.149872 -133.175249)
			(xy 1.145768 -133.23111) (xy 1.133547 -133.285771) (xy 1.113469 -133.33806) (xy 1.085965 -133.386854)
			(xy 1.051627 -133.431105) (xy 1.031748 -133.450838) (xy 1.02463 -133.458263) (xy 1.016511 -133.47714)
			(xy 1.016 -133.487414) (xy 1.016 -139.213082) (xy 1.016518 -139.223354) (xy 1.024631 -139.242234)
			(xy 1.031748 -139.249658) (xy 1.051625 -139.269393) (xy 1.085964 -139.313644) (xy 1.113467 -139.362437)
			(xy 1.133546 -139.414726) (xy 1.145768 -139.469388) (xy 1.149872 -139.525249) (xy 1.145768 -139.58111)
			(xy 1.133547 -139.635771) (xy 1.113469 -139.68806) (xy 1.085965 -139.736854) (xy 1.051627 -139.781105)
			(xy 1.031748 -139.800838) (xy 1.02463 -139.808263) (xy 1.016511 -139.82714) (xy 1.016 -139.837414)
			(xy 1.016 -141.99997) (xy 1.016478 -142.088013) (xy 1.024245 -142.263928) (xy 1.039778 -142.439328)
			(xy 1.063047 -142.61387) (xy 1.094007 -142.787213) (xy 1.132596 -142.959019) (xy 1.17874 -143.128952)
			(xy 1.232349 -143.296679) (xy 1.26238 -143.379444) (xy 1.266533 -143.389476) (xy 1.281664 -143.405019)
			(xy 1.29159 -143.409416) (xy 1.318068 -143.420261) (xy 1.367699 -143.448732) (xy 1.412517 -143.484301)
			(xy 1.451516 -143.526168) (xy 1.483821 -143.573393) (xy 1.508705 -143.624915) (xy 1.52561 -143.679578)
			(xy 1.534156 -143.736153) (xy 1.534668 -143.764762) (xy 1.534011 -143.797079) (xy 1.523158 -143.860796)
			(xy 1.513078 -143.891508) (xy 1.509865 -143.90186) (xy 1.511582 -143.923444) (xy 1.51638 -143.933164)
			(xy 1.560488 -144.011605) (xy 1.654834 -144.164874) (xy 1.756006 -144.313727) (xy 1.863798 -144.457858)
			(xy 1.977988 -144.596974) (xy 2.098345 -144.730792) (xy 2.224622 -144.859037) (xy 2.356562 -144.981449)
			(xy 2.493895 -145.097777) (xy 2.636342 -145.207785) (xy 2.783612 -145.311247) (xy 2.935404 -145.407952)
			(xy 3.091408 -145.497704) (xy 3.251307 -145.580319) (xy 3.414774 -145.655629) (xy 3.581474 -145.723479)
			(xy 3.751069 -145.783732) (xy 3.923212 -145.836264) (xy 4.097552 -145.880968) (xy 4.273732 -145.917754)
			(xy 4.451395 -145.946545) (xy 4.630176 -145.967283) (xy 4.809711 -145.979927) (xy 4.89966 -145.98269)
			(xy 4.909963 -145.98247) (xy 4.929095 -145.974865) (xy 4.936744 -145.967958) (xy 4.958357 -145.947175)
			(xy 5.00686 -145.911929) (xy 5.060278 -145.884703) (xy 5.117297 -145.866165) (xy 5.176514 -145.856772)
			(xy 5.206492 -145.856198) (xy 5.236616 -145.856767) (xy 5.296113 -145.86624) (xy 5.353381 -145.884951)
			(xy 5.406993 -145.912436) (xy 5.455617 -145.948009) (xy 5.477256 -145.968974) (xy 5.484656 -145.975814)
			(xy 5.503255 -145.983532) (xy 5.513324 -145.98396)
		)
		(stroke
			(width 0)
			(type solid)
		)
		(fill yes)
		(layer "In4.Cu")
		(net "GND")
	)
	(gr_poly
		(pts
			(xy 178.037236 -90.805) (xy 178.047545 -90.804529) (xy 178.066498 -90.796416) (xy 178.08071 -90.781482)
			(xy 178.084734 -90.77198) (xy 178.095402 -90.744548) (xy 178.098783 -90.735241) (xy 178.098921 -90.715458)
			(xy 178.091551 -90.697099) (xy 178.084988 -90.689684) (xy 178.064901 -90.668201) (xy 178.030912 -90.620208)
			(xy 178.004693 -90.567565) (xy 177.986866 -90.511521) (xy 177.977853 -90.453405) (xy 177.977292 -90.424)
			(xy 177.977778 -90.396749) (xy 177.985534 -90.342801) (xy 178.000889 -90.290506) (xy 178.023531 -90.240929)
			(xy 178.052997 -90.195079) (xy 178.088688 -90.153888) (xy 178.129879 -90.118197) (xy 178.175729 -90.088731)
			(xy 178.225306 -90.066089) (xy 178.277601 -90.050734) (xy 178.331549 -90.042978) (xy 178.3588 -90.042492)
			(xy 178.388612 -90.043064) (xy 178.447513 -90.052325) (xy 178.50426 -90.070623) (xy 178.557477 -90.097513)
			(xy 178.60587 -90.132342) (xy 178.648267 -90.174266) (xy 178.666394 -90.19794) (xy 178.672586 -90.205601)
			(xy 178.689347 -90.215914) (xy 178.708756 -90.219172) (xy 178.718464 -90.217498) (xy 178.767566 -90.20691)
			(xy 178.867375 -90.195576) (xy 178.9176 -90.194892) (xy 178.963424 -90.195448) (xy 179.054588 -90.204847)
			(xy 179.144301 -90.223576) (xy 179.23161 -90.251437) (xy 179.31559 -90.288133) (xy 179.35575 -90.310208)
			(xy 179.366534 -90.315528) (xy 179.390523 -90.316607) (xy 179.401724 -90.31224) (xy 179.445042 -90.293305)
			(xy 179.534813 -90.263651) (xy 179.627223 -90.243686) (xy 179.721229 -90.233637) (xy 179.7685 -90.232992)
			(xy 179.811807 -90.23351) (xy 179.898011 -90.241928) (xy 179.982988 -90.258686) (xy 180.065934 -90.283624)
			(xy 180.146063 -90.316507) (xy 180.222617 -90.357022) (xy 180.29487 -90.404786) (xy 180.362139 -90.459347)
			(xy 180.423785 -90.520188) (xy 180.479227 -90.586733) (xy 180.527937 -90.658351) (xy 180.569456 -90.734365)
			(xy 180.586888 -90.774012) (xy 180.591207 -90.782965) (xy 180.605331 -90.796926) (xy 180.623695 -90.804486)
			(xy 180.633624 -90.805) (xy 200.262998 -90.805) (xy 200.290938 -90.781886) (xy 200.294494 -90.763852)
			(xy 200.30298 -90.72235) (xy 200.32683 -90.641061) (xy 200.358301 -90.562407) (xy 200.397106 -90.487102)
			(xy 200.442895 -90.415827) (xy 200.495253 -90.349228) (xy 200.553705 -90.287908) (xy 200.617723 -90.232424)
			(xy 200.686725 -90.183277) (xy 200.760087 -90.140913) (xy 200.837145 -90.105715) (xy 200.9172 -90.078003)
			(xy 200.999527 -90.058027) (xy 201.08338 -90.045969) (xy 201.168 -90.041937) (xy 201.25262 -90.045969)
			(xy 201.336473 -90.058027) (xy 201.4188 -90.078003) (xy 201.498855 -90.105715) (xy 201.575913 -90.140913)
			(xy 201.649275 -90.183277) (xy 201.718277 -90.232424) (xy 201.782295 -90.287908) (xy 201.840747 -90.349228)
			(xy 201.893105 -90.415827) (xy 201.938894 -90.487102) (xy 201.977699 -90.562407) (xy 202.00917 -90.641061)
			(xy 202.03302 -90.72235) (xy 202.041506 -90.763852) (xy 202.045062 -90.781886) (xy 202.073002 -90.805)
			(xy 215.4047 -90.805) (xy 215.413956 -90.804642) (xy 215.431275 -90.798121) (xy 215.438482 -90.7923)
			(xy 215.466179 -90.768348) (xy 215.524875 -90.724559) (xy 215.586971 -90.68574) (xy 215.61933 -90.668602)
			(xy 215.626868 -90.66437) (xy 215.63875 -90.651831) (xy 215.645753 -90.636039) (xy 215.646762 -90.627454)
			(xy 215.649465 -90.600536) (xy 215.661501 -90.547793) (xy 215.680868 -90.497279) (xy 215.707175 -90.450007)
			(xy 215.739896 -90.406925) (xy 215.778374 -90.368897) (xy 215.821839 -90.336686) (xy 215.869417 -90.310937)
			(xy 215.920156 -90.292167) (xy 215.973037 -90.280753) (xy 216.027 -90.276922) (xy 216.080963 -90.280753)
			(xy 216.133844 -90.292167) (xy 216.184583 -90.310937) (xy 216.232161 -90.336686) (xy 216.275626 -90.368897)
			(xy 216.314104 -90.406925) (xy 216.346825 -90.450007) (xy 216.373132 -90.497279) (xy 216.392499 -90.547793)
			(xy 216.404535 -90.600536) (xy 216.407238 -90.627454) (xy 216.408276 -90.636031) (xy 216.415297 -90.651803)
			(xy 216.427143 -90.664363) (xy 216.43467 -90.668602) (xy 216.46704 -90.685721) (xy 216.529138 -90.724538)
			(xy 216.587828 -90.768338) (xy 216.615518 -90.7923) (xy 216.622731 -90.798102) (xy 216.64005 -90.804602)
			(xy 216.6493 -90.805) (xy 218.710002 -90.805) (xy 218.736164 -90.786204) (xy 218.741498 -90.77071)
			(xy 218.755738 -90.730679) (xy 218.790821 -90.653289) (xy 218.833123 -90.579597) (xy 218.882259 -90.510274)
			(xy 218.937781 -90.445951) (xy 218.999182 -90.387216) (xy 219.065904 -90.334602) (xy 219.137339 -90.28859)
			(xy 219.212835 -90.249599) (xy 219.291705 -90.217983) (xy 219.37323 -90.194032) (xy 219.414852 -90.185494)
			(xy 219.432886 -90.181938) (xy 219.456 -90.153998) (xy 219.456 -80.425798) (xy 219.437204 -80.399636)
			(xy 219.42171 -80.394302) (xy 219.381705 -80.380075) (xy 219.304362 -80.345025) (xy 219.230712 -80.302763)
			(xy 219.161424 -80.253676) (xy 219.09713 -80.198209) (xy 219.038414 -80.136867) (xy 218.985811 -80.070209)
			(xy 218.939799 -79.998841) (xy 218.900798 -79.923414) (xy 218.869163 -79.844613) (xy 218.845181 -79.763156)
			(xy 218.82907 -79.679784) (xy 218.820978 -79.595257) (xy 218.820978 -79.510343) (xy 218.82907 -79.425816)
			(xy 218.845181 -79.342444) (xy 218.869163 -79.260987) (xy 218.900798 -79.182186) (xy 218.939799 -79.106759)
			(xy 218.985811 -79.035391) (xy 219.038414 -78.968733) (xy 219.09713 -78.907391) (xy 219.161424 -78.851924)
			(xy 219.230712 -78.802837) (xy 219.304362 -78.760575) (xy 219.381705 -78.725525) (xy 219.42171 -78.711298)
			(xy 219.437204 -78.705964) (xy 219.456 -78.679802) (xy 219.456 -74.452988) (xy 219.455824 -74.446258)
			(xy 219.45234 -74.433259) (xy 219.449142 -74.427334) (xy 219.42815 -74.390244) (xy 219.392542 -74.312807)
			(xy 219.364502 -74.23232) (xy 219.344286 -74.149521) (xy 219.332081 -74.065168) (xy 219.327998 -73.980035)
			(xy 219.332075 -73.894901) (xy 219.344273 -73.810547) (xy 219.364482 -73.727746) (xy 219.392516 -73.647257)
			(xy 219.428118 -73.569818) (xy 219.449142 -73.532746) (xy 219.452309 -73.52681) (xy 219.455781 -73.513817)
			(xy 219.456 -73.507092) (xy 219.456 -72.730614) (xy 219.456521 -72.697354) (xy 219.465206 -72.631403)
			(xy 219.48243 -72.56715) (xy 219.507898 -72.505698) (xy 219.541173 -72.448098) (xy 219.581686 -72.395337)
			(xy 219.604844 -72.371458) (xy 228.896418 -63.079884) (xy 228.902987 -63.072634) (xy 228.910576 -63.054621)
			(xy 228.910905 -63.035077) (xy 228.907848 -63.025782) (xy 228.86924 -62.924944) (xy 228.844602 -62.907418)
			(xy 228.829616 -62.906656) (xy 228.729688 -62.901177) (xy 228.530341 -62.883215) (xy 228.331872 -62.857291)
			(xy 228.1346 -62.823445) (xy 227.93884 -62.781733) (xy 227.744906 -62.73222) (xy 227.553109 -62.674987)
			(xy 227.363755 -62.610124) (xy 227.177149 -62.537736) (xy 226.993589 -62.457939) (xy 226.813369 -62.370861)
			(xy 226.636778 -62.276641) (xy 226.464099 -62.175429) (xy 226.295608 -62.067389) (xy 226.131575 -61.952693)
			(xy 225.972263 -61.831525) (xy 225.817928 -61.704079) (xy 225.668816 -61.57056) (xy 225.525167 -61.43118)
			(xy 225.38721 -61.286164) (xy 225.255166 -61.135743) (xy 225.129247 -60.980159) (xy 225.009656 -60.819661)
			(xy 224.896582 -60.654506) (xy 224.790208 -60.484958) (xy 224.690703 -60.31129) (xy 224.598228 -60.133779)
			(xy 224.51293 -59.952709) (xy 224.434946 -59.768371) (xy 224.364401 -59.581061) (xy 224.301408 -59.391077)
			(xy 224.246068 -59.198725) (xy 224.198469 -59.004313) (xy 224.158688 -58.808151) (xy 224.126789 -58.610555)
			(xy 224.102822 -58.41184) (xy 224.086825 -58.212326) (xy 224.078826 -58.012331) (xy 224.078292 -57.912254)
			(xy 224.0788 -57.811552) (xy 224.086911 -57.610312) (xy 224.103119 -57.409562) (xy 224.127396 -57.209627)
			(xy 224.159704 -57.010832) (xy 224.19999 -56.813499) (xy 224.248189 -56.617948) (xy 224.304223 -56.424496)
			(xy 224.368 -56.233457) (xy 224.439418 -56.045141) (xy 224.51836 -55.859854) (xy 224.604698 -55.677895)
			(xy 224.698294 -55.49956) (xy 224.798993 -55.325138) (xy 224.906634 -55.154913) (xy 225.021042 -54.989159)
			(xy 225.142031 -54.828147) (xy 225.269405 -54.672136) (xy 225.402957 -54.521381) (xy 225.542471 -54.376125)
			(xy 225.687721 -54.236605) (xy 225.83847 -54.103046) (xy 225.994475 -53.975666) (xy 226.155482 -53.85467)
			(xy 226.321231 -53.740255) (xy 226.491452 -53.632606) (xy 226.665869 -53.531899) (xy 226.8442 -53.438296)
			(xy 227.026155 -53.351949) (xy 227.211439 -53.272999) (xy 227.399752 -53.201573) (xy 227.590788 -53.137787)
			(xy 227.784237 -53.081745) (xy 227.979786 -53.033538) (xy 228.177117 -52.993243) (xy 228.375911 -52.960927)
			(xy 228.575845 -52.936641) (xy 228.776595 -52.920424) (xy 228.977834 -52.912304) (xy 229.078536 -52.911756)
			(xy 251.079254 -52.911756) (xy 251.177082 -52.91223) (xy 251.372587 -52.919882) (xy 251.567644 -52.935176)
			(xy 251.761953 -52.958089) (xy 251.955217 -52.988585) (xy 252.14714 -53.026618) (xy 252.337429 -53.07213)
			(xy 252.525791 -53.125051) (xy 252.711939 -53.1853) (xy 252.895588 -53.252784) (xy 253.076456 -53.327401)
			(xy 253.254267 -53.409037) (xy 253.428748 -53.497565) (xy 253.599633 -53.592851) (xy 253.766659 -53.694749)
			(xy 253.929572 -53.803103) (xy 254.088121 -53.917747) (xy 254.242064 -54.038505) (xy 254.391165 -54.165193)
			(xy 254.535196 -54.297617) (xy 254.673937 -54.435574) (xy 254.740918 -54.506876) (xy 254.74803 -54.514496)
			(xy 254.766826 -54.522878) (xy 254.850392 -54.524402) (xy 254.860651 -54.524082) (xy 254.879641 -54.516338)
			(xy 254.887222 -54.509416) (xy 258.116324 -51.280314) (xy 258.122624 -51.273474) (xy 258.130275 -51.256542)
			(xy 258.131404 -51.237996) (xy 258.129024 -51.229006) (xy 258.101846 -51.143154) (xy 258.098718 -51.134499)
			(xy 258.087389 -51.120012) (xy 258.071696 -51.110424) (xy 258.06273 -51.108356) (xy 258.062476 -51.108356)
			(xy 258.021904 -51.100582) (xy 257.9423 -51.078482) (xy 257.865088 -51.049094) (xy 257.790935 -51.012673)
			(xy 257.720478 -50.969532) (xy 257.654327 -50.920043) (xy 257.593049 -50.864632) (xy 257.537175 -50.803778)
			(xy 257.487184 -50.738004) (xy 257.443509 -50.667878) (xy 257.406525 -50.594003) (xy 257.376552 -50.517017)
			(xy 257.353847 -50.437583) (xy 257.338607 -50.356386) (xy 257.330962 -50.274126) (xy 257.330448 -50.232818)
			(xy 257.330448 -50.231802) (xy 257.33109 -50.185433) (xy 257.340818 -50.093205) (xy 257.360074 -50.002487)
			(xy 257.388651 -49.914261) (xy 257.406902 -49.87163) (xy 257.410698 -49.861688) (xy 257.410681 -49.840432)
			(xy 257.406902 -49.830482) (xy 257.388745 -49.787929) (xy 257.360329 -49.699877) (xy 257.3412 -49.609353)
			(xy 257.331564 -49.517333) (xy 257.330956 -49.471072) (xy 257.330956 -49.470818) (xy 257.331446 -49.429355)
			(xy 257.339189 -49.346791) (xy 257.354582 -49.265306) (xy 257.377492 -49.185607) (xy 257.407719 -49.108385)
			(xy 257.445001 -49.034312) (xy 257.489014 -48.96403) (xy 257.513836 -48.930814) (xy 257.520093 -48.921637)
			(xy 257.524835 -48.899962) (xy 257.520061 -48.878294) (xy 257.513836 -48.869092) (xy 257.488938 -48.835805)
			(xy 257.444755 -48.765386) (xy 257.407339 -48.69115) (xy 257.377015 -48.613746) (xy 257.354049 -48.533849)
			(xy 257.338641 -48.452157) (xy 257.330926 -48.369384) (xy 257.330448 -48.327818) (xy 257.331032 -48.281422)
			(xy 257.340664 -48.189131) (xy 257.359857 -48.098346) (xy 257.388401 -48.010053) (xy 257.406648 -47.967392)
			(xy 257.410459 -47.95745) (xy 257.410466 -47.936183) (xy 257.406648 -47.926244) (xy 257.388433 -47.883639)
			(xy 257.359921 -47.79547) (xy 257.340724 -47.704816) (xy 257.331051 -47.612658) (xy 257.330448 -47.566326)
			(xy 257.330448 -47.565818) (xy 257.330952 -47.52347) (xy 257.339003 -47.439156) (xy 257.355032 -47.35599)
			(xy 257.378893 -47.274723) (xy 257.410372 -47.196093) (xy 257.449183 -47.120812) (xy 257.494973 -47.04956)
			(xy 257.547329 -46.982984) (xy 257.605777 -46.921686) (xy 257.669787 -46.866221) (xy 257.738779 -46.817092)
			(xy 257.812129 -46.774743) (xy 257.889172 -46.739559) (xy 257.969211 -46.711857) (xy 258.05152 -46.691889)
			(xy 258.135355 -46.679836) (xy 258.219956 -46.675806) (xy 258.304557 -46.679836) (xy 258.388392 -46.691889)
			(xy 258.470701 -46.711857) (xy 258.55074 -46.739559) (xy 258.627783 -46.774743) (xy 258.701133 -46.817092)
			(xy 258.770125 -46.866221) (xy 258.834135 -46.921686) (xy 258.892583 -46.982984) (xy 258.944939 -47.04956)
			(xy 258.990729 -47.120812) (xy 259.02954 -47.196093) (xy 259.061019 -47.274723) (xy 259.08488 -47.35599)
			(xy 259.100909 -47.439156) (xy 259.10896 -47.52347) (xy 259.109464 -47.565818) (xy 259.109464 -47.566326)
			(xy 259.108855 -47.612658) (xy 259.099194 -47.704818) (xy 259.080001 -47.795473) (xy 259.051484 -47.88364)
			(xy 259.033264 -47.926244) (xy 259.029459 -47.936186) (xy 259.029466 -47.957447) (xy 259.033264 -47.967392)
			(xy 259.051502 -48.010057) (xy 259.08004 -48.09835) (xy 259.099235 -48.189134) (xy 259.108879 -48.281422)
			(xy 259.109464 -48.327818) (xy 259.108991 -48.369383) (xy 259.101256 -48.452153) (xy 259.085836 -48.53384)
			(xy 259.062865 -48.613734) (xy 259.032543 -48.691137) (xy 258.995136 -48.765375) (xy 258.950968 -48.835801)
			(xy 258.926076 -48.869092) (xy 258.91973 -48.878247) (xy 258.914881 -48.899962) (xy 258.919698 -48.921685)
			(xy 258.926076 -48.930814) (xy 258.950888 -48.964038) (xy 258.994917 -49.034312) (xy 259.03221 -49.10838)
			(xy 259.062443 -49.185601) (xy 259.085352 -49.265301) (xy 259.10074 -49.346788) (xy 259.10847 -49.429354)
			(xy 259.108956 -49.470818) (xy 259.108956 -49.471072) (xy 259.108366 -49.517335) (xy 259.098757 -49.609361)
			(xy 259.079629 -49.699889) (xy 259.051189 -49.787936) (xy 259.03301 -49.830482) (xy 259.029195 -49.840425)
			(xy 259.029179 -49.861696) (xy 259.03301 -49.87163) (xy 259.051325 -49.914373) (xy 259.079978 -50.002845)
			(xy 259.09923 -50.093825) (xy 259.108872 -50.18632) (xy 259.109464 -50.232818) (xy 259.109027 -50.272979)
			(xy 259.101804 -50.352974) (xy 259.0874 -50.431993) (xy 259.065932 -50.509392) (xy 259.037575 -50.584542)
			(xy 259.002561 -50.656829) (xy 258.961173 -50.725666) (xy 258.913749 -50.790492) (xy 258.860675 -50.85078)
			(xy 258.831842 -50.87874) (xy 258.820412 -50.889408) (xy 258.813554 -50.919888) (xy 258.854448 -51.021996)
			(xy 258.858605 -51.031265) (xy 258.87282 -51.045754) (xy 258.891542 -51.053594) (xy 258.901692 -51.054)
			(xy 270.405606 -51.054) (xy 270.415676 -51.053576) (xy 270.434279 -51.04586) (xy 270.441674 -51.039014)
			(xy 271.257014 -50.223674) (xy 271.263866 -50.216278) (xy 271.271604 -50.197679) (xy 271.272 -50.187606)
			(xy 271.272 -49.559464) (xy 271.270984 -49.549812) (xy 271.268876 -49.540937) (xy 271.259337 -49.525405)
			(xy 271.244941 -49.514226) (xy 271.22753 -49.50883) (xy 271.218406 -49.508918) (xy 271.210278 -49.509934)
			(xy 271.162821 -49.519792) (xy 271.066466 -49.53036) (xy 271.018 -49.531016) (xy 270.975627 -49.530512)
			(xy 270.891266 -49.522456) (xy 270.808052 -49.506418) (xy 270.726739 -49.482543) (xy 270.648064 -49.451046)
			(xy 270.57274 -49.412213) (xy 270.501447 -49.366397) (xy 270.434833 -49.31401) (xy 270.3735 -49.25553)
			(xy 270.318004 -49.191483) (xy 270.268846 -49.122452) (xy 270.226474 -49.04906) (xy 270.191269 -48.971973)
			(xy 270.163552 -48.891889) (xy 270.143572 -48.809532) (xy 270.131512 -48.725649) (xy 270.12748 -48.641)
			(xy 270.131512 -48.556351) (xy 270.143572 -48.472468) (xy 270.163552 -48.390111) (xy 270.191269 -48.310027)
			(xy 270.226474 -48.23294) (xy 270.268846 -48.159548) (xy 270.318004 -48.090517) (xy 270.3735 -48.02647)
			(xy 270.434833 -47.96799) (xy 270.501447 -47.915603) (xy 270.57274 -47.869787) (xy 270.648064 -47.830954)
			(xy 270.726739 -47.799457) (xy 270.808052 -47.775582) (xy 270.891266 -47.759544) (xy 270.975627 -47.751488)
			(xy 271.018 -47.750984) (xy 271.066466 -47.75164) (xy 271.162822 -47.762203) (xy 271.210278 -47.772066)
			(xy 271.218406 -47.773082) (xy 271.227516 -47.773189) (xy 271.244885 -47.767732) (xy 271.259246 -47.756541)
			(xy 271.268782 -47.741033) (xy 271.270984 -47.732188) (xy 271.272 -47.722536) (xy 271.272 -45.940218)
			(xy 271.271644 -45.931767) (xy 271.266061 -45.915811) (xy 271.261078 -45.908976) (xy 271.235449 -45.875429)
			(xy 271.18994 -45.804318) (xy 271.151372 -45.729214) (xy 271.120094 -45.650795) (xy 271.096386 -45.569765)
			(xy 271.080461 -45.486853) (xy 271.072463 -45.402806) (xy 271.072464 -45.318379) (xy 271.080464 -45.234331)
			(xy 271.09639 -45.15142) (xy 271.120099 -45.07039) (xy 271.151379 -44.991971) (xy 271.189947 -44.916869)
			(xy 271.235458 -44.845758) (xy 271.261078 -44.812204) (xy 271.26607 -44.805375) (xy 271.27164 -44.789414)
			(xy 271.272 -44.780962) (xy 271.272 -43.18) (xy 271.272521 -43.14674) (xy 271.281209 -43.08079) (xy 271.298434 -43.016539)
			(xy 271.323903 -42.955088) (xy 271.357179 -42.897489) (xy 271.397692 -42.844729) (xy 271.420844 -42.820844)
			(xy 273.706844 -40.534844) (xy 273.730724 -40.511688) (xy 273.783488 -40.471182) (xy 273.841089 -40.437911)
			(xy 273.90254 -40.412447) (xy 273.966791 -40.395225) (xy 274.032741 -40.386539) (xy 274.066 -40.386)
			(xy 274.524216 -40.386) (xy 274.552664 -40.360854) (xy 274.555204 -40.34155) (xy 274.561042 -40.299054)
			(xy 274.579842 -40.215355) (xy 274.606612 -40.133855) (xy 274.641104 -40.055311) (xy 274.682997 -39.980452)
			(xy 274.731902 -39.909973) (xy 274.787365 -39.84453) (xy 274.84887 -39.78473) (xy 274.915846 -39.731129)
			(xy 274.987672 -39.684225) (xy 275.063679 -39.644453) (xy 275.143162 -39.612182) (xy 275.225382 -39.587714)
			(xy 275.309576 -39.571274) (xy 275.394962 -39.563015) (xy 275.480746 -39.563015) (xy 275.566132 -39.571274)
			(xy 275.650326 -39.587714) (xy 275.732546 -39.612182) (xy 275.812029 -39.644453) (xy 275.888036 -39.684225)
			(xy 275.959862 -39.731129) (xy 276.026838 -39.78473) (xy 276.088343 -39.84453) (xy 276.143806 -39.909973)
			(xy 276.192711 -39.980452) (xy 276.234604 -40.055311) (xy 276.269096 -40.133855) (xy 276.295866 -40.215355)
			(xy 276.314666 -40.299054) (xy 276.320504 -40.34155) (xy 276.323044 -40.360854) (xy 276.351492 -40.386)
			(xy 276.462998 -40.386) (xy 276.490938 -40.362886) (xy 276.494494 -40.344852) (xy 276.50298 -40.30335)
			(xy 276.52683 -40.222061) (xy 276.558301 -40.143407) (xy 276.597106 -40.068102) (xy 276.642895 -39.996827)
			(xy 276.695253 -39.930228) (xy 276.753705 -39.868908) (xy 276.817723 -39.813424) (xy 276.886725 -39.764277)
			(xy 276.960087 -39.721913) (xy 277.037145 -39.686715) (xy 277.1172 -39.659003) (xy 277.199527 -39.639027)
			(xy 277.28338 -39.626969) (xy 277.368 -39.622937) (xy 277.45262 -39.626969) (xy 277.536473 -39.639027)
			(xy 277.6188 -39.659003) (xy 277.698855 -39.686715) (xy 277.775913 -39.721913) (xy 277.849275 -39.764277)
			(xy 277.918277 -39.813424) (xy 277.982295 -39.868908) (xy 278.040747 -39.930228) (xy 278.093105 -39.996827)
			(xy 278.138894 -40.068102) (xy 278.177699 -40.143407) (xy 278.20917 -40.222061) (xy 278.23302 -40.30335)
			(xy 278.241506 -40.344852) (xy 278.245062 -40.362886) (xy 278.273002 -40.386) (xy 282.089606 -40.386)
			(xy 282.099676 -40.385576) (xy 282.118279 -40.37786) (xy 282.125674 -40.371014) (xy 283.322014 -39.174674)
			(xy 283.328866 -39.167278) (xy 283.336604 -39.148679) (xy 283.337 -39.138606) (xy 283.337 -34.876994)
			(xy 283.336576 -34.866924) (xy 283.32886 -34.848321) (xy 283.322014 -34.840926) (xy 282.405074 -33.923986)
			(xy 282.397678 -33.917134) (xy 282.379079 -33.909396) (xy 282.369006 -33.909) (xy 275.714714 -33.909)
			(xy 275.706586 -33.911794) (xy 275.660106 -33.927009) (xy 275.564662 -33.948364) (xy 275.467452 -33.959126)
			(xy 275.41855 -33.9598) (xy 275.369648 -33.959119) (xy 275.272438 -33.948362) (xy 275.176995 -33.927006)
			(xy 275.130514 -33.911794) (xy 275.122386 -33.909) (xy 270.4084 -33.909) (xy 270.37514 -33.908479)
			(xy 270.30919 -33.899791) (xy 270.244939 -33.882566) (xy 270.183488 -33.857097) (xy 270.125889 -33.823821)
			(xy 270.073129 -33.783308) (xy 270.049244 -33.760156) (xy 268.816074 -32.526986) (xy 268.808678 -32.520134)
			(xy 268.790079 -32.512396) (xy 268.780006 -32.512) (xy 247.144794 -32.512) (xy 247.134724 -32.512424)
			(xy 247.116121 -32.52014) (xy 247.108726 -32.526986) (xy 241.68608 -37.949632) (xy 244.794541 -37.949632)
			(xy 244.798537 -37.767766) (xy 244.810517 -37.586251) (xy 244.830459 -37.405438) (xy 244.858324 -37.225675)
			(xy 244.894058 -37.04731) (xy 244.937591 -36.870686) (xy 244.988841 -36.696145) (xy 245.047708 -36.524023)
			(xy 245.114079 -36.354653) (xy 245.187825 -36.188362) (xy 245.268804 -36.025471) (xy 245.356859 -35.866294)
			(xy 245.451822 -35.711138) (xy 245.553507 -35.560303) (xy 245.66172 -35.414081) (xy 245.776252 -35.272752)
			(xy 245.89688 -35.136591) (xy 246.023373 -35.005859) (xy 246.155486 -34.88081) (xy 246.292964 -34.761684)
			(xy 246.435542 -34.648712) (xy 246.582945 -34.542112) (xy 246.734888 -34.442089) (xy 246.891077 -34.348837)
			(xy 247.051212 -34.262535) (xy 247.214983 -34.18335) (xy 247.382074 -34.111435) (xy 247.552162 -34.046929)
			(xy 247.72492 -33.989957) (xy 247.900014 -33.940627) (xy 248.077105 -33.899036) (xy 248.255852 -33.865263)
			(xy 248.43591 -33.839375) (xy 248.616932 -33.82142) (xy 248.798567 -33.811434) (xy 248.980466 -33.809436)
			(xy 249.162277 -33.81543) (xy 249.343649 -33.829403) (xy 249.524233 -33.85133) (xy 249.703679 -33.881168)
			(xy 249.881641 -33.918859) (xy 250.057776 -33.96433) (xy 250.231744 -34.017494) (xy 250.403208 -34.078248)
			(xy 250.571839 -34.146475) (xy 250.73731 -34.222043) (xy 250.899302 -34.304806) (xy 251.057502 -34.394605)
			(xy 251.211605 -34.491266) (xy 251.361314 -34.594603) (xy 251.506339 -34.704415) (xy 251.646401 -34.820492)
			(xy 251.781229 -34.942609) (xy 251.910563 -35.07053) (xy 252.034154 -35.204009) (xy 252.151762 -35.342787)
			(xy 252.263161 -35.486598) (xy 252.368136 -35.635162) (xy 252.466484 -35.788194) (xy 252.558015 -35.945399)
			(xy 252.642553 -36.106472) (xy 252.719934 -36.271103) (xy 252.790009 -36.438974) (xy 252.852643 -36.609761)
			(xy 252.907714 -36.783134) (xy 252.955118 -36.958759) (xy 252.994761 -37.136296) (xy 253.020061 -37.278761)
			(xy 259.293102 -37.278761) (xy 259.293102 -37.194039) (xy 259.301155 -37.109702) (xy 259.317189 -37.026512)
			(xy 259.341057 -36.945222) (xy 259.372545 -36.86657) (xy 259.411367 -36.791267) (xy 259.45717 -36.719995)
			(xy 259.509541 -36.653399) (xy 259.568006 -36.592084) (xy 259.632034 -36.536603) (xy 259.701046 -36.48746)
			(xy 259.774416 -36.4451) (xy 259.851481 -36.409905) (xy 259.931543 -36.382196) (xy 260.013876 -36.362222)
			(xy 260.097735 -36.350165) (xy 260.18236 -36.346134) (xy 260.266985 -36.350165) (xy 260.350844 -36.362222)
			(xy 260.433177 -36.382196) (xy 260.513239 -36.409905) (xy 260.590304 -36.4451) (xy 260.663674 -36.48746)
			(xy 260.732686 -36.536603) (xy 260.796714 -36.592084) (xy 260.855179 -36.653399) (xy 260.90755 -36.719995)
			(xy 260.953353 -36.791267) (xy 260.992175 -36.86657) (xy 261.023663 -36.945222) (xy 261.047531 -37.026512)
			(xy 261.063565 -37.109702) (xy 261.071618 -37.194039) (xy 261.072122 -37.2364) (xy 261.071618 -37.278761)
			(xy 261.063565 -37.363098) (xy 261.047531 -37.446288) (xy 261.023663 -37.527578) (xy 260.992175 -37.60623)
			(xy 260.953353 -37.681533) (xy 260.90755 -37.752805) (xy 260.855179 -37.819401) (xy 260.796714 -37.880716)
			(xy 260.732686 -37.936197) (xy 260.663674 -37.98534) (xy 260.590304 -38.0277) (xy 260.513239 -38.062895)
			(xy 260.433177 -38.090604) (xy 260.350844 -38.110578) (xy 260.266985 -38.122635) (xy 260.18236 -38.126667)
			(xy 260.097735 -38.122635) (xy 260.013876 -38.110578) (xy 259.931543 -38.090604) (xy 259.851481 -38.062895)
			(xy 259.774416 -38.0277) (xy 259.701046 -37.98534) (xy 259.632034 -37.936197) (xy 259.568006 -37.880716)
			(xy 259.509541 -37.819401) (xy 259.45717 -37.752805) (xy 259.411367 -37.681533) (xy 259.372545 -37.60623)
			(xy 259.341057 -37.527578) (xy 259.317189 -37.446288) (xy 259.301155 -37.363098) (xy 259.293102 -37.278761)
			(xy 253.020061 -37.278761) (xy 253.026568 -37.315403) (xy 253.050477 -37.495735) (xy 253.066442 -37.676943)
			(xy 253.074432 -37.858677) (xy 253.074932 -37.949632) (xy 253.074432 -38.040587) (xy 253.066442 -38.222321)
			(xy 253.050477 -38.403529) (xy 253.026568 -38.583861) (xy 252.994761 -38.762968) (xy 252.955118 -38.940505)
			(xy 252.907714 -39.11613) (xy 252.885164 -39.18712) (xy 257.640836 -39.18712) (xy 257.64147 -39.140233)
			(xy 257.65136 -39.046981) (xy 257.671 -38.955286) (xy 257.700173 -38.866165) (xy 257.718814 -38.823138)
			(xy 257.722486 -38.813745) (xy 257.722992 -38.793601) (xy 257.71983 -38.784022) (xy 257.705286 -38.745426)
			(xy 257.682591 -38.666124) (xy 257.667328 -38.585063) (xy 257.659626 -38.502938) (xy 257.659124 -38.461696)
			(xy 257.659628 -38.419335) (xy 257.667681 -38.334998) (xy 257.683715 -38.251808) (xy 257.707583 -38.170518)
			(xy 257.739071 -38.091866) (xy 257.777893 -38.016563) (xy 257.823696 -37.945291) (xy 257.876067 -37.878695)
			(xy 257.934532 -37.81738) (xy 257.99856 -37.761899) (xy 258.067572 -37.712756) (xy 258.140942 -37.670396)
			(xy 258.218007 -37.635201) (xy 258.298069 -37.607492) (xy 258.380402 -37.587518) (xy 258.464261 -37.575461)
			(xy 258.548886 -37.57143) (xy 258.633511 -37.575461) (xy 258.71737 -37.587518) (xy 258.799703 -37.607492)
			(xy 258.879765 -37.635201) (xy 258.95683 -37.670396) (xy 259.0302 -37.712756) (xy 259.099212 -37.761899)
			(xy 259.16324 -37.81738) (xy 259.221705 -37.878695) (xy 259.274076 -37.945291) (xy 259.319879 -38.016563)
			(xy 259.358701 -38.091866) (xy 259.390189 -38.170518) (xy 259.414057 -38.251808) (xy 259.430091 -38.334998)
			(xy 259.438144 -38.419335) (xy 259.438648 -38.461696) (xy 259.438331 -38.49433) (xy 259.433502 -38.559421)
			(xy 259.428996 -38.591744) (xy 259.428996 -38.591998) (xy 259.427875 -38.603483) (xy 259.434899 -38.625441)
			(xy 259.442458 -38.634162) (xy 259.506212 -38.700964) (xy 259.528056 -38.709092) (xy 259.53974 -38.707822)
			(xy 259.562407 -38.705593) (xy 259.607896 -38.703178) (xy 259.630672 -38.702996) (xy 259.671767 -38.703493)
			(xy 259.753606 -38.711073) (xy 259.834397 -38.72617) (xy 259.91345 -38.748656) (xy 259.990092 -38.77834)
			(xy 260.063669 -38.814967) (xy 260.133553 -38.858226) (xy 260.199148 -38.907747) (xy 260.259895 -38.963108)
			(xy 260.315275 -39.023838) (xy 260.364817 -39.089418) (xy 260.408098 -39.159288) (xy 260.444748 -39.232853)
			(xy 260.474455 -39.309486) (xy 260.496966 -39.388533) (xy 260.512089 -39.469319) (xy 260.519694 -39.551155)
			(xy 260.52018 -39.59225) (xy 260.52018 -39.592758) (xy 260.519659 -39.635175) (xy 260.511589 -39.719623)
			(xy 260.495517 -39.80292) (xy 260.47159 -39.884309) (xy 260.440025 -39.963051) (xy 260.401108 -40.038431)
			(xy 260.355193 -40.109764) (xy 260.302698 -40.176404) (xy 260.244097 -40.237744) (xy 260.212332 -40.265858)
			(xy 260.204413 -40.273406) (xy 260.195328 -40.293284) (xy 260.194806 -40.304212) (xy 260.194806 -40.381428)
			(xy 260.19531 -40.392357) (xy 260.204412 -40.412232) (xy 260.212332 -40.419782) (xy 260.24409 -40.447905)
			(xy 260.302694 -40.509243) (xy 260.355193 -40.575881) (xy 260.401112 -40.647213) (xy 260.440033 -40.722591)
			(xy 260.471603 -40.801332) (xy 260.495535 -40.88272) (xy 260.511612 -40.966017) (xy 260.519688 -41.050465)
			(xy 260.52018 -41.092882) (xy 260.519705 -41.135309) (xy 260.511626 -41.219777) (xy 260.49554 -41.303091)
			(xy 260.471593 -41.384495) (xy 260.440002 -41.463249) (xy 260.401055 -41.538636) (xy 260.355107 -41.609972)
			(xy 260.302573 -41.676608) (xy 260.243933 -41.737938) (xy 260.179718 -41.793405) (xy 260.110513 -41.842505)
			(xy 260.036947 -41.884791) (xy 259.959689 -41.919879) (xy 259.919724 -41.93413) (xy 259.91947 -41.93413)
			(xy 259.910504 -41.937772) (xy 259.896015 -41.950583) (xy 259.891276 -41.959022) (xy 259.854446 -42.030904)
			(xy 259.852668 -42.049954) (xy 259.855462 -42.059606) (xy 259.867486 -42.101336) (xy 259.88432 -42.186539)
			(xy 259.892782 -42.272975) (xy 259.893308 -42.3164) (xy 259.892842 -42.358233) (xy 259.885017 -42.441532)
			(xy 259.869417 -42.523731) (xy 259.858256 -42.56405) (xy 259.856062 -42.573304) (xy 259.857882 -42.59222)
			(xy 259.861812 -42.60088) (xy 259.87502 -42.627804) (xy 259.879643 -42.636192) (xy 259.893874 -42.648989)
			(xy 259.902706 -42.652696) (xy 259.941221 -42.667831) (xy 260.015569 -42.704177) (xy 260.086221 -42.747271)
			(xy 260.152565 -42.79674) (xy 260.214028 -42.852157) (xy 260.270078 -42.913043) (xy 260.320231 -42.978871)
			(xy 260.364054 -43.049073) (xy 260.401167 -43.123041) (xy 260.431251 -43.200137) (xy 260.454044 -43.279693)
			(xy 260.469349 -43.361022) (xy 260.477035 -43.443421) (xy 260.477508 -43.4848) (xy 260.477004 -43.527148)
			(xy 260.468953 -43.611462) (xy 260.452924 -43.694628) (xy 260.429063 -43.775895) (xy 260.397584 -43.854525)
			(xy 260.358773 -43.929806) (xy 260.312983 -44.001058) (xy 260.260627 -44.067634) (xy 260.202179 -44.128932)
			(xy 260.138169 -44.184397) (xy 260.069177 -44.233526) (xy 259.995827 -44.275875) (xy 259.918784 -44.311059)
			(xy 259.838745 -44.338761) (xy 259.756436 -44.358729) (xy 259.672601 -44.370782) (xy 259.588 -44.374813)
			(xy 259.503399 -44.370782) (xy 259.419564 -44.358729) (xy 259.337255 -44.338761) (xy 259.257216 -44.311059)
			(xy 259.180173 -44.275875) (xy 259.106823 -44.233526) (xy 259.037831 -44.184397) (xy 258.973821 -44.128932)
			(xy 258.915373 -44.067634) (xy 258.863017 -44.001058) (xy 258.817227 -43.929806) (xy 258.778416 -43.854525)
			(xy 258.746937 -43.775895) (xy 258.723076 -43.694628) (xy 258.707047 -43.611462) (xy 258.698996 -43.527148)
			(xy 258.698492 -43.4848) (xy 258.698492 -43.48353) (xy 258.699023 -43.44191) (xy 258.706887 -43.359041)
			(xy 258.722447 -43.277267) (xy 258.733544 -43.23715) (xy 258.735738 -43.227896) (xy 258.733918 -43.20898)
			(xy 258.729988 -43.20032) (xy 258.71678 -43.173396) (xy 258.712157 -43.165008) (xy 258.697926 -43.152211)
			(xy 258.689094 -43.148504) (xy 258.650579 -43.133369) (xy 258.576231 -43.097023) (xy 258.505579 -43.053929)
			(xy 258.439235 -43.00446) (xy 258.377772 -42.949043) (xy 258.321722 -42.888157) (xy 258.271569 -42.822329)
			(xy 258.227746 -42.752127) (xy 258.190633 -42.678159) (xy 258.160549 -42.601063) (xy 258.137756 -42.521507)
			(xy 258.122451 -42.440178) (xy 258.114765 -42.357779) (xy 258.114292 -42.3164) (xy 258.114767 -42.275174)
			(xy 258.122403 -42.193078) (xy 258.1376 -42.112039) (xy 258.160229 -42.032754) (xy 258.190094 -41.955902)
			(xy 258.226941 -41.882142) (xy 258.270452 -41.812106) (xy 258.320255 -41.746396) (xy 258.375923 -41.685574)
			(xy 258.406138 -41.657524) (xy 258.406392 -41.65727) (xy 258.414662 -41.648719) (xy 258.423013 -41.626477)
			(xy 258.422394 -41.614598) (xy 258.413758 -41.53281) (xy 258.411815 -41.520931) (xy 258.398688 -41.50079)
			(xy 258.388612 -41.494202) (xy 258.352203 -41.47258) (xy 258.283247 -41.423422) (xy 258.219273 -41.367935)
			(xy 258.16086 -41.306622) (xy 258.108535 -41.240036) (xy 258.062773 -41.168781) (xy 258.023988 -41.093501)
			(xy 257.992529 -41.014876) (xy 257.968682 -40.933619) (xy 257.952663 -40.850463) (xy 257.944616 -40.766162)
			(xy 257.944112 -40.72382) (xy 257.944711 -40.676728) (xy 257.954665 -40.583073) (xy 257.974444 -40.49099)
			(xy 258.003827 -40.401507) (xy 258.022598 -40.358314) (xy 258.026471 -40.348329) (xy 258.026612 -40.326939)
			(xy 258.022852 -40.316912) (xy 258.004618 -40.27428) (xy 257.976086 -40.18605) (xy 257.956893 -40.09533)
			(xy 257.947248 -40.003104) (xy 257.946652 -39.95674) (xy 257.946693 -39.939388) (xy 257.947962 -39.904707)
			(xy 257.949192 -39.887398) (xy 257.949484 -39.87578) (xy 257.9409 -39.854212) (xy 257.932682 -39.845996)
			(xy 257.902445 -39.817967) (xy 257.846768 -39.757149) (xy 257.796958 -39.69144) (xy 257.753442 -39.621403)
			(xy 257.716595 -39.54764) (xy 257.686732 -39.470783) (xy 257.664109 -39.391493) (xy 257.648921 -39.310449)
			(xy 257.641298 -39.228347) (xy 257.640836 -39.18712) (xy 252.885164 -39.18712) (xy 252.852643 -39.289503)
			(xy 252.790009 -39.46029) (xy 252.719934 -39.628161) (xy 252.642553 -39.792792) (xy 252.558015 -39.953865)
			(xy 252.466484 -40.11107) (xy 252.368136 -40.264102) (xy 252.263161 -40.412666) (xy 252.151762 -40.556477)
			(xy 252.034154 -40.695255) (xy 251.910563 -40.828734) (xy 251.781229 -40.956655) (xy 251.646401 -41.078772)
			(xy 251.506339 -41.194849) (xy 251.361314 -41.304661) (xy 251.211605 -41.407998) (xy 251.057502 -41.504659)
			(xy 250.899302 -41.594458) (xy 250.73731 -41.677221) (xy 250.571839 -41.752789) (xy 250.403208 -41.821016)
			(xy 250.231744 -41.88177) (xy 250.057776 -41.934934) (xy 249.881641 -41.980405) (xy 249.703679 -42.018096)
			(xy 249.524233 -42.047934) (xy 249.343649 -42.069861) (xy 249.162277 -42.083834) (xy 248.980466 -42.089828)
			(xy 248.798567 -42.08783) (xy 248.616932 -42.077844) (xy 248.43591 -42.059889) (xy 248.255852 -42.034001)
			(xy 248.077105 -42.000228) (xy 247.900014 -41.958637) (xy 247.72492 -41.909307) (xy 247.552162 -41.852335)
			(xy 247.382074 -41.787829) (xy 247.214983 -41.715914) (xy 247.051212 -41.636729) (xy 246.891077 -41.550427)
			(xy 246.734888 -41.457175) (xy 246.582945 -41.357152) (xy 246.435542 -41.250552) (xy 246.292964 -41.13758)
			(xy 246.155486 -41.018454) (xy 246.023373 -40.893405) (xy 245.89688 -40.762673) (xy 245.776252 -40.626512)
			(xy 245.66172 -40.485183) (xy 245.553507 -40.338961) (xy 245.451822 -40.188126) (xy 245.356859 -40.03297)
			(xy 245.268804 -39.873793) (xy 245.187825 -39.710902) (xy 245.114079 -39.544611) (xy 245.047708 -39.375241)
			(xy 244.988841 -39.203119) (xy 244.937591 -39.028578) (xy 244.894058 -38.851954) (xy 244.858324 -38.673589)
			(xy 244.830459 -38.493826) (xy 244.810517 -38.313013) (xy 244.798537 -38.131498) (xy 244.794541 -37.949632)
			(xy 241.68608 -37.949632) (xy 239.906556 -39.729156) (xy 239.882676 -39.752312) (xy 239.829912 -39.792818)
			(xy 239.772311 -39.826089) (xy 239.71086 -39.851553) (xy 239.646609 -39.868775) (xy 239.580659 -39.877461)
			(xy 239.5474 -39.878) (xy 215.9254 -39.878) (xy 215.89214 -39.877479) (xy 215.82619 -39.868791) (xy 215.761939 -39.851566)
			(xy 215.700488 -39.826097) (xy 215.642889 -39.792821) (xy 215.590129 -39.752308) (xy 215.566244 -39.729156)
			(xy 214.677244 -38.840156) (xy 214.654088 -38.816276) (xy 214.613582 -38.763512) (xy 214.580311 -38.705911)
			(xy 214.554847 -38.64446) (xy 214.537625 -38.580209) (xy 214.528939 -38.514259) (xy 214.5284 -38.481)
			(xy 214.5284 -22.86) (xy 214.528921 -22.82674) (xy 214.537609 -22.76079) (xy 214.554834 -22.696539)
			(xy 214.580303 -22.635088) (xy 214.613579 -22.577489) (xy 214.654092 -22.524729) (xy 214.677244 -22.500844)
			(xy 215.820244 -21.357844) (xy 215.844124 -21.334688) (xy 215.896888 -21.294182) (xy 215.954489 -21.260911)
			(xy 216.01594 -21.235447) (xy 216.080191 -21.218225) (xy 216.146141 -21.209539) (xy 216.1794 -21.209)
			(xy 271.675606 -21.209) (xy 271.685676 -21.208576) (xy 271.704279 -21.20086) (xy 271.711674 -21.194014)
			(xy 272.781014 -20.124674) (xy 272.787866 -20.117278) (xy 272.795604 -20.098679) (xy 272.796 -20.088606)
			(xy 272.796 -1.755394) (xy 272.795576 -1.745324) (xy 272.78786 -1.726721) (xy 272.781014 -1.719326)
			(xy 272.67154 -1.609852) (xy 272.660364 -1.606042) (xy 272.621829 -1.592597) (xy 272.547173 -1.559602)
			(xy 272.475853 -1.519906) (xy 272.40847 -1.473844) (xy 272.345591 -1.421802) (xy 272.287743 -1.364219)
			(xy 272.235414 -1.301578) (xy 272.189044 -1.234407) (xy 272.149023 -1.16327) (xy 272.115686 -1.088766)
			(xy 272.102072 -1.05029) (xy 272.100802 -1.04648) (xy 272.098745 -1.041037) (xy 272.092593 -1.031164)
			(xy 272.08861 -1.026922) (xy 272.085308 -1.02362) (xy 272.066766 -1.016) (xy 268.73708 -1.016) (xy 268.710918 -1.034796)
			(xy 268.705584 -1.05029) (xy 268.691391 -1.090346) (xy 268.656395 -1.167791) (xy 268.614171 -1.241546)
			(xy 268.565104 -1.310936) (xy 268.509643 -1.37533) (xy 268.448291 -1.43414) (xy 268.38161 -1.48683)
			(xy 268.310207 -1.532919) (xy 268.234734 -1.571987) (xy 268.155878 -1.603678) (xy 268.074358 -1.627703)
			(xy 267.990919 -1.643842) (xy 267.906321 -1.651948) (xy 267.821335 -1.651948) (xy 267.736737 -1.643842)
			(xy 267.653298 -1.627703) (xy 267.571778 -1.603678) (xy 267.492922 -1.571987) (xy 267.417449 -1.532919)
			(xy 267.346046 -1.48683) (xy 267.279365 -1.43414) (xy 267.218013 -1.37533) (xy 267.162552 -1.310936)
			(xy 267.113485 -1.241546) (xy 267.071261 -1.167791) (xy 267.036265 -1.090346) (xy 267.022072 -1.05029)
			(xy 267.016738 -1.034796) (xy 266.990576 -1.016) (xy 263.65708 -1.016) (xy 263.630918 -1.034796)
			(xy 263.625584 -1.05029) (xy 263.611391 -1.090346) (xy 263.576395 -1.167791) (xy 263.534171 -1.241546)
			(xy 263.485104 -1.310936) (xy 263.429643 -1.37533) (xy 263.368291 -1.43414) (xy 263.30161 -1.48683)
			(xy 263.230207 -1.532919) (xy 263.154734 -1.571987) (xy 263.075878 -1.603678) (xy 262.994358 -1.627703)
			(xy 262.910919 -1.643842) (xy 262.826321 -1.651948) (xy 262.741335 -1.651948) (xy 262.656737 -1.643842)
			(xy 262.573298 -1.627703) (xy 262.491778 -1.603678) (xy 262.412922 -1.571987) (xy 262.337449 -1.532919)
			(xy 262.266046 -1.48683) (xy 262.199365 -1.43414) (xy 262.138013 -1.37533) (xy 262.082552 -1.310936)
			(xy 262.033485 -1.241546) (xy 261.991261 -1.167791) (xy 261.956265 -1.090346) (xy 261.942072 -1.05029)
			(xy 261.936738 -1.034796) (xy 261.910576 -1.016) (xy 258.57708 -1.016) (xy 258.550918 -1.034796)
			(xy 258.545584 -1.05029) (xy 258.531391 -1.090346) (xy 258.496395 -1.167791) (xy 258.454171 -1.241546)
			(xy 258.405104 -1.310936) (xy 258.349643 -1.37533) (xy 258.288291 -1.43414) (xy 258.22161 -1.48683)
			(xy 258.150207 -1.532919) (xy 258.074734 -1.571987) (xy 257.995878 -1.603678) (xy 257.914358 -1.627703)
			(xy 257.830919 -1.643842) (xy 257.746321 -1.651948) (xy 257.661335 -1.651948) (xy 257.576737 -1.643842)
			(xy 257.493298 -1.627703) (xy 257.411778 -1.603678) (xy 257.332922 -1.571987) (xy 257.257449 -1.532919)
			(xy 257.186046 -1.48683) (xy 257.119365 -1.43414) (xy 257.058013 -1.37533) (xy 257.002552 -1.310936)
			(xy 256.953485 -1.241546) (xy 256.911261 -1.167791) (xy 256.876265 -1.090346) (xy 256.862072 -1.05029)
			(xy 256.856738 -1.034796) (xy 256.830576 -1.016) (xy 253.49708 -1.016) (xy 253.470918 -1.034796)
			(xy 253.465584 -1.05029) (xy 253.451391 -1.090346) (xy 253.416395 -1.167791) (xy 253.374171 -1.241546)
			(xy 253.325104 -1.310936) (xy 253.269643 -1.37533) (xy 253.208291 -1.43414) (xy 253.14161 -1.48683)
			(xy 253.070207 -1.532919) (xy 252.994734 -1.571987) (xy 252.915878 -1.603678) (xy 252.834358 -1.627703)
			(xy 252.750919 -1.643842) (xy 252.666321 -1.651948) (xy 252.581335 -1.651948) (xy 252.496737 -1.643842)
			(xy 252.413298 -1.627703) (xy 252.331778 -1.603678) (xy 252.252922 -1.571987) (xy 252.177449 -1.532919)
			(xy 252.106046 -1.48683) (xy 252.039365 -1.43414) (xy 251.978013 -1.37533) (xy 251.922552 -1.310936)
			(xy 251.873485 -1.241546) (xy 251.831261 -1.167791) (xy 251.796265 -1.090346) (xy 251.782072 -1.05029)
			(xy 251.776738 -1.034796) (xy 251.750576 -1.016) (xy 248.41708 -1.016) (xy 248.390918 -1.034796)
			(xy 248.385584 -1.05029) (xy 248.371391 -1.090346) (xy 248.336395 -1.167791) (xy 248.294171 -1.241546)
			(xy 248.245104 -1.310936) (xy 248.189643 -1.37533) (xy 248.128291 -1.43414) (xy 248.06161 -1.48683)
			(xy 247.990207 -1.532919) (xy 247.914734 -1.571987) (xy 247.835878 -1.603678) (xy 247.754358 -1.627703)
			(xy 247.670919 -1.643842) (xy 247.586321 -1.651948) (xy 247.501335 -1.651948) (xy 247.416737 -1.643842)
			(xy 247.333298 -1.627703) (xy 247.251778 -1.603678) (xy 247.172922 -1.571987) (xy 247.097449 -1.532919)
			(xy 247.026046 -1.48683) (xy 246.959365 -1.43414) (xy 246.898013 -1.37533) (xy 246.842552 -1.310936)
			(xy 246.793485 -1.241546) (xy 246.751261 -1.167791) (xy 246.716265 -1.090346) (xy 246.702072 -1.05029)
			(xy 246.696738 -1.034796) (xy 246.670576 -1.016) (xy 243.33708 -1.016) (xy 243.310918 -1.034796)
			(xy 243.305584 -1.05029) (xy 243.291391 -1.090346) (xy 243.256395 -1.167791) (xy 243.214171 -1.241546)
			(xy 243.165104 -1.310936) (xy 243.109643 -1.37533) (xy 243.048291 -1.43414) (xy 242.98161 -1.48683)
			(xy 242.910207 -1.532919) (xy 242.834734 -1.571987) (xy 242.755878 -1.603678) (xy 242.674358 -1.627703)
			(xy 242.590919 -1.643842) (xy 242.506321 -1.651948) (xy 242.421335 -1.651948) (xy 242.336737 -1.643842)
			(xy 242.253298 -1.627703) (xy 242.171778 -1.603678) (xy 242.092922 -1.571987) (xy 242.017449 -1.532919)
			(xy 241.946046 -1.48683) (xy 241.879365 -1.43414) (xy 241.818013 -1.37533) (xy 241.762552 -1.310936)
			(xy 241.713485 -1.241546) (xy 241.671261 -1.167791) (xy 241.636265 -1.090346) (xy 241.622072 -1.05029)
			(xy 241.616738 -1.034796) (xy 241.590576 -1.016) (xy 238.25708 -1.016) (xy 238.230918 -1.034796)
			(xy 238.225584 -1.05029) (xy 238.211391 -1.090346) (xy 238.176395 -1.167791) (xy 238.134171 -1.241546)
			(xy 238.085104 -1.310936) (xy 238.029643 -1.37533) (xy 237.968291 -1.43414) (xy 237.90161 -1.48683)
			(xy 237.830207 -1.532919) (xy 237.754734 -1.571987) (xy 237.675878 -1.603678) (xy 237.594358 -1.627703)
			(xy 237.510919 -1.643842) (xy 237.426321 -1.651948) (xy 237.341335 -1.651948) (xy 237.256737 -1.643842)
			(xy 237.173298 -1.627703) (xy 237.091778 -1.603678) (xy 237.012922 -1.571987) (xy 236.937449 -1.532919)
			(xy 236.866046 -1.48683) (xy 236.799365 -1.43414) (xy 236.738013 -1.37533) (xy 236.682552 -1.310936)
			(xy 236.633485 -1.241546) (xy 236.591261 -1.167791) (xy 236.556265 -1.090346) (xy 236.542072 -1.05029)
			(xy 236.536738 -1.034796) (xy 236.510576 -1.016) (xy 233.17708 -1.016) (xy 233.150918 -1.034796)
			(xy 233.145584 -1.05029) (xy 233.131391 -1.090346) (xy 233.096395 -1.167791) (xy 233.054171 -1.241546)
			(xy 233.005104 -1.310936) (xy 232.949643 -1.37533) (xy 232.888291 -1.43414) (xy 232.82161 -1.48683)
			(xy 232.750207 -1.532919) (xy 232.674734 -1.571987) (xy 232.595878 -1.603678) (xy 232.514358 -1.627703)
			(xy 232.430919 -1.643842) (xy 232.346321 -1.651948) (xy 232.261335 -1.651948) (xy 232.176737 -1.643842)
			(xy 232.093298 -1.627703) (xy 232.011778 -1.603678) (xy 231.932922 -1.571987) (xy 231.857449 -1.532919)
			(xy 231.786046 -1.48683) (xy 231.719365 -1.43414) (xy 231.658013 -1.37533) (xy 231.602552 -1.310936)
			(xy 231.553485 -1.241546) (xy 231.511261 -1.167791) (xy 231.476265 -1.090346) (xy 231.462072 -1.05029)
			(xy 231.456738 -1.034796) (xy 231.430576 -1.016) (xy 228.09708 -1.016) (xy 228.070918 -1.034796)
			(xy 228.065584 -1.05029) (xy 228.051391 -1.090346) (xy 228.016395 -1.167791) (xy 227.974171 -1.241546)
			(xy 227.925104 -1.310936) (xy 227.869643 -1.37533) (xy 227.808291 -1.43414) (xy 227.74161 -1.48683)
			(xy 227.670207 -1.532919) (xy 227.594734 -1.571987) (xy 227.515878 -1.603678) (xy 227.434358 -1.627703)
			(xy 227.350919 -1.643842) (xy 227.266321 -1.651948) (xy 227.181335 -1.651948) (xy 227.096737 -1.643842)
			(xy 227.013298 -1.627703) (xy 226.931778 -1.603678) (xy 226.852922 -1.571987) (xy 226.777449 -1.532919)
			(xy 226.706046 -1.48683) (xy 226.639365 -1.43414) (xy 226.578013 -1.37533) (xy 226.522552 -1.310936)
			(xy 226.473485 -1.241546) (xy 226.431261 -1.167791) (xy 226.396265 -1.090346) (xy 226.382072 -1.05029)
			(xy 226.376738 -1.034796) (xy 226.350576 -1.016) (xy 223.01708 -1.016) (xy 222.990918 -1.034796)
			(xy 222.985584 -1.05029) (xy 222.971391 -1.090346) (xy 222.936395 -1.167791) (xy 222.894171 -1.241546)
			(xy 222.845104 -1.310936) (xy 222.789643 -1.37533) (xy 222.728291 -1.43414) (xy 222.66161 -1.48683)
			(xy 222.590207 -1.532919) (xy 222.514734 -1.571987) (xy 222.435878 -1.603678) (xy 222.354358 -1.627703)
			(xy 222.270919 -1.643842) (xy 222.186321 -1.651948) (xy 222.101335 -1.651948) (xy 222.016737 -1.643842)
			(xy 221.933298 -1.627703) (xy 221.851778 -1.603678) (xy 221.772922 -1.571987) (xy 221.697449 -1.532919)
			(xy 221.626046 -1.48683) (xy 221.559365 -1.43414) (xy 221.498013 -1.37533) (xy 221.442552 -1.310936)
			(xy 221.393485 -1.241546) (xy 221.351261 -1.167791) (xy 221.316265 -1.090346) (xy 221.302072 -1.05029)
			(xy 221.296738 -1.034796) (xy 221.270576 -1.016) (xy 217.93708 -1.016) (xy 217.910918 -1.034796)
			(xy 217.905584 -1.05029) (xy 217.891391 -1.090346) (xy 217.856395 -1.167791) (xy 217.814171 -1.241546)
			(xy 217.765104 -1.310936) (xy 217.709643 -1.37533) (xy 217.648291 -1.43414) (xy 217.58161 -1.48683)
			(xy 217.510207 -1.532919) (xy 217.434734 -1.571987) (xy 217.355878 -1.603678) (xy 217.274358 -1.627703)
			(xy 217.190919 -1.643842) (xy 217.106321 -1.651948) (xy 217.021335 -1.651948) (xy 216.936737 -1.643842)
			(xy 216.853298 -1.627703) (xy 216.771778 -1.603678) (xy 216.692922 -1.571987) (xy 216.617449 -1.532919)
			(xy 216.546046 -1.48683) (xy 216.479365 -1.43414) (xy 216.418013 -1.37533) (xy 216.362552 -1.310936)
			(xy 216.313485 -1.241546) (xy 216.271261 -1.167791) (xy 216.236265 -1.090346) (xy 216.222072 -1.05029)
			(xy 216.216738 -1.034796) (xy 216.190576 -1.016) (xy 212.85708 -1.016) (xy 212.830918 -1.034796)
			(xy 212.825584 -1.05029) (xy 212.811391 -1.090346) (xy 212.776395 -1.167791) (xy 212.734171 -1.241546)
			(xy 212.685104 -1.310936) (xy 212.629643 -1.37533) (xy 212.568291 -1.43414) (xy 212.50161 -1.48683)
			(xy 212.430207 -1.532919) (xy 212.354734 -1.571987) (xy 212.275878 -1.603678) (xy 212.194358 -1.627703)
			(xy 212.110919 -1.643842) (xy 212.026321 -1.651948) (xy 211.941335 -1.651948) (xy 211.856737 -1.643842)
			(xy 211.773298 -1.627703) (xy 211.691778 -1.603678) (xy 211.612922 -1.571987) (xy 211.537449 -1.532919)
			(xy 211.466046 -1.48683) (xy 211.399365 -1.43414) (xy 211.338013 -1.37533) (xy 211.282552 -1.310936)
			(xy 211.233485 -1.241546) (xy 211.191261 -1.167791) (xy 211.156265 -1.090346) (xy 211.142072 -1.05029)
			(xy 211.136738 -1.034796) (xy 211.110576 -1.016) (xy 207.77708 -1.016) (xy 207.750918 -1.034796)
			(xy 207.745584 -1.05029) (xy 207.731391 -1.090346) (xy 207.696395 -1.167791) (xy 207.654171 -1.241546)
			(xy 207.605104 -1.310936) (xy 207.549643 -1.37533) (xy 207.488291 -1.43414) (xy 207.42161 -1.48683)
			(xy 207.350207 -1.532919) (xy 207.274734 -1.571987) (xy 207.195878 -1.603678) (xy 207.114358 -1.627703)
			(xy 207.030919 -1.643842) (xy 206.946321 -1.651948) (xy 206.861335 -1.651948) (xy 206.776737 -1.643842)
			(xy 206.693298 -1.627703) (xy 206.611778 -1.603678) (xy 206.532922 -1.571987) (xy 206.457449 -1.532919)
			(xy 206.386046 -1.48683) (xy 206.319365 -1.43414) (xy 206.258013 -1.37533) (xy 206.202552 -1.310936)
			(xy 206.153485 -1.241546) (xy 206.111261 -1.167791) (xy 206.076265 -1.090346) (xy 206.062072 -1.05029)
			(xy 206.056738 -1.034796) (xy 206.030576 -1.016) (xy 202.69708 -1.016) (xy 202.670918 -1.034796)
			(xy 202.665584 -1.05029) (xy 202.651391 -1.090346) (xy 202.616395 -1.167791) (xy 202.574171 -1.241546)
			(xy 202.525104 -1.310936) (xy 202.469643 -1.37533) (xy 202.408291 -1.43414) (xy 202.34161 -1.48683)
			(xy 202.270207 -1.532919) (xy 202.194734 -1.571987) (xy 202.115878 -1.603678) (xy 202.034358 -1.627703)
			(xy 201.950919 -1.643842) (xy 201.866321 -1.651948) (xy 201.781335 -1.651948) (xy 201.696737 -1.643842)
			(xy 201.613298 -1.627703) (xy 201.531778 -1.603678) (xy 201.452922 -1.571987) (xy 201.377449 -1.532919)
			(xy 201.306046 -1.48683) (xy 201.239365 -1.43414) (xy 201.178013 -1.37533) (xy 201.122552 -1.310936)
			(xy 201.073485 -1.241546) (xy 201.031261 -1.167791) (xy 200.996265 -1.090346) (xy 200.982072 -1.05029)
			(xy 200.976738 -1.034796) (xy 200.950576 -1.016) (xy 197.61708 -1.016) (xy 197.590918 -1.034796)
			(xy 197.585584 -1.05029) (xy 197.571391 -1.090346) (xy 197.536395 -1.167791) (xy 197.494171 -1.241546)
			(xy 197.445104 -1.310936) (xy 197.389643 -1.37533) (xy 197.328291 -1.43414) (xy 197.26161 -1.48683)
			(xy 197.190207 -1.532919) (xy 197.114734 -1.571987) (xy 197.035878 -1.603678) (xy 196.954358 -1.627703)
			(xy 196.870919 -1.643842) (xy 196.786321 -1.651948) (xy 196.701335 -1.651948) (xy 196.616737 -1.643842)
			(xy 196.533298 -1.627703) (xy 196.451778 -1.603678) (xy 196.372922 -1.571987) (xy 196.297449 -1.532919)
			(xy 196.226046 -1.48683) (xy 196.159365 -1.43414) (xy 196.098013 -1.37533) (xy 196.042552 -1.310936)
			(xy 195.993485 -1.241546) (xy 195.951261 -1.167791) (xy 195.916265 -1.090346) (xy 195.902072 -1.05029)
			(xy 195.896738 -1.034796) (xy 195.870576 -1.016) (xy 192.53708 -1.016) (xy 192.510918 -1.034796)
			(xy 192.505584 -1.05029) (xy 192.491391 -1.090346) (xy 192.456395 -1.167791) (xy 192.414171 -1.241546)
			(xy 192.365104 -1.310936) (xy 192.309643 -1.37533) (xy 192.248291 -1.43414) (xy 192.18161 -1.48683)
			(xy 192.110207 -1.532919) (xy 192.034734 -1.571987) (xy 191.955878 -1.603678) (xy 191.874358 -1.627703)
			(xy 191.790919 -1.643842) (xy 191.706321 -1.651948) (xy 191.621335 -1.651948) (xy 191.536737 -1.643842)
			(xy 191.453298 -1.627703) (xy 191.371778 -1.603678) (xy 191.292922 -1.571987) (xy 191.217449 -1.532919)
			(xy 191.146046 -1.48683) (xy 191.079365 -1.43414) (xy 191.018013 -1.37533) (xy 190.962552 -1.310936)
			(xy 190.913485 -1.241546) (xy 190.871261 -1.167791) (xy 190.836265 -1.090346) (xy 190.822072 -1.05029)
			(xy 190.816738 -1.034796) (xy 190.790576 -1.016) (xy 187.45708 -1.016) (xy 187.430918 -1.034796)
			(xy 187.425584 -1.05029) (xy 187.411391 -1.090346) (xy 187.376395 -1.167791) (xy 187.334171 -1.241546)
			(xy 187.285104 -1.310936) (xy 187.229643 -1.37533) (xy 187.168291 -1.43414) (xy 187.10161 -1.48683)
			(xy 187.030207 -1.532919) (xy 186.954734 -1.571987) (xy 186.875878 -1.603678) (xy 186.794358 -1.627703)
			(xy 186.710919 -1.643842) (xy 186.626321 -1.651948) (xy 186.541335 -1.651948) (xy 186.456737 -1.643842)
			(xy 186.373298 -1.627703) (xy 186.291778 -1.603678) (xy 186.212922 -1.571987) (xy 186.137449 -1.532919)
			(xy 186.066046 -1.48683) (xy 185.999365 -1.43414) (xy 185.938013 -1.37533) (xy 185.882552 -1.310936)
			(xy 185.833485 -1.241546) (xy 185.791261 -1.167791) (xy 185.756265 -1.090346) (xy 185.742072 -1.05029)
			(xy 185.736738 -1.034796) (xy 185.710576 -1.016) (xy 182.37708 -1.016) (xy 182.350918 -1.034796)
			(xy 182.345584 -1.05029) (xy 182.331391 -1.090346) (xy 182.296395 -1.167791) (xy 182.254171 -1.241546)
			(xy 182.205104 -1.310936) (xy 182.149643 -1.37533) (xy 182.088291 -1.43414) (xy 182.02161 -1.48683)
			(xy 181.950207 -1.532919) (xy 181.874734 -1.571987) (xy 181.795878 -1.603678) (xy 181.714358 -1.627703)
			(xy 181.630919 -1.643842) (xy 181.546321 -1.651948) (xy 181.461335 -1.651948) (xy 181.376737 -1.643842)
			(xy 181.293298 -1.627703) (xy 181.211778 -1.603678) (xy 181.132922 -1.571987) (xy 181.057449 -1.532919)
			(xy 180.986046 -1.48683) (xy 180.919365 -1.43414) (xy 180.858013 -1.37533) (xy 180.802552 -1.310936)
			(xy 180.753485 -1.241546) (xy 180.711261 -1.167791) (xy 180.676265 -1.090346) (xy 180.662072 -1.05029)
			(xy 180.656738 -1.034796) (xy 180.630576 -1.016) (xy 177.29708 -1.016) (xy 177.270918 -1.034796)
			(xy 177.265584 -1.05029) (xy 177.251391 -1.090346) (xy 177.216395 -1.167791) (xy 177.174171 -1.241546)
			(xy 177.125104 -1.310936) (xy 177.069643 -1.37533) (xy 177.008291 -1.43414) (xy 176.94161 -1.48683)
			(xy 176.870207 -1.532919) (xy 176.794734 -1.571987) (xy 176.715878 -1.603678) (xy 176.634358 -1.627703)
			(xy 176.550919 -1.643842) (xy 176.466321 -1.651948) (xy 176.381335 -1.651948) (xy 176.296737 -1.643842)
			(xy 176.213298 -1.627703) (xy 176.131778 -1.603678) (xy 176.052922 -1.571987) (xy 175.977449 -1.532919)
			(xy 175.906046 -1.48683) (xy 175.839365 -1.43414) (xy 175.778013 -1.37533) (xy 175.722552 -1.310936)
			(xy 175.673485 -1.241546) (xy 175.631261 -1.167791) (xy 175.596265 -1.090346) (xy 175.582072 -1.05029)
			(xy 175.576738 -1.034796) (xy 175.550576 -1.016) (xy 172.21708 -1.016) (xy 172.190918 -1.034796)
			(xy 172.185584 -1.05029) (xy 172.171391 -1.090346) (xy 172.136395 -1.167791) (xy 172.094171 -1.241546)
			(xy 172.045104 -1.310936) (xy 171.989643 -1.37533) (xy 171.928291 -1.43414) (xy 171.86161 -1.48683)
			(xy 171.790207 -1.532919) (xy 171.714734 -1.571987) (xy 171.635878 -1.603678) (xy 171.554358 -1.627703)
			(xy 171.470919 -1.643842) (xy 171.386321 -1.651948) (xy 171.301335 -1.651948) (xy 171.216737 -1.643842)
			(xy 171.133298 -1.627703) (xy 171.051778 -1.603678) (xy 170.972922 -1.571987) (xy 170.897449 -1.532919)
			(xy 170.826046 -1.48683) (xy 170.759365 -1.43414) (xy 170.698013 -1.37533) (xy 170.642552 -1.310936)
			(xy 170.593485 -1.241546) (xy 170.551261 -1.167791) (xy 170.516265 -1.090346) (xy 170.502072 -1.05029)
			(xy 170.496738 -1.034796) (xy 170.470576 -1.016) (xy 167.13708 -1.016) (xy 167.110918 -1.034796)
			(xy 167.105584 -1.05029) (xy 167.091391 -1.090346) (xy 167.056395 -1.167791) (xy 167.014171 -1.241546)
			(xy 166.965104 -1.310936) (xy 166.909643 -1.37533) (xy 166.848291 -1.43414) (xy 166.78161 -1.48683)
			(xy 166.710207 -1.532919) (xy 166.634734 -1.571987) (xy 166.555878 -1.603678) (xy 166.474358 -1.627703)
			(xy 166.390919 -1.643842) (xy 166.306321 -1.651948) (xy 166.221335 -1.651948) (xy 166.136737 -1.643842)
			(xy 166.053298 -1.627703) (xy 165.971778 -1.603678) (xy 165.892922 -1.571987) (xy 165.817449 -1.532919)
			(xy 165.746046 -1.48683) (xy 165.679365 -1.43414) (xy 165.618013 -1.37533) (xy 165.562552 -1.310936)
			(xy 165.513485 -1.241546) (xy 165.471261 -1.167791) (xy 165.436265 -1.090346) (xy 165.422072 -1.05029)
			(xy 165.416738 -1.034796) (xy 165.390576 -1.016) (xy 162.05708 -1.016) (xy 162.030918 -1.034796)
			(xy 162.025584 -1.05029) (xy 162.011391 -1.090346) (xy 161.976395 -1.167791) (xy 161.934171 -1.241546)
			(xy 161.885104 -1.310936) (xy 161.829643 -1.37533) (xy 161.768291 -1.43414) (xy 161.70161 -1.48683)
			(xy 161.630207 -1.532919) (xy 161.554734 -1.571987) (xy 161.475878 -1.603678) (xy 161.394358 -1.627703)
			(xy 161.310919 -1.643842) (xy 161.226321 -1.651948) (xy 161.141335 -1.651948) (xy 161.056737 -1.643842)
			(xy 160.973298 -1.627703) (xy 160.891778 -1.603678) (xy 160.812922 -1.571987) (xy 160.737449 -1.532919)
			(xy 160.666046 -1.48683) (xy 160.599365 -1.43414) (xy 160.538013 -1.37533) (xy 160.482552 -1.310936)
			(xy 160.433485 -1.241546) (xy 160.391261 -1.167791) (xy 160.356265 -1.090346) (xy 160.342072 -1.05029)
			(xy 160.336738 -1.034796) (xy 160.310576 -1.016) (xy 156.97708 -1.016) (xy 156.950918 -1.034796)
			(xy 156.945584 -1.05029) (xy 156.931391 -1.090346) (xy 156.896395 -1.167791) (xy 156.854171 -1.241546)
			(xy 156.805104 -1.310936) (xy 156.749643 -1.37533) (xy 156.688291 -1.43414) (xy 156.62161 -1.48683)
			(xy 156.550207 -1.532919) (xy 156.474734 -1.571987) (xy 156.395878 -1.603678) (xy 156.314358 -1.627703)
			(xy 156.230919 -1.643842) (xy 156.146321 -1.651948) (xy 156.061335 -1.651948) (xy 155.976737 -1.643842)
			(xy 155.893298 -1.627703) (xy 155.811778 -1.603678) (xy 155.732922 -1.571987) (xy 155.657449 -1.532919)
			(xy 155.586046 -1.48683) (xy 155.519365 -1.43414) (xy 155.458013 -1.37533) (xy 155.402552 -1.310936)
			(xy 155.353485 -1.241546) (xy 155.311261 -1.167791) (xy 155.276265 -1.090346) (xy 155.262072 -1.05029)
			(xy 155.256738 -1.034796) (xy 155.230576 -1.016) (xy 151.89708 -1.016) (xy 151.870918 -1.034796)
			(xy 151.865584 -1.05029) (xy 151.851389 -1.090347) (xy 151.81639 -1.167795) (xy 151.774164 -1.241553)
			(xy 151.725097 -1.310949) (xy 151.669636 -1.375348) (xy 151.608287 -1.434165) (xy 151.541608 -1.486864)
			(xy 151.470207 -1.532964) (xy 151.394735 -1.572044) (xy 151.315881 -1.603749) (xy 151.234363 -1.62779)
			(xy 151.150923 -1.643947) (xy 151.066323 -1.652074) (xy 151.023828 -1.652524) (xy 151.023574 -1.652524)
			(xy 150.982468 -1.652066) (xy 150.900607 -1.644485) (xy 150.819795 -1.629379) (xy 150.740722 -1.606879)
			(xy 150.664063 -1.577176) (xy 150.590474 -1.540524) (xy 150.520582 -1.497236) (xy 150.454984 -1.447682)
			(xy 150.39424 -1.392284) (xy 150.366222 -1.362202) (xy 150.359364 -1.354582) (xy 150.340314 -1.345692)
			(xy 150.25624 -1.343914) (xy 150.245998 -1.344164) (xy 150.22699 -1.351755) (xy 150.21941 -1.358646)
			(xy 149.747986 -1.83007) (xy 149.741141 -1.837468) (xy 149.733419 -1.856067) (xy 149.733 -1.866138)
			(xy 149.733 -4.373642) (xy 242.624091 -4.373642) (xy 242.624091 -4.236958) (xy 242.632038 -4.100506)
			(xy 242.647906 -3.964747) (xy 242.671641 -3.830141) (xy 242.703163 -3.697142) (xy 242.742364 -3.566201)
			(xy 242.789112 -3.43776) (xy 242.84325 -3.312256) (xy 242.904593 -3.190111) (xy 242.972935 -3.07174)
			(xy 243.048043 -2.957543) (xy 243.129665 -2.847906) (xy 243.217523 -2.743201) (xy 243.311321 -2.643781)
			(xy 243.410741 -2.549983) (xy 243.515446 -2.462125) (xy 243.625083 -2.380503) (xy 243.73928 -2.305395)
			(xy 243.857651 -2.237053) (xy 243.979796 -2.17571) (xy 244.1053 -2.121572) (xy 244.233741 -2.074824)
			(xy 244.364682 -2.035623) (xy 244.497681 -2.004101) (xy 244.632287 -1.980366) (xy 244.768046 -1.964498)
			(xy 244.904498 -1.956551) (xy 245.041182 -1.956551) (xy 245.177634 -1.964498) (xy 245.313393 -1.980366)
			(xy 245.447999 -2.004101) (xy 245.580998 -2.035623) (xy 245.711939 -2.074824) (xy 245.84038 -2.121572)
			(xy 245.965884 -2.17571) (xy 246.088029 -2.237053) (xy 246.2064 -2.305395) (xy 246.320597 -2.380503)
			(xy 246.430234 -2.462125) (xy 246.534939 -2.549983) (xy 246.634359 -2.643781) (xy 246.728157 -2.743201)
			(xy 246.816015 -2.847906) (xy 246.897637 -2.957543) (xy 246.972745 -3.07174) (xy 247.041087 -3.190111)
			(xy 247.10243 -3.312256) (xy 247.156568 -3.43776) (xy 247.203316 -3.566201) (xy 247.242517 -3.697142)
			(xy 247.274039 -3.830141) (xy 247.297774 -3.964747) (xy 247.313642 -4.100506) (xy 247.321589 -4.236958)
			(xy 247.322086 -4.3053) (xy 247.321589 -4.373642) (xy 247.313642 -4.510094) (xy 247.297774 -4.645853)
			(xy 247.274039 -4.780459) (xy 247.242517 -4.913458) (xy 247.203316 -5.044399) (xy 247.156568 -5.17284)
			(xy 247.10243 -5.298344) (xy 247.041087 -5.420489) (xy 246.972745 -5.53886) (xy 246.897637 -5.653057)
			(xy 246.816015 -5.762694) (xy 246.728157 -5.867399) (xy 246.634359 -5.966819) (xy 246.534939 -6.060617)
			(xy 246.430234 -6.148475) (xy 246.320597 -6.230097) (xy 246.2064 -6.305205) (xy 246.088029 -6.373547)
			(xy 245.965884 -6.43489) (xy 245.84038 -6.489028) (xy 245.711939 -6.535776) (xy 245.580998 -6.574977)
			(xy 245.447999 -6.606499) (xy 245.313393 -6.630234) (xy 245.177634 -6.646102) (xy 245.041182 -6.654049)
			(xy 244.904498 -6.654049) (xy 244.768046 -6.646102) (xy 244.632287 -6.630234) (xy 244.497681 -6.606499)
			(xy 244.364682 -6.574977) (xy 244.233741 -6.535776) (xy 244.1053 -6.489028) (xy 243.979796 -6.43489)
			(xy 243.857651 -6.373547) (xy 243.73928 -6.305205) (xy 243.625083 -6.230097) (xy 243.515446 -6.148475)
			(xy 243.410741 -6.060617) (xy 243.311321 -5.966819) (xy 243.217523 -5.867399) (xy 243.129665 -5.762694)
			(xy 243.048043 -5.653057) (xy 242.972935 -5.53886) (xy 242.904593 -5.420489) (xy 242.84325 -5.298344)
			(xy 242.789112 -5.17284) (xy 242.742364 -5.044399) (xy 242.703163 -4.913458) (xy 242.671641 -4.780459)
			(xy 242.647906 -4.645853) (xy 242.632038 -4.510094) (xy 242.624091 -4.373642) (xy 149.733 -4.373642)
			(xy 149.733 -11.811) (xy 161.213292 -11.811) (xy 161.213292 -11.810238) (xy 161.2137 -11.772018)
			(xy 161.220265 -11.695859) (xy 161.233349 -11.620547) (xy 161.252856 -11.546637) (xy 161.265362 -11.510518)
			(xy 161.267948 -11.502202) (xy 161.267948 -11.484798) (xy 161.265362 -11.476482) (xy 161.252871 -11.440359)
			(xy 161.233381 -11.366447) (xy 161.220297 -11.291136) (xy 161.213715 -11.214981) (xy 161.213292 -11.176762)
			(xy 161.213292 -11.176) (xy 161.213787 -11.132867) (xy 161.222145 -11.047006) (xy 161.238773 -10.962358)
			(xy 161.263515 -10.879715) (xy 161.296139 -10.799856) (xy 161.336337 -10.723528) (xy 161.383734 -10.651448)
			(xy 161.437884 -10.584294) (xy 161.498278 -10.522696) (xy 161.564351 -10.467231) (xy 161.63548 -10.41842)
			(xy 161.711 -10.376723) (xy 161.7902 -10.342529) (xy 161.872338 -10.316161) (xy 161.956642 -10.297865)
			(xy 161.999422 -10.292334) (xy 162.010643 -10.290369) (xy 162.029893 -10.278242) (xy 162.036506 -10.268966)
			(xy 162.058636 -10.234762) (xy 162.108294 -10.170172) (xy 162.163649 -10.110392) (xy 162.224237 -10.055923)
			(xy 162.289549 -10.007219) (xy 162.35904 -9.964689) (xy 162.432128 -9.928689) (xy 162.508201 -9.899521)
			(xy 162.586621 -9.877428) (xy 162.666732 -9.862596) (xy 162.747864 -9.855149) (xy 162.7886 -9.854692)
			(xy 162.829702 -9.855167) (xy 162.911557 -9.862752) (xy 162.992362 -9.877857) (xy 163.071429 -9.900353)
			(xy 163.148083 -9.930049) (xy 163.22167 -9.966691) (xy 163.291562 -10.009966) (xy 163.357163 -10.059506)
			(xy 163.417913 -10.114887) (xy 163.473294 -10.175637) (xy 163.522834 -10.241238) (xy 163.566109 -10.31113)
			(xy 163.602751 -10.384717) (xy 163.632447 -10.461371) (xy 163.654943 -10.540438) (xy 163.670048 -10.621243)
			(xy 163.677633 -10.703098) (xy 163.678108 -10.7442) (xy 163.677552 -10.788906) (xy 163.668575 -10.877868)
			(xy 163.650722 -10.96548) (xy 163.624174 -11.050861) (xy 163.589197 -11.133148) (xy 163.546144 -11.211513)
			(xy 163.495449 -11.285166) (xy 163.437624 -11.353364) (xy 163.40582 -11.384788) (xy 163.398468 -11.392585)
			(xy 163.390431 -11.412428) (xy 163.390326 -11.423142) (xy 163.39312 -11.498834) (xy 163.394022 -11.509372)
			(xy 163.403216 -11.528395) (xy 163.4109 -11.535664) (xy 163.411408 -11.535918) (xy 163.444099 -11.564059)
			(xy 163.504484 -11.625663) (xy 163.558621 -11.692823) (xy 163.606001 -11.764909) (xy 163.64618 -11.841243)
			(xy 163.67878 -11.921109) (xy 163.702371 -12) (xy 202.998829 -12) (xy 203.002784 -11.801167) (xy 203.014639 -11.602649)
			(xy 203.034378 -11.404758) (xy 203.061969 -11.207809) (xy 203.097367 -11.012113) (xy 203.140519 -10.817979)
			(xy 203.191353 -10.625713) (xy 203.249792 -10.435621) (xy 203.315742 -10.248002) (xy 203.389099 -10.063154)
			(xy 203.469746 -9.881368) (xy 203.557557 -9.702932) (xy 203.652393 -9.528128) (xy 203.754103 -9.357233)
			(xy 203.862527 -9.190517) (xy 203.977493 -9.028243) (xy 204.09882 -8.870667) (xy 204.226316 -8.71804)
			(xy 204.359779 -8.570603) (xy 204.498997 -8.428588) (xy 204.643752 -8.29222) (xy 204.793814 -8.161714)
			(xy 204.948945 -8.037278) (xy 205.108902 -7.919108) (xy 205.273429 -7.807391) (xy 205.442268 -7.702303)
			(xy 205.615152 -7.60401) (xy 205.791806 -7.512668) (xy 205.971953 -7.428422) (xy 206.155306 -7.351404)
			(xy 206.341576 -7.281737) (xy 206.530469 -7.21953) (xy 206.721686 -7.164882) (xy 206.914924 -7.11788)
			(xy 207.109877 -7.078597) (xy 207.306239 -7.047095) (xy 207.503697 -7.023426) (xy 207.701941 -7.007625)
			(xy 207.900656 -6.999718) (xy 208.000092 -6.999224) (xy 230.000048 -6.999224) (xy 230.099484 -6.99972)
			(xy 230.298198 -7.007626) (xy 230.496441 -7.023427) (xy 230.693899 -7.047096) (xy 230.89026 -7.078597)
			(xy 231.085213 -7.117879) (xy 231.278451 -7.164881) (xy 231.469667 -7.219529) (xy 231.658559 -7.281735)
			(xy 231.844829 -7.351402) (xy 232.028182 -7.428419) (xy 232.208327 -7.512665) (xy 232.384982 -7.604006)
			(xy 232.557865 -7.702298) (xy 232.726703 -7.807386) (xy 232.891231 -7.919103) (xy 233.051186 -8.037272)
			(xy 233.206318 -8.161708) (xy 233.356379 -8.292212) (xy 233.501134 -8.42858) (xy 233.640352 -8.570594)
			(xy 233.773815 -8.718031) (xy 233.90131 -8.870658) (xy 234.022637 -9.028232) (xy 234.137603 -9.190506)
			(xy 234.246026 -9.357222) (xy 234.347736 -9.528116) (xy 234.442572 -9.70292) (xy 234.530383 -9.881355)
			(xy 234.61103 -10.06314) (xy 234.684387 -10.247988) (xy 234.750336 -10.435606) (xy 234.808775 -10.625698)
			(xy 234.85961 -10.817962) (xy 234.902761 -11.012096) (xy 234.938159 -11.207792) (xy 234.96575 -11.40474)
			(xy 234.985489 -11.60263) (xy 234.997344 -11.801148) (xy 235.001299 -11.99998) (xy 234.997344 -12.198812)
			(xy 234.985489 -12.39733) (xy 234.96575 -12.59522) (xy 234.938159 -12.792168) (xy 234.902761 -12.987864)
			(xy 234.85961 -13.181998) (xy 234.808775 -13.374262) (xy 234.750336 -13.564354) (xy 234.684387 -13.751972)
			(xy 234.61103 -13.93682) (xy 234.530383 -14.118605) (xy 234.442572 -14.29704) (xy 234.347736 -14.471844)
			(xy 234.246026 -14.642738) (xy 234.137603 -14.809454) (xy 234.022637 -14.971728) (xy 233.90131 -15.129302)
			(xy 233.773815 -15.281929) (xy 233.640352 -15.429366) (xy 233.501134 -15.57138) (xy 233.356379 -15.707748)
			(xy 233.206318 -15.838252) (xy 233.051186 -15.962688) (xy 232.891231 -16.080857) (xy 232.726703 -16.192574)
			(xy 232.557865 -16.297662) (xy 232.384982 -16.395954) (xy 232.208327 -16.487295) (xy 232.028182 -16.571541)
			(xy 231.844829 -16.648558) (xy 231.658559 -16.718225) (xy 231.469667 -16.780431) (xy 231.278451 -16.835079)
			(xy 231.085213 -16.882081) (xy 230.89026 -16.921363) (xy 230.693899 -16.952864) (xy 230.496441 -16.976533)
			(xy 230.298198 -16.992334) (xy 230.099484 -17.00024) (xy 230.000048 -17.000728) (xy 208.000092 -17.000728)
			(xy 207.900656 -17.000282) (xy 207.701941 -16.992375) (xy 207.503697 -16.976574) (xy 207.306239 -16.952905)
			(xy 207.109877 -16.921403) (xy 206.914924 -16.88212) (xy 206.721686 -16.835118) (xy 206.530469 -16.78047)
			(xy 206.341576 -16.718263) (xy 206.155306 -16.648596) (xy 205.971953 -16.571578) (xy 205.791806 -16.487332)
			(xy 205.615152 -16.39599) (xy 205.442268 -16.297697) (xy 205.273429 -16.192609) (xy 205.108902 -16.080892)
			(xy 204.948945 -15.962722) (xy 204.793814 -15.838286) (xy 204.643752 -15.70778) (xy 204.498997 -15.571412)
			(xy 204.359779 -15.429397) (xy 204.226316 -15.28196) (xy 204.09882 -15.129333) (xy 203.977493 -14.971757)
			(xy 203.862527 -14.809483) (xy 203.754103 -14.642767) (xy 203.652393 -14.471872) (xy 203.557557 -14.297068)
			(xy 203.469746 -14.118632) (xy 203.389099 -13.936846) (xy 203.315742 -13.751998) (xy 203.249792 -13.564379)
			(xy 203.191353 -13.374287) (xy 203.140519 -13.182021) (xy 203.097367 -12.987887) (xy 203.061969 -12.792191)
			(xy 203.034378 -12.595242) (xy 203.014639 -12.397351) (xy 203.002784 -12.198833) (xy 202.998829 -12)
			(xy 163.702371 -12) (xy 163.703494 -12.003756) (xy 163.72009 -12.088408) (xy 163.728413 -12.174268)
			(xy 163.728908 -12.2174) (xy 163.728433 -12.258502) (xy 163.720848 -12.340357) (xy 163.705743 -12.421162)
			(xy 163.683247 -12.500229) (xy 163.653551 -12.576883) (xy 163.616909 -12.65047) (xy 163.573634 -12.720362)
			(xy 163.524094 -12.785963) (xy 163.468713 -12.846713) (xy 163.407963 -12.902094) (xy 163.342362 -12.951634)
			(xy 163.27247 -12.994909) (xy 163.198883 -13.031551) (xy 163.122229 -13.061247) (xy 163.043162 -13.083743)
			(xy 162.962357 -13.098848) (xy 162.880502 -13.106433) (xy 162.8394 -13.106908) (xy 162.79634 -13.10644)
			(xy 162.710622 -13.098119) (xy 162.626109 -13.081554) (xy 162.543592 -13.056902) (xy 162.463843 -13.024392)
			(xy 162.387608 -12.984328) (xy 162.315601 -12.937087) (xy 162.248496 -12.883108) (xy 162.18692 -12.822899)
			(xy 162.131449 -12.757022) (xy 162.10661 -12.721844) (xy 162.099403 -12.712362) (xy 162.078593 -12.700839)
			(xy 162.066732 -12.699746) (xy 162.024246 -12.697463) (xy 161.939947 -12.685919) (xy 161.857135 -12.666377)
			(xy 161.776568 -12.639016) (xy 161.698983 -12.604085) (xy 161.625087 -12.561905) (xy 161.555558 -12.51286)
			(xy 161.491031 -12.4574) (xy 161.432095 -12.39603) (xy 161.379289 -12.329313) (xy 161.333096 -12.257857)
			(xy 161.293938 -12.182317) (xy 161.262174 -12.103382) (xy 161.238093 -12.021775) (xy 161.221915 -11.938241)
			(xy 161.213789 -11.853543) (xy 161.213292 -11.811) (xy 149.733 -11.811) (xy 149.733 -22.501606) (xy 149.733424 -22.511676)
			(xy 149.74114 -22.530279) (xy 149.747986 -22.537674) (xy 150.51532 -23.305008) (xy 150.52272 -23.31185)
			(xy 150.541318 -23.319576) (xy 150.551388 -23.319994) (xy 202.389994 -23.319994) (xy 202.423254 -23.320515)
			(xy 202.489205 -23.329201) (xy 202.553456 -23.346426) (xy 202.614908 -23.371894) (xy 202.672508 -23.40517)
			(xy 202.725268 -23.445682) (xy 202.74915 -23.468838) (xy 204.575156 -25.294844) (xy 204.598312 -25.318724)
			(xy 204.638818 -25.371488) (xy 204.672089 -25.429089) (xy 204.697553 -25.49054) (xy 204.714775 -25.554791)
			(xy 204.723461 -25.620741) (xy 204.724 -25.654) (xy 204.724 -44.995338) (xy 204.72443 -45.005405)
			(xy 204.732154 -45.023999) (xy 204.738986 -45.031406) (xy 205.316328 -45.608748) (xy 205.323726 -45.615596)
			(xy 205.342324 -45.623328) (xy 205.352396 -45.623734) (xy 212.598508 -45.623734) (xy 212.631768 -45.624256)
			(xy 212.697719 -45.632943) (xy 212.761971 -45.650168) (xy 212.823423 -45.675635) (xy 212.881024 -45.708908)
			(xy 212.933786 -45.749418) (xy 212.957664 -45.772578) (xy 214.509604 -47.324518) (xy 214.532763 -47.348397)
			(xy 214.573277 -47.401158) (xy 214.606553 -47.458758) (xy 214.632023 -47.52021) (xy 214.649251 -47.584462)
			(xy 214.657941 -47.650413) (xy 214.658448 -47.683674) (xy 214.658448 -64.802258) (xy 214.657929 -64.835519)
			(xy 214.649248 -64.901473) (xy 214.632028 -64.965728) (xy 214.606564 -65.027184) (xy 214.573293 -65.084789)
			(xy 214.532785 -65.137556) (xy 214.509604 -65.161414) (xy 213.167722 -66.503296) (xy 213.163912 -66.51244)
			(xy 213.146548 -66.552276) (xy 213.105139 -66.628681) (xy 213.056477 -66.700685) (xy 213.001026 -66.767601)
			(xy 212.939316 -66.828791) (xy 212.871932 -66.883673) (xy 212.799519 -66.931723) (xy 212.722766 -66.972483)
			(xy 212.642404 -67.005566) (xy 212.559199 -67.030655) (xy 212.473945 -67.047512) (xy 212.387453 -67.055976)
			(xy 212.344 -67.056508) (xy 212.343238 -67.056508) (xy 212.297698 -67.055905) (xy 212.207101 -67.046548)
			(xy 212.117932 -67.027988) (xy 212.031125 -67.000421) (xy 211.947586 -66.964133) (xy 211.868189 -66.919505)
			(xy 211.830666 -66.893694) (xy 211.824062 -66.889122) (xy 211.80933 -66.884296) (xy 211.60867 -66.884296)
			(xy 211.593938 -66.889122) (xy 211.587334 -66.893694) (xy 211.549749 -66.91953) (xy 211.47025 -66.964244)
			(xy 211.386591 -67.000583) (xy 211.29965 -67.028163) (xy 211.210342 -67.046695) (xy 211.119606 -67.055984)
			(xy 211.074 -67.056508) (xy 211.028397 -67.055941) (xy 210.937666 -67.046635) (xy 210.848362 -67.028101)
			(xy 210.761422 -67.000532) (xy 210.677757 -66.964218) (xy 210.598243 -66.919539) (xy 210.560666 -66.893694)
			(xy 210.554062 -66.889122) (xy 210.53933 -66.884296) (xy 210.347306 -66.884296) (xy 210.332066 -66.889122)
			(xy 210.325716 -66.893948) (xy 210.293201 -66.916959) (xy 210.224769 -66.957743) (xy 210.152964 -66.992245)
			(xy 210.078362 -67.020188) (xy 210.001561 -67.041348) (xy 209.923174 -67.055555) (xy 209.843832 -67.062697)
			(xy 209.804 -67.063112) (xy 209.764188 -67.062643) (xy 209.684887 -67.055479) (xy 209.606543 -67.041261)
			(xy 209.529782 -67.020102) (xy 209.455217 -66.992173) (xy 209.383445 -66.957696) (xy 209.315038 -66.916947)
			(xy 209.282538 -66.893948) (xy 209.275851 -66.889511) (xy 209.260586 -66.88459) (xy 209.252566 -66.884296)
			(xy 87.164164 -66.884296) (xy 87.154097 -66.884726) (xy 87.135501 -66.892449) (xy 87.128096 -66.899282)
			(xy 83.551168 -70.47621) (xy 102.272839 -70.47621) (xy 102.272839 -70.34343) (xy 102.280856 -70.210893)
			(xy 102.296861 -70.079082) (xy 102.320795 -69.948478) (xy 102.352571 -69.819557) (xy 102.392073 -69.69279)
			(xy 102.439158 -69.568639) (xy 102.493652 -69.447558) (xy 102.555357 -69.329988) (xy 102.624049 -69.216358)
			(xy 102.699476 -69.107083) (xy 102.781363 -69.002561) (xy 102.869412 -68.903174) (xy 102.963301 -68.809285)
			(xy 103.062688 -68.721236) (xy 103.167209 -68.639348) (xy 103.276484 -68.563921) (xy 103.390114 -68.495229)
			(xy 103.507684 -68.433524) (xy 103.628766 -68.379029) (xy 103.752916 -68.331945) (xy 103.879683 -68.292442)
			(xy 104.008604 -68.260666) (xy 104.139208 -68.236732) (xy 104.271019 -68.220727) (xy 104.403556 -68.212709)
			(xy 104.469946 -68.212208) (xy 104.4702 -68.212208) (xy 104.537259 -68.212753) (xy 104.671128 -68.220938)
			(xy 104.804248 -68.237271) (xy 104.936124 -68.261692) (xy 105.066266 -68.29411) (xy 105.194189 -68.334403)
			(xy 105.319416 -68.382423) (xy 105.441482 -68.43799) (xy 105.559932 -68.500898) (xy 105.674326 -68.570911)
			(xy 105.784236 -68.647771) (xy 105.889256 -68.73119) (xy 105.988992 -68.820858) (xy 106.083075 -68.916441)
			(xy 106.171154 -69.017584) (xy 106.252901 -69.12391) (xy 106.290872 -69.179186) (xy 106.297984 -69.1896)
			(xy 106.320082 -69.201538) (xy 106.42981 -69.201538) (xy 106.451908 -69.1896) (xy 106.45902 -69.179186)
			(xy 106.496972 -69.123886) (xy 106.578722 -69.017537) (xy 106.666808 -68.916373) (xy 106.7609 -68.820772)
			(xy 106.86065 -68.731088) (xy 106.965684 -68.647656) (xy 107.075612 -68.570786) (xy 107.190025 -68.500765)
			(xy 107.308495 -68.437855) (xy 107.430583 -68.382288) (xy 107.555833 -68.334272) (xy 107.683779 -68.293986)
			(xy 107.813945 -68.26158) (xy 107.945844 -68.237175) (xy 108.078987 -68.220861) (xy 108.212877 -68.212699)
			(xy 108.279946 -68.212208) (xy 108.346561 -68.21269) (xy 108.479549 -68.220738) (xy 108.611805 -68.236826)
			(xy 108.742843 -68.260895) (xy 108.872183 -68.292856) (xy 108.99935 -68.332592) (xy 109.123877 -68.379958)
			(xy 109.245307 -68.434779) (xy 109.363193 -68.496853) (xy 109.420406 -68.530978) (xy 109.42955 -68.536566)
			(xy 109.450632 -68.53936) (xy 109.532928 -68.515484) (xy 109.542922 -68.512001) (xy 109.559058 -68.498337)
			(xy 109.56417 -68.489068) (xy 109.58283 -68.45221) (xy 109.625989 -68.381762) (xy 109.675492 -68.315617)
			(xy 109.730913 -68.254346) (xy 109.791775 -68.198475) (xy 109.857554 -68.148486) (xy 109.927683 -68.10481)
			(xy 110.001559 -68.067822) (xy 110.078545 -68.037842) (xy 110.157978 -68.015126) (xy 110.239175 -67.999871)
			(xy 110.321437 -67.992208) (xy 110.362746 -67.991736) (xy 110.405062 -67.99221) (xy 110.489311 -68.000245)
			(xy 110.572415 -68.016248) (xy 110.653623 -68.040074) (xy 110.7322 -68.071508) (xy 110.807436 -68.110264)
			(xy 110.843314 -68.132706) (xy 110.851703 -68.137589) (xy 110.870746 -68.14126) (xy 110.889789 -68.137589)
			(xy 110.898178 -68.132706) (xy 110.93406 -68.110273) (xy 111.0093 -68.071533) (xy 111.087878 -68.040113)
			(xy 111.169085 -68.016295) (xy 111.252187 -68.000296) (xy 111.336432 -67.992261) (xy 111.42106 -67.992261)
			(xy 111.505305 -68.000296) (xy 111.588407 -68.016295) (xy 111.669614 -68.040113) (xy 111.748192 -68.071533)
			(xy 111.823432 -68.110273) (xy 111.859314 -68.132706) (xy 111.867703 -68.137589) (xy 111.886746 -68.14126)
			(xy 111.905789 -68.137589) (xy 111.914178 -68.132706) (xy 111.950069 -68.110288) (xy 112.025305 -68.07154)
			(xy 112.103881 -68.040112) (xy 112.185086 -68.016287) (xy 112.268187 -68.000282) (xy 112.352432 -67.99224)
			(xy 112.394746 -67.991736) (xy 112.435853 -67.992169) (xy 112.517717 -67.999757) (xy 112.598532 -68.014865)
			(xy 112.677609 -68.037364) (xy 112.754273 -68.067061) (xy 112.827871 -68.103704) (xy 112.897774 -68.146979)
			(xy 112.963387 -68.196519) (xy 113.024151 -68.251901) (xy 113.079547 -68.312651) (xy 113.129102 -68.378253)
			(xy 113.172394 -68.448146) (xy 113.209054 -68.521735) (xy 113.23877 -68.598392) (xy 113.261287 -68.677463)
			(xy 113.276414 -68.758274) (xy 113.284022 -68.840137) (xy 113.284508 -68.881244) (xy 113.28401 -68.923565)
			(xy 113.275935 -69.007823) (xy 113.25989 -69.090932) (xy 113.236022 -69.17214) (xy 113.204546 -69.250713)
			(xy 113.165747 -69.32594) (xy 113.143284 -69.361812) (xy 113.138384 -69.370188) (xy 113.134743 -69.389237)
			(xy 113.138412 -69.408281) (xy 113.143284 -69.416676) (xy 113.165741 -69.45255) (xy 113.20452 -69.527784)
			(xy 113.235984 -69.606359) (xy 113.259846 -69.687566) (xy 113.275894 -69.770671) (xy 113.28398 -69.854924)
			(xy 113.284508 -69.897244) (xy 113.28401 -69.939565) (xy 113.275935 -70.023823) (xy 113.25989 -70.106932)
			(xy 113.236022 -70.18814) (xy 113.204546 -70.266713) (xy 113.165747 -70.34194) (xy 113.143284 -70.377812)
			(xy 113.138384 -70.386188) (xy 113.134743 -70.405237) (xy 113.138412 -70.424281) (xy 113.143284 -70.432676)
			(xy 113.165741 -70.46855) (xy 113.169679 -70.47619) (xy 142.272999 -70.47619) (xy 142.272999 -70.34341)
			(xy 142.281016 -70.210873) (xy 142.297021 -70.079062) (xy 142.320956 -69.948457) (xy 142.352732 -69.819536)
			(xy 142.392235 -69.692769) (xy 142.439319 -69.568618) (xy 142.493814 -69.447536) (xy 142.55552 -69.329966)
			(xy 142.624212 -69.216336) (xy 142.69964 -69.107061) (xy 142.781528 -69.002539) (xy 142.869577 -68.903153)
			(xy 142.963467 -68.809264) (xy 143.062854 -68.721215) (xy 143.167377 -68.639328) (xy 143.276653 -68.563901)
			(xy 143.390283 -68.49521) (xy 143.507854 -68.433505) (xy 143.628936 -68.379011) (xy 143.753087 -68.331928)
			(xy 143.879855 -68.292427) (xy 144.008777 -68.260651) (xy 144.139381 -68.236718) (xy 144.271193 -68.220715)
			(xy 144.40373 -68.212699) (xy 144.47012 -68.212208) (xy 144.470374 -68.212208) (xy 144.537433 -68.212773)
			(xy 144.671301 -68.220957) (xy 144.804421 -68.237289) (xy 144.936297 -68.261708) (xy 145.066438 -68.294124)
			(xy 145.194361 -68.334416) (xy 145.319588 -68.382435) (xy 145.441654 -68.438) (xy 145.560104 -68.500906)
			(xy 145.674498 -68.570919) (xy 145.784409 -68.647777) (xy 145.889428 -68.731195) (xy 145.989165 -68.820862)
			(xy 146.083248 -68.916444) (xy 146.171327 -69.017586) (xy 146.253075 -69.123911) (xy 146.291046 -69.179186)
			(xy 146.298158 -69.1896) (xy 146.320256 -69.201538) (xy 146.429984 -69.201538) (xy 146.452082 -69.1896)
			(xy 146.459194 -69.179186) (xy 146.497159 -69.123904) (xy 146.578897 -69.017568) (xy 146.66697 -68.916415)
			(xy 146.761048 -68.820822) (xy 146.860781 -68.731145) (xy 146.965799 -68.647719) (xy 147.07571 -68.570853)
			(xy 147.190104 -68.500834) (xy 147.308556 -68.437923) (xy 147.430624 -68.382354) (xy 147.555855 -68.334334)
			(xy 147.683782 -68.294042) (xy 147.813928 -68.261627) (xy 147.945808 -68.237211) (xy 148.078933 -68.220884)
			(xy 148.212805 -68.212708) (xy 148.279866 -68.212208) (xy 148.28012 -68.212208) (xy 148.34651 -68.212678)
			(xy 148.479047 -68.220696) (xy 148.610858 -68.236702) (xy 148.741462 -68.260637) (xy 148.870383 -68.292414)
			(xy 148.99715 -68.331918) (xy 149.1213 -68.379003) (xy 149.242381 -68.433498) (xy 149.359951 -68.495204)
			(xy 149.473581 -68.563897) (xy 149.582855 -68.639324) (xy 149.687377 -68.721212) (xy 149.786763 -68.809262)
			(xy 149.880652 -68.903152) (xy 149.9687 -69.002539) (xy 150.050587 -69.107061) (xy 150.126014 -69.216336)
			(xy 150.194706 -69.329966) (xy 150.256411 -69.447537) (xy 150.310905 -69.568618) (xy 150.357989 -69.692769)
			(xy 150.397491 -69.819537) (xy 150.429267 -69.948458) (xy 150.453201 -70.079062) (xy 150.469206 -70.210873)
			(xy 150.477223 -70.34341) (xy 150.477223 -70.476189) (xy 182.273209 -70.476189) (xy 182.273209 -70.343411)
			(xy 182.281226 -70.210875) (xy 182.297231 -70.079066) (xy 182.321165 -69.948463) (xy 182.35294 -69.819543)
			(xy 182.392442 -69.692777) (xy 182.439526 -69.568627) (xy 182.49402 -69.447547) (xy 182.555724 -69.329978)
			(xy 182.624415 -69.216349) (xy 182.699842 -69.107075) (xy 182.781728 -69.002554) (xy 182.869776 -68.903169)
			(xy 182.963664 -68.80928) (xy 183.06305 -68.721232) (xy 183.16757 -68.639345) (xy 183.276844 -68.563919)
			(xy 183.390473 -68.495227) (xy 183.508042 -68.433522) (xy 183.629122 -68.379028) (xy 183.753271 -68.331944)
			(xy 183.880037 -68.292442) (xy 184.008957 -68.260666) (xy 184.13956 -68.236732) (xy 184.271369 -68.220727)
			(xy 184.403905 -68.212709) (xy 184.470294 -68.212208) (xy 184.470548 -68.212208) (xy 184.537608 -68.212714)
			(xy 184.671477 -68.220902) (xy 184.804598 -68.237238) (xy 184.936475 -68.261662) (xy 185.066617 -68.294083)
			(xy 185.19454 -68.334379) (xy 185.319768 -68.382402) (xy 185.441834 -68.437971) (xy 185.560284 -68.500881)
			(xy 185.674677 -68.570897) (xy 185.784588 -68.647759) (xy 185.889606 -68.731181) (xy 185.989343 -68.820851)
			(xy 186.083425 -68.916437) (xy 186.171503 -69.017581) (xy 186.253249 -69.123909) (xy 186.29122 -69.179186)
			(xy 186.298332 -69.1896) (xy 186.32043 -69.201538) (xy 186.430158 -69.201538) (xy 186.452256 -69.1896)
			(xy 186.459368 -69.179186) (xy 186.49735 -69.123916) (xy 186.579088 -69.01758) (xy 186.667159 -68.916427)
			(xy 186.761236 -68.820834) (xy 186.860968 -68.731157) (xy 186.965984 -68.64773) (xy 187.075894 -68.570864)
			(xy 187.190287 -68.500844) (xy 187.308737 -68.437933) (xy 187.430805 -68.382363) (xy 187.556034 -68.334342)
			(xy 187.68396 -68.294048) (xy 187.814105 -68.261632) (xy 187.945984 -68.237215) (xy 188.079108 -68.220887)
			(xy 188.212979 -68.212709) (xy 188.28004 -68.212208) (xy 188.280294 -68.212208) (xy 188.346684 -68.212667)
			(xy 188.479223 -68.220684) (xy 188.611036 -68.236689) (xy 188.741642 -68.260623) (xy 188.870565 -68.292399)
			(xy 188.997333 -68.331901) (xy 189.121486 -68.378986) (xy 189.242569 -68.433481) (xy 189.360141 -68.495187)
			(xy 189.473772 -68.563879) (xy 189.583049 -68.639307) (xy 189.687572 -68.721195) (xy 189.78696 -68.809245)
			(xy 189.880851 -68.903136) (xy 189.968901 -69.002523) (xy 190.050789 -69.107046) (xy 190.126218 -69.216323)
			(xy 190.19491 -69.329954) (xy 190.256617 -69.447526) (xy 190.311112 -69.568609) (xy 190.358197 -69.692761)
			(xy 190.397699 -69.81953) (xy 190.429476 -69.948452) (xy 190.453411 -70.079058) (xy 190.469416 -70.210871)
			(xy 190.477433 -70.34341) (xy 190.477433 -70.47619) (xy 190.469416 -70.608729) (xy 190.453411 -70.740542)
			(xy 190.429476 -70.871148) (xy 190.397699 -71.00007) (xy 190.358197 -71.126839) (xy 190.311112 -71.250991)
			(xy 190.256617 -71.372074) (xy 190.19491 -71.489646) (xy 190.126218 -71.603277) (xy 190.050789 -71.712554)
			(xy 189.968901 -71.817077) (xy 189.880851 -71.916464) (xy 189.78696 -72.010355) (xy 189.687572 -72.098405)
			(xy 189.583049 -72.180293) (xy 189.473772 -72.255721) (xy 189.360141 -72.324413) (xy 189.242569 -72.386119)
			(xy 189.121486 -72.440614) (xy 188.997333 -72.487699) (xy 188.870565 -72.527201) (xy 188.741642 -72.558977)
			(xy 188.611036 -72.582911) (xy 188.479223 -72.598916) (xy 188.346684 -72.606933) (xy 188.280294 -72.607424)
			(xy 188.28004 -72.607424) (xy 188.212979 -72.606957) (xy 188.079109 -72.598768) (xy 187.945986 -72.582431)
			(xy 187.814108 -72.558005) (xy 187.683965 -72.525583) (xy 187.556041 -72.485285) (xy 187.430813 -72.43726)
			(xy 187.308746 -72.381688) (xy 187.190296 -72.318775) (xy 187.075903 -72.248756) (xy 186.965993 -72.171891)
			(xy 186.860975 -72.088466) (xy 186.761239 -71.998793) (xy 186.667158 -71.903204) (xy 186.579082 -71.802056)
			(xy 186.497337 -71.695724) (xy 186.459368 -71.640446) (xy 186.452256 -71.630032) (xy 186.430158 -71.618094)
			(xy 186.32043 -71.618094) (xy 186.298332 -71.630032) (xy 186.29122 -71.640446) (xy 186.253257 -71.695729)
			(xy 186.171517 -71.802065) (xy 186.083444 -71.903217) (xy 185.989366 -71.998809) (xy 185.889632 -72.088485)
			(xy 185.784614 -72.171911) (xy 185.674703 -72.248777) (xy 185.560309 -72.318795) (xy 185.441857 -72.381706)
			(xy 185.319789 -72.437275) (xy 185.194558 -72.485295) (xy 185.066632 -72.525588) (xy 184.936486 -72.558003)
			(xy 184.804605 -72.582419) (xy 184.671481 -72.598746) (xy 184.537609 -72.606924) (xy 184.470548 -72.607424)
			(xy 184.470294 -72.607424) (xy 184.403905 -72.606891) (xy 184.271369 -72.598873) (xy 184.13956 -72.582868)
			(xy 184.008957 -72.558934) (xy 183.880037 -72.527158) (xy 183.753271 -72.487656) (xy 183.629122 -72.440572)
			(xy 183.508042 -72.386078) (xy 183.390473 -72.324373) (xy 183.276844 -72.255681) (xy 183.16757 -72.180255)
			(xy 183.06305 -72.098368) (xy 182.963664 -72.01032) (xy 182.869776 -71.916431) (xy 182.781728 -71.817046)
			(xy 182.699842 -71.712525) (xy 182.624415 -71.603251) (xy 182.555724 -71.489622) (xy 182.49402 -71.372053)
			(xy 182.439526 -71.250973) (xy 182.392442 -71.126823) (xy 182.35294 -71.000057) (xy 182.321165 -70.871137)
			(xy 182.297231 -70.740534) (xy 182.281226 -70.608725) (xy 182.273209 -70.476189) (xy 150.477223 -70.476189)
			(xy 150.477223 -70.47619) (xy 150.469206 -70.608727) (xy 150.453201 -70.740538) (xy 150.429267 -70.871142)
			(xy 150.397491 -71.000063) (xy 150.357989 -71.126831) (xy 150.310905 -71.250982) (xy 150.256411 -71.372063)
			(xy 150.194706 -71.489634) (xy 150.126014 -71.603264) (xy 150.050587 -71.712539) (xy 149.9687 -71.817061)
			(xy 149.880652 -71.916448) (xy 149.786763 -72.010338) (xy 149.687377 -72.098388) (xy 149.582855 -72.180276)
			(xy 149.473581 -72.255703) (xy 149.359951 -72.324396) (xy 149.242381 -72.386102) (xy 149.1213 -72.440597)
			(xy 148.99715 -72.487682) (xy 148.870383 -72.527186) (xy 148.741462 -72.558963) (xy 148.610858 -72.582898)
			(xy 148.479047 -72.598904) (xy 148.34651 -72.606922) (xy 148.28012 -72.607424) (xy 148.279866 -72.607424)
			(xy 148.212806 -72.606936) (xy 148.078935 -72.598749) (xy 147.945813 -72.582413) (xy 147.813936 -72.557989)
			(xy 147.683793 -72.525568) (xy 147.555869 -72.485271) (xy 147.430641 -72.437248) (xy 147.308574 -72.381677)
			(xy 147.190124 -72.318766) (xy 147.075731 -72.248748) (xy 146.96582 -72.171885) (xy 146.860802 -72.088461)
			(xy 146.761067 -71.998789) (xy 146.666985 -71.903201) (xy 146.578908 -71.802054) (xy 146.497164 -71.695724)
			(xy 146.459194 -71.640446) (xy 146.452082 -71.630032) (xy 146.429984 -71.618094) (xy 146.320256 -71.618094)
			(xy 146.298158 -71.630032) (xy 146.291046 -71.640446) (xy 146.253066 -71.695717) (xy 146.171327 -71.802053)
			(xy 146.083256 -71.903205) (xy 145.989178 -71.998797) (xy 145.889445 -72.088474) (xy 145.784429 -72.1719)
			(xy 145.674519 -72.248766) (xy 145.560126 -72.318785) (xy 145.441676 -72.381697) (xy 145.319608 -72.437267)
			(xy 145.194379 -72.485288) (xy 145.066454 -72.525581) (xy 144.936309 -72.557998) (xy 144.804429 -72.582415)
			(xy 144.671306 -72.598744) (xy 144.537435 -72.606923) (xy 144.470374 -72.607424) (xy 144.47012 -72.607424)
			(xy 144.40373 -72.606901) (xy 144.271193 -72.598885) (xy 144.139381 -72.582882) (xy 144.008777 -72.558949)
			(xy 143.879855 -72.527173) (xy 143.753087 -72.487672) (xy 143.628936 -72.440589) (xy 143.507854 -72.386095)
			(xy 143.390283 -72.32439) (xy 143.276653 -72.255699) (xy 143.167377 -72.180272) (xy 143.062854 -72.098385)
			(xy 142.963467 -72.010336) (xy 142.869577 -71.916447) (xy 142.781528 -71.817061) (xy 142.69964 -71.712539)
			(xy 142.624212 -71.603264) (xy 142.55552 -71.489634) (xy 142.493814 -71.372064) (xy 142.439319 -71.250982)
			(xy 142.392235 -71.126831) (xy 142.352732 -71.000064) (xy 142.320956 -70.871143) (xy 142.297021 -70.740538)
			(xy 142.281016 -70.608727) (xy 142.272999 -70.47619) (xy 113.169679 -70.47619) (xy 113.20452 -70.543784)
			(xy 113.235984 -70.622359) (xy 113.259846 -70.703566) (xy 113.275894 -70.786671) (xy 113.28398 -70.870924)
			(xy 113.284508 -70.913244) (xy 113.28401 -70.955565) (xy 113.275935 -71.039823) (xy 113.25989 -71.122932)
			(xy 113.236022 -71.20414) (xy 113.204546 -71.282713) (xy 113.165747 -71.35794) (xy 113.143284 -71.393812)
			(xy 113.138384 -71.402188) (xy 113.134743 -71.421237) (xy 113.138412 -71.440281) (xy 113.143284 -71.448676)
			(xy 113.165741 -71.48455) (xy 113.20452 -71.559784) (xy 113.235984 -71.638359) (xy 113.259846 -71.719566)
			(xy 113.275894 -71.802671) (xy 113.28398 -71.886924) (xy 113.284508 -71.929244) (xy 113.284076 -71.97034)
			(xy 113.27649 -72.05218) (xy 113.261386 -72.132972) (xy 113.238894 -72.212026) (xy 113.209205 -72.288669)
			(xy 113.172573 -72.362245) (xy 113.12931 -72.432129) (xy 113.079784 -72.497724) (xy 113.024418 -72.55847)
			(xy 112.963685 -72.61385) (xy 112.898102 -72.663391) (xy 112.828229 -72.706671) (xy 112.754661 -72.74332)
			(xy 112.678026 -72.773027) (xy 112.598977 -72.795538) (xy 112.518189 -72.810661) (xy 112.43635 -72.818266)
			(xy 112.395254 -72.818752) (xy 112.394746 -72.818752) (xy 112.352431 -72.818268) (xy 112.268182 -72.810233)
			(xy 112.185079 -72.794231) (xy 112.103871 -72.770407) (xy 112.025293 -72.738975) (xy 111.950057 -72.700222)
			(xy 111.914178 -72.677782) (xy 111.905789 -72.672899) (xy 111.886746 -72.669228) (xy 111.867703 -72.672899)
			(xy 111.859314 -72.677782) (xy 111.823432 -72.700215) (xy 111.748192 -72.738955) (xy 111.669614 -72.770375)
			(xy 111.588407 -72.794193) (xy 111.505305 -72.810192) (xy 111.42106 -72.818227) (xy 111.336432 -72.818227)
			(xy 111.252187 -72.810192) (xy 111.169085 -72.794193) (xy 111.087878 -72.770375) (xy 111.0093 -72.738955)
			(xy 110.93406 -72.700215) (xy 110.898178 -72.677782) (xy 110.889789 -72.672899) (xy 110.870746 -72.669228)
			(xy 110.851703 -72.672899) (xy 110.843314 -72.677782) (xy 110.807431 -72.700214) (xy 110.732192 -72.738958)
			(xy 110.653615 -72.770383) (xy 110.572408 -72.794205) (xy 110.489306 -72.810208) (xy 110.40506 -72.818248)
			(xy 110.362746 -72.818752) (xy 110.321736 -72.818307) (xy 110.240064 -72.81076) (xy 110.159434 -72.795726)
			(xy 110.08053 -72.773333) (xy 110.004023 -72.74377) (xy 109.930563 -72.70729) (xy 109.860773 -72.664201)
			(xy 109.795246 -72.614871) (xy 109.734539 -72.559717) (xy 109.679168 -72.499208) (xy 109.629603 -72.433859)
			(xy 109.586264 -72.364224) (xy 109.567472 -72.32777) (xy 109.567218 -72.327516) (xy 109.562054 -72.318376)
			(xy 109.545915 -72.304988) (xy 109.535976 -72.301608) (xy 109.464348 -72.281034) (xy 109.454008 -72.278644)
			(xy 109.433011 -72.281518) (xy 109.423708 -72.286622) (xy 109.366375 -72.320967) (xy 109.24821 -72.383438)
			(xy 109.126467 -72.438611) (xy 109.001595 -72.486281) (xy 108.874056 -72.526273) (xy 108.744322 -72.558439)
			(xy 108.612872 -72.58266) (xy 108.480194 -72.598845) (xy 108.346777 -72.606936) (xy 108.279946 -72.607424)
			(xy 108.212878 -72.606923) (xy 108.078991 -72.598751) (xy 107.945853 -72.582428) (xy 107.813957 -72.558015)
			(xy 107.683796 -72.525603) (xy 107.555854 -72.485313) (xy 107.430608 -72.437295) (xy 107.308524 -72.381727)
			(xy 107.190056 -72.318816) (xy 107.075645 -72.248797) (xy 106.965718 -72.171931) (xy 106.860684 -72.088503)
			(xy 106.760934 -71.998824) (xy 106.666839 -71.903228) (xy 106.57875 -71.802071) (xy 106.496994 -71.69573)
			(xy 106.45902 -71.640446) (xy 106.451908 -71.630032) (xy 106.42981 -71.618094) (xy 106.320082 -71.618094)
			(xy 106.297984 -71.630032) (xy 106.290872 -71.640446) (xy 106.252874 -71.695705) (xy 106.171137 -71.802041)
			(xy 106.083067 -71.903193) (xy 105.98899 -71.998786) (xy 105.889259 -72.088462) (xy 105.784244 -72.171889)
			(xy 105.674336 -72.248756) (xy 105.559944 -72.318775) (xy 105.441494 -72.381688) (xy 105.319428 -72.437258)
			(xy 105.1942 -72.48528) (xy 105.066275 -72.525575) (xy 104.936132 -72.557993) (xy 104.804253 -72.582412)
			(xy 104.671131 -72.598742) (xy 104.53726 -72.606922) (xy 104.4702 -72.607424) (xy 104.469946 -72.607424)
			(xy 104.403556 -72.606931) (xy 104.271019 -72.598913) (xy 104.139208 -72.582908) (xy 104.008604 -72.558974)
			(xy 103.879683 -72.527198) (xy 103.752916 -72.487695) (xy 103.628766 -72.440611) (xy 103.507684 -72.386116)
			(xy 103.390114 -72.324411) (xy 103.276484 -72.255719) (xy 103.167209 -72.180292) (xy 103.062688 -72.098404)
			(xy 102.963301 -72.010355) (xy 102.869412 -71.916466) (xy 102.781363 -71.817079) (xy 102.699476 -71.712557)
			(xy 102.624049 -71.603282) (xy 102.555357 -71.489652) (xy 102.493652 -71.372082) (xy 102.439158 -71.251001)
			(xy 102.392073 -71.12685) (xy 102.352571 -71.000083) (xy 102.320795 -70.871162) (xy 102.296861 -70.740558)
			(xy 102.280856 -70.608747) (xy 102.272839 -70.47621) (xy 83.551168 -70.47621) (xy 78.83525 -75.192128)
			(xy 78.81137 -75.215285) (xy 78.758607 -75.255793) (xy 78.701007 -75.289064) (xy 78.639555 -75.314529)
			(xy 78.575304 -75.331752) (xy 78.509354 -75.340437) (xy 78.476094 -75.340972) (xy 56.173878 -75.340972)
			(xy 56.140618 -75.340449) (xy 56.074668 -75.331761) (xy 56.010417 -75.314535) (xy 55.948966 -75.289067)
			(xy 55.891366 -75.255792) (xy 55.838605 -75.215282) (xy 55.814722 -75.192128) (xy 49.59858 -68.975986)
			(xy 49.591185 -68.969133) (xy 49.572586 -68.961393) (xy 49.562512 -68.961) (xy 39.862252 -68.961)
			(xy 39.852186 -68.961432) (xy 39.833594 -68.969159) (xy 39.826184 -68.975986) (xy 38.876986 -69.925184)
			(xy 38.870143 -69.932583) (xy 38.862426 -69.951182) (xy 38.862 -69.961252) (xy 38.862 -74.601578)
			(xy 38.862438 -74.611642) (xy 38.870172 -74.630226) (xy 38.876986 -74.637646) (xy 41.999351 -77.760011)
			(xy 61.960756 -77.760011) (xy 61.960756 -77.675289) (xy 61.968809 -77.590952) (xy 61.984843 -77.507762)
			(xy 62.008711 -77.426472) (xy 62.040199 -77.34782) (xy 62.079021 -77.272517) (xy 62.124824 -77.201245)
			(xy 62.177195 -77.134649) (xy 62.23566 -77.073334) (xy 62.299688 -77.017853) (xy 62.3687 -76.96871)
			(xy 62.44207 -76.92635) (xy 62.519135 -76.891155) (xy 62.599197 -76.863446) (xy 62.68153 -76.843472)
			(xy 62.765389 -76.831415) (xy 62.850014 -76.827384) (xy 62.934639 -76.831415) (xy 63.018498 -76.843472)
			(xy 63.100831 -76.863446) (xy 63.180893 -76.891155) (xy 63.257958 -76.92635) (xy 63.331328 -76.96871)
			(xy 63.40034 -77.017853) (xy 63.464368 -77.073334) (xy 63.522833 -77.134649) (xy 63.575204 -77.201245)
			(xy 63.621007 -77.272517) (xy 63.659829 -77.34782) (xy 63.691317 -77.426472) (xy 63.715185 -77.507762)
			(xy 63.731219 -77.590952) (xy 63.739272 -77.675289) (xy 63.739776 -77.71765) (xy 63.739272 -77.760011)
			(xy 101.960676 -77.760011) (xy 101.960676 -77.675289) (xy 101.968729 -77.590952) (xy 101.984763 -77.507762)
			(xy 102.008631 -77.426472) (xy 102.040119 -77.34782) (xy 102.078941 -77.272517) (xy 102.124744 -77.201245)
			(xy 102.177115 -77.134649) (xy 102.23558 -77.073334) (xy 102.299608 -77.017853) (xy 102.36862 -76.96871)
			(xy 102.44199 -76.92635) (xy 102.519055 -76.891155) (xy 102.599117 -76.863446) (xy 102.68145 -76.843472)
			(xy 102.765309 -76.831415) (xy 102.849934 -76.827384) (xy 102.934559 -76.831415) (xy 103.018418 -76.843472)
			(xy 103.100751 -76.863446) (xy 103.180813 -76.891155) (xy 103.257878 -76.92635) (xy 103.331248 -76.96871)
			(xy 103.40026 -77.017853) (xy 103.464288 -77.073334) (xy 103.522753 -77.134649) (xy 103.575124 -77.201245)
			(xy 103.620927 -77.272517) (xy 103.659749 -77.34782) (xy 103.691237 -77.426472) (xy 103.715105 -77.507762)
			(xy 103.731139 -77.590952) (xy 103.739192 -77.675289) (xy 103.739696 -77.71765) (xy 103.739192 -77.760011)
			(xy 141.96085 -77.760011) (xy 141.96085 -77.675289) (xy 141.968903 -77.590952) (xy 141.984937 -77.507762)
			(xy 142.008805 -77.426472) (xy 142.040293 -77.34782) (xy 142.079115 -77.272517) (xy 142.124918 -77.201245)
			(xy 142.177289 -77.134649) (xy 142.235754 -77.073334) (xy 142.299782 -77.017853) (xy 142.368794 -76.96871)
			(xy 142.442164 -76.92635) (xy 142.519229 -76.891155) (xy 142.599291 -76.863446) (xy 142.681624 -76.843472)
			(xy 142.765483 -76.831415) (xy 142.850108 -76.827384) (xy 142.934733 -76.831415) (xy 143.018592 -76.843472)
			(xy 143.100925 -76.863446) (xy 143.180987 -76.891155) (xy 143.258052 -76.92635) (xy 143.331422 -76.96871)
			(xy 143.400434 -77.017853) (xy 143.464462 -77.073334) (xy 143.522927 -77.134649) (xy 143.575298 -77.201245)
			(xy 143.621101 -77.272517) (xy 143.659923 -77.34782) (xy 143.691411 -77.426472) (xy 143.715279 -77.507762)
			(xy 143.731313 -77.590952) (xy 143.739366 -77.675289) (xy 143.73987 -77.71765) (xy 143.739366 -77.760011)
			(xy 181.961024 -77.760011) (xy 181.961024 -77.675289) (xy 181.969077 -77.590952) (xy 181.985111 -77.507762)
			(xy 182.008979 -77.426472) (xy 182.040467 -77.34782) (xy 182.079289 -77.272517) (xy 182.125092 -77.201245)
			(xy 182.177463 -77.134649) (xy 182.235928 -77.073334) (xy 182.299956 -77.017853) (xy 182.368968 -76.96871)
			(xy 182.442338 -76.92635) (xy 182.519403 -76.891155) (xy 182.599465 -76.863446) (xy 182.681798 -76.843472)
			(xy 182.765657 -76.831415) (xy 182.850282 -76.827384) (xy 182.934907 -76.831415) (xy 183.018766 -76.843472)
			(xy 183.101099 -76.863446) (xy 183.181161 -76.891155) (xy 183.258226 -76.92635) (xy 183.331596 -76.96871)
			(xy 183.400608 -77.017853) (xy 183.464636 -77.073334) (xy 183.523101 -77.134649) (xy 183.575472 -77.201245)
			(xy 183.621275 -77.272517) (xy 183.660097 -77.34782) (xy 183.691585 -77.426472) (xy 183.715453 -77.507762)
			(xy 183.731487 -77.590952) (xy 183.73954 -77.675289) (xy 183.740044 -77.71765) (xy 183.73954 -77.760011)
			(xy 183.731487 -77.844348) (xy 183.715453 -77.927538) (xy 183.691585 -78.008828) (xy 183.660097 -78.08748)
			(xy 183.621275 -78.162783) (xy 183.575472 -78.234055) (xy 183.523101 -78.300651) (xy 183.464636 -78.361966)
			(xy 183.400608 -78.417447) (xy 183.331596 -78.46659) (xy 183.258226 -78.50895) (xy 183.181161 -78.544145)
			(xy 183.101099 -78.571854) (xy 183.018766 -78.591828) (xy 182.934907 -78.603885) (xy 182.850282 -78.607917)
			(xy 182.765657 -78.603885) (xy 182.681798 -78.591828) (xy 182.599465 -78.571854) (xy 182.519403 -78.544145)
			(xy 182.442338 -78.50895) (xy 182.368968 -78.46659) (xy 182.299956 -78.417447) (xy 182.235928 -78.361966)
			(xy 182.177463 -78.300651) (xy 182.125092 -78.234055) (xy 182.079289 -78.162783) (xy 182.040467 -78.08748)
			(xy 182.008979 -78.008828) (xy 181.985111 -77.927538) (xy 181.969077 -77.844348) (xy 181.961024 -77.760011)
			(xy 143.739366 -77.760011) (xy 143.731313 -77.844348) (xy 143.715279 -77.927538) (xy 143.691411 -78.008828)
			(xy 143.659923 -78.08748) (xy 143.621101 -78.162783) (xy 143.575298 -78.234055) (xy 143.522927 -78.300651)
			(xy 143.464462 -78.361966) (xy 143.400434 -78.417447) (xy 143.331422 -78.46659) (xy 143.258052 -78.50895)
			(xy 143.180987 -78.544145) (xy 143.100925 -78.571854) (xy 143.018592 -78.591828) (xy 142.934733 -78.603885)
			(xy 142.850108 -78.607917) (xy 142.765483 -78.603885) (xy 142.681624 -78.591828) (xy 142.599291 -78.571854)
			(xy 142.519229 -78.544145) (xy 142.442164 -78.50895) (xy 142.368794 -78.46659) (xy 142.299782 -78.417447)
			(xy 142.235754 -78.361966) (xy 142.177289 -78.300651) (xy 142.124918 -78.234055) (xy 142.079115 -78.162783)
			(xy 142.040293 -78.08748) (xy 142.008805 -78.008828) (xy 141.984937 -77.927538) (xy 141.968903 -77.844348)
			(xy 141.96085 -77.760011) (xy 103.739192 -77.760011) (xy 103.731139 -77.844348) (xy 103.715105 -77.927538)
			(xy 103.691237 -78.008828) (xy 103.659749 -78.08748) (xy 103.620927 -78.162783) (xy 103.575124 -78.234055)
			(xy 103.522753 -78.300651) (xy 103.464288 -78.361966) (xy 103.40026 -78.417447) (xy 103.331248 -78.46659)
			(xy 103.257878 -78.50895) (xy 103.180813 -78.544145) (xy 103.100751 -78.571854) (xy 103.018418 -78.591828)
			(xy 102.934559 -78.603885) (xy 102.849934 -78.607917) (xy 102.765309 -78.603885) (xy 102.68145 -78.591828)
			(xy 102.599117 -78.571854) (xy 102.519055 -78.544145) (xy 102.44199 -78.50895) (xy 102.36862 -78.46659)
			(xy 102.299608 -78.417447) (xy 102.23558 -78.361966) (xy 102.177115 -78.300651) (xy 102.124744 -78.234055)
			(xy 102.078941 -78.162783) (xy 102.040119 -78.08748) (xy 102.008631 -78.008828) (xy 101.984763 -77.927538)
			(xy 101.968729 -77.844348) (xy 101.960676 -77.760011) (xy 63.739272 -77.760011) (xy 63.731219 -77.844348)
			(xy 63.715185 -77.927538) (xy 63.691317 -78.008828) (xy 63.659829 -78.08748) (xy 63.621007 -78.162783)
			(xy 63.575204 -78.234055) (xy 63.522833 -78.300651) (xy 63.464368 -78.361966) (xy 63.40034 -78.417447)
			(xy 63.331328 -78.46659) (xy 63.257958 -78.50895) (xy 63.180893 -78.544145) (xy 63.100831 -78.571854)
			(xy 63.018498 -78.591828) (xy 62.934639 -78.603885) (xy 62.850014 -78.607917) (xy 62.765389 -78.603885)
			(xy 62.68153 -78.591828) (xy 62.599197 -78.571854) (xy 62.519135 -78.544145) (xy 62.44207 -78.50895)
			(xy 62.3687 -78.46659) (xy 62.299688 -78.417447) (xy 62.23566 -78.361966) (xy 62.177195 -78.300651)
			(xy 62.124824 -78.234055) (xy 62.079021 -78.162783) (xy 62.040199 -78.08748) (xy 62.008711 -78.008828)
			(xy 61.984843 -77.927538) (xy 61.968809 -77.844348) (xy 61.960756 -77.760011) (xy 41.999351 -77.760011)
			(xy 47.028354 -82.789014) (xy 47.035751 -82.795861) (xy 47.054351 -82.803589) (xy 47.064422 -82.804)
			(xy 149.098 -82.804) (xy 149.13126 -82.804521) (xy 149.19721 -82.813209) (xy 149.261461 -82.830434)
			(xy 149.322912 -82.855903) (xy 149.380511 -82.889179) (xy 149.433271 -82.929692) (xy 149.457156 -82.952844)
			(xy 157.294326 -90.790014) (xy 157.301722 -90.796866) (xy 157.320321 -90.804604) (xy 157.330394 -90.805)
		)
		(stroke
			(width 0)
			(type solid)
		)
		(fill yes)
		(layer "In4.Cu")
		(net "P3V3_AUX")
	)
	(gr_poly
		(pts
			(xy 221.756224 -145.98396) (xy 221.766291 -145.983531) (xy 221.784886 -145.975806) (xy 221.792292 -145.968974)
			(xy 222.733616 -145.02765) (xy 222.740464 -145.020253) (xy 222.748193 -145.001654) (xy 222.748602 -144.991582)
			(xy 222.748602 -144.282414) (xy 222.74826 -144.272883) (xy 222.741388 -144.255108) (xy 222.728481 -144.241088)
			(xy 222.711334 -144.232772) (xy 222.701866 -144.231614) (xy 222.633396 -144.225687) (xy 222.497246 -144.206835)
			(xy 222.362431 -144.180055) (xy 222.229412 -144.145438) (xy 222.098645 -144.103105) (xy 221.970576 -144.053198)
			(xy 221.845644 -143.995889) (xy 221.724277 -143.931374) (xy 221.606889 -143.859874) (xy 221.493882 -143.781633)
			(xy 221.385642 -143.696919) (xy 221.282541 -143.606021) (xy 221.18493 -143.509251) (xy 221.093144 -143.40694)
			(xy 221.007497 -143.299438) (xy 220.928281 -143.187112) (xy 220.855767 -143.070347) (xy 220.790205 -142.949543)
			(xy 220.731817 -142.825111) (xy 220.680804 -142.697479) (xy 220.63734 -142.567083) (xy 220.601574 -142.434369)
			(xy 220.573629 -142.299791) (xy 220.553599 -142.163809) (xy 220.541554 -142.026889) (xy 220.537534 -141.889498)
			(xy 220.541554 -141.752108) (xy 220.5536 -141.615188) (xy 220.573629 -141.479206) (xy 220.601575 -141.344628)
			(xy 220.637341 -141.211914) (xy 220.680805 -141.081518) (xy 220.731818 -140.953886) (xy 220.790206 -140.829455)
			(xy 220.855769 -140.70865) (xy 220.928282 -140.591885) (xy 221.007498 -140.479559) (xy 221.093146 -140.372057)
			(xy 221.184932 -140.269746) (xy 221.282543 -140.172977) (xy 221.385645 -140.082079) (xy 221.493884 -139.997365)
			(xy 221.606891 -139.919124) (xy 221.72428 -139.847624) (xy 221.845647 -139.78311) (xy 221.970579 -139.725801)
			(xy 222.098648 -139.675894) (xy 222.229415 -139.633561) (xy 222.362434 -139.598945) (xy 222.497249 -139.572165)
			(xy 222.633399 -139.553313) (xy 222.701866 -139.547346) (xy 222.711323 -139.546178) (xy 222.728432 -139.537821)
			(xy 222.741326 -139.52381) (xy 222.748237 -139.506067) (xy 222.748602 -139.496546) (xy 222.748602 -120.246648)
			(xy 222.748169 -120.236582) (xy 222.740442 -120.217991) (xy 222.733616 -120.21058) (xy 221.963996 -119.44096)
			(xy 221.9566 -119.434108) (xy 221.938002 -119.426365) (xy 221.927928 -119.425974) (xy 177.772314 -119.425974)
			(xy 177.761095 -119.426569) (xy 177.740787 -119.436114) (xy 177.726438 -119.453366) (xy 177.723038 -119.464074)
			(xy 177.698654 -119.559324) (xy 177.696348 -119.570372) (xy 177.700471 -119.592532) (xy 177.713697 -119.610784)
			(xy 177.723292 -119.616728) (xy 177.723546 -119.616728) (xy 177.77655 -119.646354) (xy 177.878908 -119.711698)
			(xy 177.976674 -119.783734) (xy 178.06941 -119.862139) (xy 178.156701 -119.946562) (xy 178.23816 -120.036628)
			(xy 178.31342 -120.131933) (xy 178.382147 -120.232052) (xy 178.444033 -120.336539) (xy 178.498802 -120.444925)
			(xy 178.546209 -120.556727) (xy 178.586042 -120.671447) (xy 178.618125 -120.78857) (xy 178.642312 -120.907575)
			(xy 178.658498 -121.02793) (xy 178.666608 -121.149097) (xy 178.667156 -121.209816) (xy 178.666649 -121.270543)
			(xy 178.658536 -121.391727) (xy 178.642348 -121.512098) (xy 178.618156 -121.631119) (xy 178.586068 -121.748258)
			(xy 178.546228 -121.862993) (xy 178.498813 -121.97481) (xy 178.444036 -122.083211) (xy 178.382141 -122.18771)
			(xy 178.313404 -122.287843) (xy 178.238132 -122.38316) (xy 178.156662 -122.473238) (xy 178.069358 -122.557672)
			(xy 177.976609 -122.636086) (xy 177.878829 -122.708131) (xy 177.776456 -122.773484) (xy 177.669946 -122.831853)
			(xy 177.559776 -122.882977) (xy 177.446436 -122.926629) (xy 177.330435 -122.962613) (xy 177.212289 -122.990769)
			(xy 177.092526 -123.01097) (xy 176.971681 -123.023127) (xy 176.850294 -123.027186) (xy 176.728907 -123.023127)
			(xy 176.608062 -123.01097) (xy 176.488299 -122.990769) (xy 176.370153 -122.962613) (xy 176.254152 -122.926629)
			(xy 176.140812 -122.882977) (xy 176.030642 -122.831853) (xy 175.924132 -122.773484) (xy 175.821759 -122.708131)
			(xy 175.723979 -122.636086) (xy 175.63123 -122.557672) (xy 175.543926 -122.473238) (xy 175.462456 -122.38316)
			(xy 175.387184 -122.287843) (xy 175.318447 -122.18771) (xy 175.256552 -122.083211) (xy 175.201775 -121.97481)
			(xy 175.15436 -121.862993) (xy 175.11452 -121.748258) (xy 175.082432 -121.631119) (xy 175.05824 -121.512098)
			(xy 175.042052 -121.391727) (xy 175.033939 -121.270543) (xy 175.033432 -121.209816) (xy 175.033928 -121.149096)
			(xy 175.042038 -121.027926) (xy 175.058224 -120.907569) (xy 175.082414 -120.788562) (xy 175.114498 -120.671436)
			(xy 175.154334 -120.556715) (xy 175.201744 -120.444911) (xy 175.256516 -120.336524) (xy 175.318405 -120.232037)
			(xy 175.387136 -120.131917) (xy 175.4624 -120.036612) (xy 175.543862 -119.946547) (xy 175.631159 -119.862124)
			(xy 175.723899 -119.783721) (xy 175.821669 -119.711688) (xy 175.924033 -119.646346) (xy 175.977042 -119.616728)
			(xy 175.977296 -119.616728) (xy 175.986836 -119.610742) (xy 175.999977 -119.592483) (xy 176.004131 -119.570374)
			(xy 176.001934 -119.559324) (xy 175.97755 -119.464074) (xy 175.97418 -119.453353) (xy 175.95984 -119.436085)
			(xy 175.9395 -119.426593) (xy 175.928274 -119.425974) (xy 170.152314 -119.425974) (xy 170.141095 -119.426569)
			(xy 170.120787 -119.436114) (xy 170.106438 -119.453366) (xy 170.103038 -119.464074) (xy 170.078654 -119.559324)
			(xy 170.076348 -119.570372) (xy 170.080471 -119.592532) (xy 170.093697 -119.610784) (xy 170.103292 -119.616728)
			(xy 170.103546 -119.616728) (xy 170.15655 -119.646354) (xy 170.258908 -119.711698) (xy 170.356674 -119.783734)
			(xy 170.44941 -119.862139) (xy 170.536701 -119.946562) (xy 170.61816 -120.036628) (xy 170.69342 -120.131933)
			(xy 170.762147 -120.232052) (xy 170.824033 -120.336539) (xy 170.878802 -120.444925) (xy 170.926209 -120.556727)
			(xy 170.966042 -120.671447) (xy 170.998125 -120.78857) (xy 171.022312 -120.907575) (xy 171.038498 -121.02793)
			(xy 171.046608 -121.149097) (xy 171.047156 -121.209816) (xy 171.046649 -121.270543) (xy 171.038536 -121.391727)
			(xy 171.022348 -121.512098) (xy 170.998156 -121.631119) (xy 170.966068 -121.748258) (xy 170.926228 -121.862993)
			(xy 170.878813 -121.97481) (xy 170.824036 -122.083211) (xy 170.762141 -122.18771) (xy 170.693404 -122.287843)
			(xy 170.618132 -122.38316) (xy 170.536662 -122.473238) (xy 170.449358 -122.557672) (xy 170.356609 -122.636086)
			(xy 170.258829 -122.708131) (xy 170.156456 -122.773484) (xy 170.049946 -122.831853) (xy 169.939776 -122.882977)
			(xy 169.826436 -122.926629) (xy 169.710435 -122.962613) (xy 169.592289 -122.990769) (xy 169.472526 -123.01097)
			(xy 169.351681 -123.023127) (xy 169.230294 -123.027186) (xy 169.108907 -123.023127) (xy 168.988062 -123.01097)
			(xy 168.868299 -122.990769) (xy 168.750153 -122.962613) (xy 168.634152 -122.926629) (xy 168.520812 -122.882977)
			(xy 168.410642 -122.831853) (xy 168.304132 -122.773484) (xy 168.201759 -122.708131) (xy 168.103979 -122.636086)
			(xy 168.01123 -122.557672) (xy 167.923926 -122.473238) (xy 167.842456 -122.38316) (xy 167.767184 -122.287843)
			(xy 167.698447 -122.18771) (xy 167.636552 -122.083211) (xy 167.581775 -121.97481) (xy 167.53436 -121.862993)
			(xy 167.49452 -121.748258) (xy 167.462432 -121.631119) (xy 167.43824 -121.512098) (xy 167.422052 -121.391727)
			(xy 167.413939 -121.270543) (xy 167.413432 -121.209816) (xy 167.413928 -121.149096) (xy 167.422038 -121.027926)
			(xy 167.438224 -120.907569) (xy 167.462414 -120.788562) (xy 167.494498 -120.671436) (xy 167.534334 -120.556715)
			(xy 167.581744 -120.444911) (xy 167.636516 -120.336524) (xy 167.698405 -120.232037) (xy 167.767136 -120.131917)
			(xy 167.8424 -120.036612) (xy 167.923862 -119.946547) (xy 168.011159 -119.862124) (xy 168.103899 -119.783721)
			(xy 168.201669 -119.711688) (xy 168.304033 -119.646346) (xy 168.357042 -119.616728) (xy 168.357296 -119.616728)
			(xy 168.366836 -119.610742) (xy 168.379977 -119.592483) (xy 168.384131 -119.570374) (xy 168.381934 -119.559324)
			(xy 168.35755 -119.464074) (xy 168.35418 -119.453353) (xy 168.33984 -119.436085) (xy 168.3195 -119.426593)
			(xy 168.308274 -119.425974) (xy 137.77214 -119.425974) (xy 137.760918 -119.426564) (xy 137.7406 -119.436104)
			(xy 137.726243 -119.453358) (xy 137.722864 -119.464074) (xy 137.69848 -119.559324) (xy 137.696174 -119.570371)
			(xy 137.700298 -119.59253) (xy 137.713527 -119.610777) (xy 137.723118 -119.616728) (xy 137.723372 -119.616728)
			(xy 137.776365 -119.646363) (xy 137.878702 -119.711724) (xy 137.976446 -119.783773) (xy 138.069161 -119.862188)
			(xy 138.156433 -119.946619) (xy 138.237873 -120.036689) (xy 138.313116 -120.131996) (xy 138.381827 -120.232115)
			(xy 138.443699 -120.336598) (xy 138.498456 -120.44498) (xy 138.545854 -120.556776) (xy 138.585681 -120.671488)
			(xy 138.617759 -120.788603) (xy 138.641945 -120.907599) (xy 138.658131 -121.027944) (xy 138.666245 -121.149102)
			(xy 138.666728 -121.209816) (xy 138.666221 -121.270535) (xy 138.65811 -121.391701) (xy 138.641924 -121.512056)
			(xy 138.617735 -121.63106) (xy 138.585652 -121.748183) (xy 138.545817 -121.862901) (xy 138.498409 -121.974703)
			(xy 138.443639 -122.083089) (xy 138.381753 -122.187574) (xy 138.313025 -122.287692) (xy 138.237764 -122.382996)
			(xy 138.156306 -122.473061) (xy 138.069013 -122.557484) (xy 137.976277 -122.635887) (xy 137.878511 -122.707922)
			(xy 137.776152 -122.773265) (xy 137.669657 -122.831626) (xy 137.559502 -122.882743) (xy 137.446179 -122.926389)
			(xy 137.330194 -122.962368) (xy 137.212064 -122.99052) (xy 137.092318 -123.010718) (xy 136.97149 -123.022874)
			(xy 136.85012 -123.026932) (xy 136.72875 -123.022874) (xy 136.607922 -123.010718) (xy 136.488176 -122.99052)
			(xy 136.370046 -122.962368) (xy 136.254061 -122.926389) (xy 136.140738 -122.882743) (xy 136.030583 -122.831626)
			(xy 135.924088 -122.773265) (xy 135.821729 -122.707922) (xy 135.723963 -122.635887) (xy 135.631227 -122.557484)
			(xy 135.543934 -122.473061) (xy 135.462476 -122.382996) (xy 135.387215 -122.287692) (xy 135.318487 -122.187574)
			(xy 135.256601 -122.083089) (xy 135.201831 -121.974703) (xy 135.154423 -121.862901) (xy 135.114588 -121.748183)
			(xy 135.082505 -121.63106) (xy 135.058316 -121.512056) (xy 135.04213 -121.391701) (xy 135.034019 -121.270535)
			(xy 135.033512 -121.209816) (xy 135.034018 -121.149102) (xy 135.042127 -121.027944) (xy 135.058307 -120.907598)
			(xy 135.082489 -120.788602) (xy 135.114564 -120.671486) (xy 135.154387 -120.556774) (xy 135.201783 -120.444977)
			(xy 135.256539 -120.336594) (xy 135.31841 -120.232111) (xy 135.387121 -120.131992) (xy 135.462364 -120.036685)
			(xy 135.543805 -119.946617) (xy 135.631078 -119.862187) (xy 135.723794 -119.783775) (xy 135.821541 -119.711729)
			(xy 135.92388 -119.646372) (xy 135.976868 -119.616728) (xy 135.977122 -119.616728) (xy 135.986659 -119.61074)
			(xy 135.999793 -119.59248) (xy 136.003944 -119.570375) (xy 136.00176 -119.559324) (xy 135.977376 -119.464074)
			(xy 135.974007 -119.45335) (xy 135.959668 -119.436075) (xy 135.939328 -119.426573) (xy 135.9281 -119.425974)
			(xy 130.15214 -119.425974) (xy 130.140918 -119.426564) (xy 130.1206 -119.436104) (xy 130.106243 -119.453358)
			(xy 130.102864 -119.464074) (xy 130.07848 -119.559324) (xy 130.076174 -119.570371) (xy 130.080298 -119.59253)
			(xy 130.093527 -119.610777) (xy 130.103118 -119.616728) (xy 130.103372 -119.616728) (xy 130.156365 -119.646363)
			(xy 130.258702 -119.711724) (xy 130.356446 -119.783773) (xy 130.449161 -119.862188) (xy 130.536433 -119.946619)
			(xy 130.617873 -120.036689) (xy 130.693116 -120.131996) (xy 130.761827 -120.232115) (xy 130.823699 -120.336598)
			(xy 130.878456 -120.44498) (xy 130.925854 -120.556776) (xy 130.965681 -120.671488) (xy 130.997759 -120.788603)
			(xy 131.021945 -120.907599) (xy 131.038131 -121.027944) (xy 131.046245 -121.149102) (xy 131.046728 -121.209816)
			(xy 131.046221 -121.270535) (xy 131.03811 -121.391701) (xy 131.021924 -121.512056) (xy 130.997735 -121.63106)
			(xy 130.965652 -121.748183) (xy 130.925817 -121.862901) (xy 130.878409 -121.974703) (xy 130.823639 -122.083089)
			(xy 130.761753 -122.187574) (xy 130.693025 -122.287692) (xy 130.617764 -122.382996) (xy 130.536306 -122.473061)
			(xy 130.449013 -122.557484) (xy 130.356277 -122.635887) (xy 130.258511 -122.707922) (xy 130.156152 -122.773265)
			(xy 130.049657 -122.831626) (xy 129.939502 -122.882743) (xy 129.826179 -122.926389) (xy 129.710194 -122.962368)
			(xy 129.592064 -122.99052) (xy 129.472318 -123.010718) (xy 129.35149 -123.022874) (xy 129.23012 -123.026932)
			(xy 129.10875 -123.022874) (xy 128.987922 -123.010718) (xy 128.868176 -122.99052) (xy 128.750046 -122.962368)
			(xy 128.634061 -122.926389) (xy 128.520738 -122.882743) (xy 128.410583 -122.831626) (xy 128.304088 -122.773265)
			(xy 128.201729 -122.707922) (xy 128.103963 -122.635887) (xy 128.011227 -122.557484) (xy 127.923934 -122.473061)
			(xy 127.842476 -122.382996) (xy 127.767215 -122.287692) (xy 127.698487 -122.187574) (xy 127.636601 -122.083089)
			(xy 127.581831 -121.974703) (xy 127.534423 -121.862901) (xy 127.494588 -121.748183) (xy 127.462505 -121.63106)
			(xy 127.438316 -121.512056) (xy 127.42213 -121.391701) (xy 127.414019 -121.270535) (xy 127.413512 -121.209816)
			(xy 127.414018 -121.149102) (xy 127.422127 -121.027944) (xy 127.438307 -120.907598) (xy 127.462489 -120.788602)
			(xy 127.494564 -120.671486) (xy 127.534387 -120.556774) (xy 127.581783 -120.444977) (xy 127.636539 -120.336594)
			(xy 127.69841 -120.232111) (xy 127.767121 -120.131992) (xy 127.842364 -120.036685) (xy 127.923805 -119.946617)
			(xy 128.011078 -119.862187) (xy 128.103794 -119.783775) (xy 128.201541 -119.711729) (xy 128.30388 -119.646372)
			(xy 128.356868 -119.616728) (xy 128.357122 -119.616728) (xy 128.366659 -119.61074) (xy 128.379793 -119.59248)
			(xy 128.383944 -119.570375) (xy 128.38176 -119.559324) (xy 128.357376 -119.464074) (xy 128.354007 -119.45335)
			(xy 128.339668 -119.436075) (xy 128.319328 -119.426573) (xy 128.3081 -119.425974) (xy 97.771966 -119.425974)
			(xy 97.76074 -119.426559) (xy 97.740413 -119.436094) (xy 97.726047 -119.453349) (xy 97.72269 -119.464074)
			(xy 97.698306 -119.559324) (xy 97.696001 -119.570374) (xy 97.700122 -119.592537) (xy 97.713341 -119.610797)
			(xy 97.722944 -119.616728) (xy 97.723198 -119.616728) (xy 97.776208 -119.646343) (xy 97.87857 -119.711687)
			(xy 97.976338 -119.783721) (xy 98.069077 -119.862126) (xy 98.156372 -119.946549) (xy 98.237832 -120.036615)
			(xy 98.313095 -120.13192) (xy 98.381824 -120.23204) (xy 98.443713 -120.336527) (xy 98.498483 -120.444914)
			(xy 98.545892 -120.556718) (xy 98.585727 -120.671439) (xy 98.617811 -120.788564) (xy 98.641999 -120.907571)
			(xy 98.658185 -121.027927) (xy 98.666296 -121.149096) (xy 98.666808 -121.209816) (xy 98.666301 -121.270543)
			(xy 98.658188 -121.391727) (xy 98.642 -121.512098) (xy 98.617808 -121.631119) (xy 98.58572 -121.748258)
			(xy 98.54588 -121.862993) (xy 98.498465 -121.97481) (xy 98.443688 -122.083211) (xy 98.381793 -122.18771)
			(xy 98.313056 -122.287843) (xy 98.237784 -122.38316) (xy 98.156314 -122.473238) (xy 98.06901 -122.557672)
			(xy 97.976261 -122.636086) (xy 97.878481 -122.708131) (xy 97.776108 -122.773484) (xy 97.669598 -122.831853)
			(xy 97.559428 -122.882977) (xy 97.446088 -122.926629) (xy 97.330087 -122.962613) (xy 97.211941 -122.990769)
			(xy 97.092178 -123.01097) (xy 96.971333 -123.023127) (xy 96.849946 -123.027186) (xy 96.728559 -123.023127)
			(xy 96.607714 -123.01097) (xy 96.487951 -122.990769) (xy 96.369805 -122.962613) (xy 96.253804 -122.926629)
			(xy 96.140464 -122.882977) (xy 96.030294 -122.831853) (xy 95.923784 -122.773484) (xy 95.821411 -122.708131)
			(xy 95.723631 -122.636086) (xy 95.630882 -122.557672) (xy 95.543578 -122.473238) (xy 95.462108 -122.38316)
			(xy 95.386836 -122.287843) (xy 95.318099 -122.18771) (xy 95.256204 -122.083211) (xy 95.201427 -121.97481)
			(xy 95.154012 -121.862993) (xy 95.114172 -121.748258) (xy 95.082084 -121.631119) (xy 95.057892 -121.512098)
			(xy 95.041704 -121.391727) (xy 95.033591 -121.270543) (xy 95.033084 -121.209816) (xy 95.03358 -121.149095)
			(xy 95.04169 -121.027925) (xy 95.057876 -120.907568) (xy 95.082065 -120.78856) (xy 95.114148 -120.671433)
			(xy 95.153984 -120.556712) (xy 95.201393 -120.444907) (xy 95.256164 -120.336518) (xy 95.318053 -120.23203)
			(xy 95.386782 -120.131909) (xy 95.462046 -120.036602) (xy 95.543507 -119.946535) (xy 95.630802 -119.862111)
			(xy 95.723542 -119.783706) (xy 95.821311 -119.71167) (xy 95.923673 -119.646326) (xy 95.976694 -119.616728)
			(xy 95.976948 -119.616728) (xy 95.986496 -119.610746) (xy 95.99965 -119.592488) (xy 96.003807 -119.570371)
			(xy 96.001586 -119.559324) (xy 95.977202 -119.464074) (xy 95.973834 -119.453347) (xy 95.959497 -119.436065)
			(xy 95.939156 -119.426553) (xy 95.927926 -119.425974) (xy 90.151966 -119.425974) (xy 90.14074 -119.426559)
			(xy 90.120413 -119.436094) (xy 90.106047 -119.453349) (xy 90.10269 -119.464074) (xy 90.078306 -119.559324)
			(xy 90.076001 -119.570374) (xy 90.080122 -119.592537) (xy 90.093341 -119.610797) (xy 90.102944 -119.616728)
			(xy 90.103198 -119.616728) (xy 90.156208 -119.646343) (xy 90.25857 -119.711687) (xy 90.356338 -119.783721)
			(xy 90.449077 -119.862126) (xy 90.536372 -119.946549) (xy 90.617832 -120.036615) (xy 90.693095 -120.13192)
			(xy 90.761824 -120.23204) (xy 90.823713 -120.336527) (xy 90.878483 -120.444914) (xy 90.925892 -120.556718)
			(xy 90.965727 -120.671439) (xy 90.997811 -120.788564) (xy 91.021999 -120.907571) (xy 91.038185 -121.027927)
			(xy 91.046296 -121.149096) (xy 91.046808 -121.209816) (xy 91.046301 -121.270543) (xy 91.038188 -121.391727)
			(xy 91.022 -121.512098) (xy 90.997808 -121.631119) (xy 90.96572 -121.748258) (xy 90.92588 -121.862993)
			(xy 90.878465 -121.97481) (xy 90.823688 -122.083211) (xy 90.761793 -122.18771) (xy 90.693056 -122.287843)
			(xy 90.617784 -122.38316) (xy 90.536314 -122.473238) (xy 90.44901 -122.557672) (xy 90.356261 -122.636086)
			(xy 90.258481 -122.708131) (xy 90.156108 -122.773484) (xy 90.049598 -122.831853) (xy 89.939428 -122.882977)
			(xy 89.826088 -122.926629) (xy 89.710087 -122.962613) (xy 89.591941 -122.990769) (xy 89.472178 -123.01097)
			(xy 89.351333 -123.023127) (xy 89.229946 -123.027186) (xy 89.108559 -123.023127) (xy 88.987714 -123.01097)
			(xy 88.867951 -122.990769) (xy 88.749805 -122.962613) (xy 88.633804 -122.926629) (xy 88.520464 -122.882977)
			(xy 88.410294 -122.831853) (xy 88.303784 -122.773484) (xy 88.201411 -122.708131) (xy 88.103631 -122.636086)
			(xy 88.010882 -122.557672) (xy 87.923578 -122.473238) (xy 87.842108 -122.38316) (xy 87.766836 -122.287843)
			(xy 87.698099 -122.18771) (xy 87.636204 -122.083211) (xy 87.581427 -121.97481) (xy 87.534012 -121.862993)
			(xy 87.494172 -121.748258) (xy 87.462084 -121.631119) (xy 87.437892 -121.512098) (xy 87.421704 -121.391727)
			(xy 87.413591 -121.270543) (xy 87.413084 -121.209816) (xy 87.41358 -121.149095) (xy 87.42169 -121.027925)
			(xy 87.437876 -120.907568) (xy 87.462065 -120.78856) (xy 87.494148 -120.671433) (xy 87.533984 -120.556712)
			(xy 87.581393 -120.444907) (xy 87.636164 -120.336518) (xy 87.698053 -120.23203) (xy 87.766782 -120.131909)
			(xy 87.842046 -120.036602) (xy 87.923507 -119.946535) (xy 88.010802 -119.862111) (xy 88.103542 -119.783706)
			(xy 88.201311 -119.71167) (xy 88.303673 -119.646326) (xy 88.356694 -119.616728) (xy 88.356948 -119.616728)
			(xy 88.366496 -119.610746) (xy 88.37965 -119.592488) (xy 88.383807 -119.570371) (xy 88.381586 -119.559324)
			(xy 88.357202 -119.464074) (xy 88.353834 -119.453347) (xy 88.339497 -119.436065) (xy 88.319156 -119.426553)
			(xy 88.307926 -119.425974) (xy 57.772046 -119.425974) (xy 57.760823 -119.426563) (xy 57.740503 -119.436102)
			(xy 57.726144 -119.453355) (xy 57.72277 -119.464074) (xy 57.698386 -119.559324) (xy 57.69608 -119.570371)
			(xy 57.700204 -119.592529) (xy 57.713435 -119.610775) (xy 57.723024 -119.616728) (xy 57.723278 -119.616728)
			(xy 57.776289 -119.646343) (xy 57.878651 -119.711686) (xy 57.976421 -119.78372) (xy 58.069161 -119.862123)
			(xy 58.156456 -119.946547) (xy 58.237918 -120.036612) (xy 58.313182 -120.131917) (xy 58.381911 -120.232037)
			(xy 58.4438 -120.336524) (xy 58.498572 -120.444912) (xy 58.545981 -120.556716) (xy 58.585817 -120.671437)
			(xy 58.617901 -120.788563) (xy 58.64209 -120.90757) (xy 58.658275 -121.027926) (xy 58.666386 -121.149096)
			(xy 58.666888 -121.209816) (xy 58.666381 -121.270543) (xy 58.658268 -121.391727) (xy 58.64208 -121.512098)
			(xy 58.617888 -121.631119) (xy 58.5858 -121.748258) (xy 58.54596 -121.862993) (xy 58.498545 -121.97481)
			(xy 58.443768 -122.083211) (xy 58.381873 -122.18771) (xy 58.313136 -122.287843) (xy 58.237864 -122.38316)
			(xy 58.156394 -122.473238) (xy 58.06909 -122.557672) (xy 57.976341 -122.636086) (xy 57.878561 -122.708131)
			(xy 57.776188 -122.773484) (xy 57.669678 -122.831853) (xy 57.559508 -122.882977) (xy 57.446168 -122.926629)
			(xy 57.330167 -122.962613) (xy 57.212021 -122.990769) (xy 57.092258 -123.01097) (xy 56.971413 -123.023127)
			(xy 56.850026 -123.027186) (xy 56.728639 -123.023127) (xy 56.607794 -123.01097) (xy 56.488031 -122.990769)
			(xy 56.369885 -122.962613) (xy 56.253884 -122.926629) (xy 56.140544 -122.882977) (xy 56.030374 -122.831853)
			(xy 55.923864 -122.773484) (xy 55.821491 -122.708131) (xy 55.723711 -122.636086) (xy 55.630962 -122.557672)
			(xy 55.543658 -122.473238) (xy 55.462188 -122.38316) (xy 55.386916 -122.287843) (xy 55.318179 -122.18771)
			(xy 55.256284 -122.083211) (xy 55.201507 -121.97481) (xy 55.154092 -121.862993) (xy 55.114252 -121.748258)
			(xy 55.082164 -121.631119) (xy 55.057972 -121.512098) (xy 55.041784 -121.391727) (xy 55.033671 -121.270543)
			(xy 55.033164 -121.209816) (xy 55.03366 -121.149095) (xy 55.04177 -121.027925) (xy 55.057956 -120.907567)
			(xy 55.082144 -120.788559) (xy 55.114228 -120.671432) (xy 55.154063 -120.55671) (xy 55.201472 -120.444905)
			(xy 55.256243 -120.336516) (xy 55.318131 -120.232027) (xy 55.38686 -120.131905) (xy 55.462123 -120.036598)
			(xy 55.543584 -119.946531) (xy 55.630879 -119.862105) (xy 55.723618 -119.783699) (xy 55.821386 -119.711663)
			(xy 55.923748 -119.646317) (xy 55.976774 -119.616728) (xy 55.977028 -119.616728) (xy 55.986564 -119.610739)
			(xy 55.999696 -119.59248) (xy 56.003847 -119.570375) (xy 56.001666 -119.559324) (xy 55.977282 -119.464074)
			(xy 55.973913 -119.453349) (xy 55.959575 -119.436073) (xy 55.939234 -119.426568) (xy 55.928006 -119.425974)
			(xy 50.152046 -119.425974) (xy 50.140823 -119.426563) (xy 50.120503 -119.436102) (xy 50.106144 -119.453355)
			(xy 50.10277 -119.464074) (xy 50.078386 -119.559324) (xy 50.07608 -119.570371) (xy 50.080204 -119.592529)
			(xy 50.093435 -119.610775) (xy 50.103024 -119.616728) (xy 50.103278 -119.616728) (xy 50.156289 -119.646343)
			(xy 50.258651 -119.711686) (xy 50.356421 -119.78372) (xy 50.449161 -119.862123) (xy 50.536456 -119.946547)
			(xy 50.617918 -120.036612) (xy 50.693182 -120.131917) (xy 50.761911 -120.232037) (xy 50.8238 -120.336524)
			(xy 50.878572 -120.444912) (xy 50.925981 -120.556716) (xy 50.965817 -120.671437) (xy 50.997901 -120.788563)
			(xy 51.02209 -120.90757) (xy 51.038275 -121.027926) (xy 51.046386 -121.149096) (xy 51.046888 -121.209816)
			(xy 51.046381 -121.270543) (xy 51.038268 -121.391727) (xy 51.02208 -121.512098) (xy 50.997888 -121.631119)
			(xy 50.9658 -121.748258) (xy 50.92596 -121.862993) (xy 50.878545 -121.97481) (xy 50.823768 -122.083211)
			(xy 50.761873 -122.18771) (xy 50.693136 -122.287843) (xy 50.617864 -122.38316) (xy 50.536394 -122.473238)
			(xy 50.44909 -122.557672) (xy 50.356341 -122.636086) (xy 50.258561 -122.708131) (xy 50.156188 -122.773484)
			(xy 50.049678 -122.831853) (xy 49.939508 -122.882977) (xy 49.826168 -122.926629) (xy 49.710167 -122.962613)
			(xy 49.592021 -122.990769) (xy 49.472258 -123.01097) (xy 49.351413 -123.023127) (xy 49.230026 -123.027186)
			(xy 49.108639 -123.023127) (xy 48.987794 -123.01097) (xy 48.868031 -122.990769) (xy 48.749885 -122.962613)
			(xy 48.633884 -122.926629) (xy 48.520544 -122.882977) (xy 48.410374 -122.831853) (xy 48.303864 -122.773484)
			(xy 48.201491 -122.708131) (xy 48.103711 -122.636086) (xy 48.010962 -122.557672) (xy 47.923658 -122.473238)
			(xy 47.842188 -122.38316) (xy 47.766916 -122.287843) (xy 47.698179 -122.18771) (xy 47.636284 -122.083211)
			(xy 47.581507 -121.97481) (xy 47.534092 -121.862993) (xy 47.494252 -121.748258) (xy 47.462164 -121.631119)
			(xy 47.437972 -121.512098) (xy 47.421784 -121.391727) (xy 47.413671 -121.270543) (xy 47.413164 -121.209816)
			(xy 47.41366 -121.149095) (xy 47.42177 -121.027925) (xy 47.437956 -120.907567) (xy 47.462144 -120.788559)
			(xy 47.494228 -120.671432) (xy 47.534063 -120.55671) (xy 47.581472 -120.444905) (xy 47.636243 -120.336516)
			(xy 47.698131 -120.232027) (xy 47.76686 -120.131905) (xy 47.842123 -120.036598) (xy 47.923584 -119.946531)
			(xy 48.010879 -119.862105) (xy 48.103618 -119.783699) (xy 48.201386 -119.711663) (xy 48.303748 -119.646317)
			(xy 48.356774 -119.616728) (xy 48.357028 -119.616728) (xy 48.366564 -119.610739) (xy 48.379696 -119.59248)
			(xy 48.383847 -119.570375) (xy 48.381666 -119.559324) (xy 48.357282 -119.464074) (xy 48.353913 -119.453349)
			(xy 48.339575 -119.436073) (xy 48.319234 -119.426568) (xy 48.308006 -119.425974) (xy 41.33342 -119.425974)
			(xy 41.323369 -119.42648) (xy 41.304809 -119.434201) (xy 41.297352 -119.44096) (xy 40.019986 -120.718326)
			(xy 40.013134 -120.725722) (xy 40.005396 -120.744321) (xy 40.005 -120.754394) (xy 40.005 -126.492)
			(xy 44.966872 -126.492) (xy 44.970902 -126.407397) (xy 44.982956 -126.32356) (xy 45.002925 -126.241249)
			(xy 45.030627 -126.161209) (xy 45.065812 -126.084164) (xy 45.108162 -126.010813) (xy 45.157292 -125.941819)
			(xy 45.212758 -125.877808) (xy 45.274058 -125.81936) (xy 45.340636 -125.767002) (xy 45.411889 -125.721211)
			(xy 45.487173 -125.6824) (xy 45.565805 -125.650921) (xy 45.647073 -125.627059) (xy 45.730241 -125.61103)
			(xy 45.814557 -125.60298) (xy 45.856906 -125.602492) (xy 45.857414 -125.602492) (xy 45.903746 -125.603096)
			(xy 45.995904 -125.612768) (xy 46.086558 -125.631964) (xy 46.174727 -125.660477) (xy 46.217332 -125.678692)
			(xy 46.227274 -125.682498) (xy 46.248538 -125.682498) (xy 46.25848 -125.678692) (xy 46.301082 -125.660468)
			(xy 46.38925 -125.631951) (xy 46.479906 -125.612759) (xy 46.572066 -125.6031) (xy 46.618398 -125.602492)
			(xy 46.618906 -125.602492) (xy 46.661254 -125.602996) (xy 46.745567 -125.611047) (xy 46.828733 -125.627077)
			(xy 46.909999 -125.650939) (xy 46.988629 -125.682418) (xy 47.06391 -125.721229) (xy 47.135161 -125.767019)
			(xy 47.201737 -125.819376) (xy 47.263034 -125.877823) (xy 47.318499 -125.941833) (xy 47.367627 -126.010825)
			(xy 47.409975 -126.084174) (xy 47.44516 -126.161217) (xy 47.472861 -126.241256) (xy 47.492829 -126.323565)
			(xy 47.504882 -126.407399) (xy 47.508913 -126.492) (xy 57.158872 -126.492) (xy 57.162902 -126.407397)
			(xy 57.174956 -126.32356) (xy 57.194925 -126.241249) (xy 57.222627 -126.161209) (xy 57.257812 -126.084164)
			(xy 57.300162 -126.010813) (xy 57.349292 -125.941819) (xy 57.404758 -125.877808) (xy 57.466058 -125.81936)
			(xy 57.532636 -125.767002) (xy 57.603889 -125.721211) (xy 57.679173 -125.6824) (xy 57.757805 -125.650921)
			(xy 57.839073 -125.627059) (xy 57.922241 -125.61103) (xy 58.006557 -125.60298) (xy 58.048906 -125.602492)
			(xy 58.049414 -125.602492) (xy 58.095746 -125.603096) (xy 58.187904 -125.612768) (xy 58.278558 -125.631964)
			(xy 58.366727 -125.660477) (xy 58.409332 -125.678692) (xy 58.419274 -125.682498) (xy 58.440538 -125.682498)
			(xy 58.45048 -125.678692) (xy 58.493082 -125.660468) (xy 58.58125 -125.631951) (xy 58.671906 -125.612759)
			(xy 58.764066 -125.6031) (xy 58.810398 -125.602492) (xy 58.810906 -125.602492) (xy 58.853254 -125.602996)
			(xy 58.937567 -125.611047) (xy 59.020733 -125.627077) (xy 59.101999 -125.650939) (xy 59.180629 -125.682418)
			(xy 59.25591 -125.721229) (xy 59.327161 -125.767019) (xy 59.393737 -125.819376) (xy 59.455034 -125.877823)
			(xy 59.510499 -125.941833) (xy 59.559627 -126.010825) (xy 59.601975 -126.084174) (xy 59.63716 -126.161217)
			(xy 59.664861 -126.241256) (xy 59.684829 -126.323565) (xy 59.696882 -126.407399) (xy 59.700913 -126.492)
			(xy 69.350872 -126.492) (xy 69.354902 -126.407397) (xy 69.366956 -126.32356) (xy 69.386925 -126.241249)
			(xy 69.414627 -126.161209) (xy 69.449812 -126.084164) (xy 69.492162 -126.010813) (xy 69.541292 -125.941819)
			(xy 69.596758 -125.877808) (xy 69.658058 -125.81936) (xy 69.724636 -125.767002) (xy 69.795889 -125.721211)
			(xy 69.871173 -125.6824) (xy 69.949805 -125.650921) (xy 70.031073 -125.627059) (xy 70.114241 -125.61103)
			(xy 70.198557 -125.60298) (xy 70.240906 -125.602492) (xy 70.241414 -125.602492) (xy 70.287746 -125.603096)
			(xy 70.379904 -125.612768) (xy 70.470558 -125.631964) (xy 70.558727 -125.660477) (xy 70.601332 -125.678692)
			(xy 70.611274 -125.682498) (xy 70.632538 -125.682498) (xy 70.64248 -125.678692) (xy 70.685082 -125.660468)
			(xy 70.77325 -125.631951) (xy 70.863906 -125.612759) (xy 70.956066 -125.6031) (xy 71.002398 -125.602492)
			(xy 71.002906 -125.602492) (xy 71.045254 -125.602996) (xy 71.129567 -125.611047) (xy 71.212733 -125.627077)
			(xy 71.293999 -125.650939) (xy 71.372629 -125.682418) (xy 71.44791 -125.721229) (xy 71.519161 -125.767019)
			(xy 71.585737 -125.819376) (xy 71.647034 -125.877823) (xy 71.702499 -125.941833) (xy 71.751627 -126.010825)
			(xy 71.793975 -126.084174) (xy 71.82916 -126.161217) (xy 71.856861 -126.241256) (xy 71.876829 -126.323565)
			(xy 71.888882 -126.407399) (xy 71.892913 -126.492) (xy 84.966772 -126.492) (xy 84.970802 -126.407396)
			(xy 84.982857 -126.323558) (xy 85.002826 -126.241246) (xy 85.030529 -126.161204) (xy 85.065715 -126.084159)
			(xy 85.108066 -126.010807) (xy 85.157198 -125.941813) (xy 85.212665 -125.877801) (xy 85.273966 -125.819352)
			(xy 85.340546 -125.766995) (xy 85.411801 -125.721204) (xy 85.487086 -125.682394) (xy 85.56572 -125.650916)
			(xy 85.646989 -125.627055) (xy 85.730159 -125.611028) (xy 85.814476 -125.602979) (xy 85.856826 -125.602492)
			(xy 85.857334 -125.602492) (xy 85.903665 -125.603124) (xy 85.995822 -125.612788) (xy 86.086476 -125.631976)
			(xy 86.174646 -125.66048) (xy 86.217252 -125.678692) (xy 86.227194 -125.682498) (xy 86.248458 -125.682498)
			(xy 86.2584 -125.678692) (xy 86.300999 -125.660461) (xy 86.389168 -125.631946) (xy 86.479825 -125.612756)
			(xy 86.571985 -125.603099) (xy 86.618318 -125.602492) (xy 86.618826 -125.602492) (xy 86.661174 -125.602997)
			(xy 86.745485 -125.61105) (xy 86.82865 -125.627081) (xy 86.909914 -125.650944) (xy 86.988542 -125.682424)
			(xy 87.063821 -125.721235) (xy 87.135071 -125.767026) (xy 87.201645 -125.819383) (xy 87.262941 -125.87783)
			(xy 87.318404 -125.941839) (xy 87.367531 -126.010831) (xy 87.409878 -126.08418) (xy 87.445061 -126.161222)
			(xy 87.472762 -126.241259) (xy 87.492729 -126.323567) (xy 87.504783 -126.407401) (xy 87.508813 -126.492)
			(xy 97.158772 -126.492) (xy 97.162802 -126.407396) (xy 97.174857 -126.323558) (xy 97.194826 -126.241246)
			(xy 97.222529 -126.161204) (xy 97.257715 -126.084159) (xy 97.300066 -126.010807) (xy 97.349198 -125.941813)
			(xy 97.404665 -125.877801) (xy 97.465966 -125.819352) (xy 97.532546 -125.766995) (xy 97.603801 -125.721204)
			(xy 97.679086 -125.682394) (xy 97.75772 -125.650916) (xy 97.838989 -125.627055) (xy 97.922159 -125.611028)
			(xy 98.006476 -125.602979) (xy 98.048826 -125.602492) (xy 98.049334 -125.602492) (xy 98.095665 -125.603124)
			(xy 98.187822 -125.612788) (xy 98.278476 -125.631976) (xy 98.366646 -125.66048) (xy 98.409252 -125.678692)
			(xy 98.419194 -125.682498) (xy 98.440458 -125.682498) (xy 98.4504 -125.678692) (xy 98.492999 -125.660461)
			(xy 98.581168 -125.631946) (xy 98.671825 -125.612756) (xy 98.763985 -125.603099) (xy 98.810318 -125.602492)
			(xy 98.810826 -125.602492) (xy 98.853174 -125.602997) (xy 98.937485 -125.61105) (xy 99.02065 -125.627081)
			(xy 99.101914 -125.650944) (xy 99.180542 -125.682424) (xy 99.255821 -125.721235) (xy 99.327071 -125.767026)
			(xy 99.393645 -125.819383) (xy 99.454941 -125.87783) (xy 99.510404 -125.941839) (xy 99.559531 -126.010831)
			(xy 99.601878 -126.08418) (xy 99.637061 -126.161222) (xy 99.664762 -126.241259) (xy 99.684729 -126.323567)
			(xy 99.696783 -126.407401) (xy 99.700813 -126.492) (xy 109.350772 -126.492) (xy 109.354802 -126.407396)
			(xy 109.366857 -126.323558) (xy 109.386826 -126.241246) (xy 109.414529 -126.161204) (xy 109.449715 -126.084159)
			(xy 109.492066 -126.010807) (xy 109.541198 -125.941813) (xy 109.596665 -125.877801) (xy 109.657966 -125.819352)
			(xy 109.724546 -125.766995) (xy 109.795801 -125.721204) (xy 109.871086 -125.682394) (xy 109.94972 -125.650916)
			(xy 110.030989 -125.627055) (xy 110.114159 -125.611028) (xy 110.198476 -125.602979) (xy 110.240826 -125.602492)
			(xy 110.241334 -125.602492) (xy 110.287665 -125.603124) (xy 110.379822 -125.612788) (xy 110.470476 -125.631976)
			(xy 110.558646 -125.66048) (xy 110.601252 -125.678692) (xy 110.611194 -125.682498) (xy 110.632458 -125.682498)
			(xy 110.6424 -125.678692) (xy 110.684999 -125.660461) (xy 110.773168 -125.631946) (xy 110.863825 -125.612756)
			(xy 110.955985 -125.603099) (xy 111.002318 -125.602492) (xy 111.002826 -125.602492) (xy 111.045174 -125.602997)
			(xy 111.129485 -125.61105) (xy 111.21265 -125.627081) (xy 111.293914 -125.650944) (xy 111.372542 -125.682424)
			(xy 111.447821 -125.721235) (xy 111.519071 -125.767026) (xy 111.585645 -125.819383) (xy 111.646941 -125.87783)
			(xy 111.702404 -125.941839) (xy 111.751531 -126.010831) (xy 111.793878 -126.08418) (xy 111.829061 -126.161222)
			(xy 111.856762 -126.241259) (xy 111.876729 -126.323567) (xy 111.888783 -126.407401) (xy 111.892813 -126.492)
			(xy 124.966988 -126.492) (xy 124.971018 -126.407399) (xy 124.983071 -126.323564) (xy 125.003039 -126.241255)
			(xy 125.030741 -126.161216) (xy 125.065925 -126.084173) (xy 125.108274 -126.010823) (xy 125.157403 -125.941831)
			(xy 125.212868 -125.877821) (xy 125.274166 -125.819373) (xy 125.340742 -125.767017) (xy 125.411994 -125.721227)
			(xy 125.487275 -125.682416) (xy 125.565905 -125.650937) (xy 125.647172 -125.627076) (xy 125.730338 -125.611047)
			(xy 125.814652 -125.602996) (xy 125.857 -125.602492) (xy 125.857508 -125.602492) (xy 125.90384 -125.603098)
			(xy 125.995998 -125.612769) (xy 126.086652 -125.631965) (xy 126.174821 -125.660477) (xy 126.217426 -125.678692)
			(xy 126.227368 -125.682498) (xy 126.248632 -125.682498) (xy 126.258574 -125.678692) (xy 126.301177 -125.66047)
			(xy 126.389344 -125.631952) (xy 126.48 -125.61276) (xy 126.57216 -125.6031) (xy 126.618492 -125.602492)
			(xy 126.619 -125.602492) (xy 126.661348 -125.602996) (xy 126.745662 -125.611047) (xy 126.828828 -125.627076)
			(xy 126.910095 -125.650937) (xy 126.988725 -125.682416) (xy 127.064006 -125.721227) (xy 127.135258 -125.767017)
			(xy 127.201834 -125.819373) (xy 127.263132 -125.877821) (xy 127.318597 -125.941831) (xy 127.367726 -126.010823)
			(xy 127.410075 -126.084173) (xy 127.445259 -126.161216) (xy 127.472961 -126.241255) (xy 127.492929 -126.323564)
			(xy 127.504982 -126.407399) (xy 127.509013 -126.492) (xy 137.158988 -126.492) (xy 137.163018 -126.407399)
			(xy 137.175071 -126.323564) (xy 137.195039 -126.241255) (xy 137.222741 -126.161216) (xy 137.257925 -126.084173)
			(xy 137.300274 -126.010823) (xy 137.349403 -125.941831) (xy 137.404868 -125.877821) (xy 137.466166 -125.819373)
			(xy 137.532742 -125.767017) (xy 137.603994 -125.721227) (xy 137.679275 -125.682416) (xy 137.757905 -125.650937)
			(xy 137.839172 -125.627076) (xy 137.922338 -125.611047) (xy 138.006652 -125.602996) (xy 138.049 -125.602492)
			(xy 138.049508 -125.602492) (xy 138.09584 -125.603098) (xy 138.187998 -125.612769) (xy 138.278652 -125.631965)
			(xy 138.366821 -125.660477) (xy 138.409426 -125.678692) (xy 138.419368 -125.682498) (xy 138.440632 -125.682498)
			(xy 138.450574 -125.678692) (xy 138.493177 -125.66047) (xy 138.581344 -125.631952) (xy 138.672 -125.61276)
			(xy 138.76416 -125.6031) (xy 138.810492 -125.602492) (xy 138.811 -125.602492) (xy 138.853348 -125.602996)
			(xy 138.937662 -125.611047) (xy 139.020828 -125.627076) (xy 139.102095 -125.650937) (xy 139.180725 -125.682416)
			(xy 139.256006 -125.721227) (xy 139.327258 -125.767017) (xy 139.393834 -125.819373) (xy 139.455132 -125.877821)
			(xy 139.510597 -125.941831) (xy 139.559726 -126.010823) (xy 139.602075 -126.084173) (xy 139.637259 -126.161216)
			(xy 139.664961 -126.241255) (xy 139.684929 -126.323564) (xy 139.696982 -126.407399) (xy 139.701013 -126.492)
			(xy 149.350988 -126.492) (xy 149.355018 -126.407399) (xy 149.367071 -126.323564) (xy 149.387039 -126.241255)
			(xy 149.414741 -126.161216) (xy 149.449925 -126.084173) (xy 149.492274 -126.010823) (xy 149.541403 -125.941831)
			(xy 149.596868 -125.877821) (xy 149.658166 -125.819373) (xy 149.724742 -125.767017) (xy 149.795994 -125.721227)
			(xy 149.871275 -125.682416) (xy 149.949905 -125.650937) (xy 150.031172 -125.627076) (xy 150.114338 -125.611047)
			(xy 150.198652 -125.602996) (xy 150.241 -125.602492) (xy 150.241508 -125.602492) (xy 150.28784 -125.603098)
			(xy 150.379998 -125.612769) (xy 150.470652 -125.631965) (xy 150.558821 -125.660477) (xy 150.601426 -125.678692)
			(xy 150.611368 -125.682498) (xy 150.632632 -125.682498) (xy 150.642574 -125.678692) (xy 150.685177 -125.66047)
			(xy 150.773344 -125.631952) (xy 150.864 -125.61276) (xy 150.95616 -125.6031) (xy 151.002492 -125.602492)
			(xy 151.003 -125.602492) (xy 151.045348 -125.602996) (xy 151.129662 -125.611047) (xy 151.212828 -125.627076)
			(xy 151.294095 -125.650937) (xy 151.372725 -125.682416) (xy 151.448006 -125.721227) (xy 151.519258 -125.767017)
			(xy 151.585834 -125.819373) (xy 151.647132 -125.877821) (xy 151.702597 -125.941831) (xy 151.751726 -126.010823)
			(xy 151.794075 -126.084173) (xy 151.829259 -126.161216) (xy 151.856961 -126.241255) (xy 151.876929 -126.323564)
			(xy 151.888982 -126.407399) (xy 151.893013 -126.492) (xy 164.967187 -126.492) (xy 164.971217 -126.407401)
			(xy 164.983271 -126.323567) (xy 165.003238 -126.241259) (xy 165.030939 -126.161222) (xy 165.066122 -126.08418)
			(xy 165.108469 -126.010831) (xy 165.157596 -125.941839) (xy 165.213059 -125.87783) (xy 165.274355 -125.819383)
			(xy 165.340929 -125.767026) (xy 165.412179 -125.721235) (xy 165.487458 -125.682424) (xy 165.566086 -125.650944)
			(xy 165.64735 -125.627081) (xy 165.730515 -125.61105) (xy 165.814826 -125.602997) (xy 165.857174 -125.602492)
			(xy 165.857682 -125.602492) (xy 165.904014 -125.603107) (xy 165.996171 -125.612776) (xy 166.086825 -125.631969)
			(xy 166.174994 -125.660478) (xy 166.2176 -125.678692) (xy 166.227542 -125.682498) (xy 166.248806 -125.682498)
			(xy 166.258748 -125.678692) (xy 166.301354 -125.660479) (xy 166.389521 -125.631959) (xy 166.480175 -125.612764)
			(xy 166.572334 -125.603101) (xy 166.618666 -125.602492) (xy 166.619174 -125.602492) (xy 166.661524 -125.602979)
			(xy 166.745841 -125.611028) (xy 166.829011 -125.627055) (xy 166.91028 -125.650916) (xy 166.988914 -125.682394)
			(xy 167.064199 -125.721204) (xy 167.135454 -125.766995) (xy 167.202034 -125.819352) (xy 167.263335 -125.877801)
			(xy 167.318802 -125.941813) (xy 167.367934 -126.010807) (xy 167.410285 -126.084159) (xy 167.445471 -126.161204)
			(xy 167.473174 -126.241246) (xy 167.493143 -126.323558) (xy 167.505198 -126.407396) (xy 167.509228 -126.492)
			(xy 177.159187 -126.492) (xy 177.163217 -126.407401) (xy 177.175271 -126.323567) (xy 177.195238 -126.241259)
			(xy 177.222939 -126.161222) (xy 177.258122 -126.08418) (xy 177.300469 -126.010831) (xy 177.349596 -125.941839)
			(xy 177.405059 -125.87783) (xy 177.466355 -125.819383) (xy 177.532929 -125.767026) (xy 177.604179 -125.721235)
			(xy 177.679458 -125.682424) (xy 177.758086 -125.650944) (xy 177.83935 -125.627081) (xy 177.922515 -125.61105)
			(xy 178.006826 -125.602997) (xy 178.049174 -125.602492) (xy 178.049682 -125.602492) (xy 178.096014 -125.603107)
			(xy 178.188171 -125.612776) (xy 178.278825 -125.631969) (xy 178.366994 -125.660478) (xy 178.4096 -125.678692)
			(xy 178.419542 -125.682498) (xy 178.440806 -125.682498) (xy 178.450748 -125.678692) (xy 178.493354 -125.660479)
			(xy 178.581521 -125.631959) (xy 178.672175 -125.612764) (xy 178.764334 -125.603101) (xy 178.810666 -125.602492)
			(xy 178.811174 -125.602492) (xy 178.853524 -125.602979) (xy 178.937841 -125.611028) (xy 179.021011 -125.627055)
			(xy 179.10228 -125.650916) (xy 179.180914 -125.682394) (xy 179.256199 -125.721204) (xy 179.327454 -125.766995)
			(xy 179.394034 -125.819352) (xy 179.455335 -125.877801) (xy 179.510802 -125.941813) (xy 179.559934 -126.010807)
			(xy 179.602285 -126.084159) (xy 179.637471 -126.161204) (xy 179.665174 -126.241246) (xy 179.685143 -126.323558)
			(xy 179.697198 -126.407396) (xy 179.701228 -126.492) (xy 189.351187 -126.492) (xy 189.355217 -126.407401)
			(xy 189.367271 -126.323567) (xy 189.387238 -126.241259) (xy 189.414939 -126.161222) (xy 189.450122 -126.08418)
			(xy 189.492469 -126.010831) (xy 189.541596 -125.941839) (xy 189.597059 -125.87783) (xy 189.658355 -125.819383)
			(xy 189.724929 -125.767026) (xy 189.796179 -125.721235) (xy 189.871458 -125.682424) (xy 189.950086 -125.650944)
			(xy 190.03135 -125.627081) (xy 190.114515 -125.61105) (xy 190.198826 -125.602997) (xy 190.241174 -125.602492)
			(xy 190.241682 -125.602492) (xy 190.288014 -125.603107) (xy 190.380171 -125.612776) (xy 190.470825 -125.631969)
			(xy 190.558994 -125.660478) (xy 190.6016 -125.678692) (xy 190.611542 -125.682498) (xy 190.632806 -125.682498)
			(xy 190.642748 -125.678692) (xy 190.685354 -125.660479) (xy 190.773521 -125.631959) (xy 190.864175 -125.612764)
			(xy 190.956334 -125.603101) (xy 191.002666 -125.602492) (xy 191.003174 -125.602492) (xy 191.045524 -125.602979)
			(xy 191.129841 -125.611028) (xy 191.213011 -125.627055) (xy 191.29428 -125.650916) (xy 191.372914 -125.682394)
			(xy 191.448199 -125.721204) (xy 191.519454 -125.766995) (xy 191.586034 -125.819352) (xy 191.647335 -125.877801)
			(xy 191.702802 -125.941813) (xy 191.751934 -126.010807) (xy 191.794285 -126.084159) (xy 191.829471 -126.161204)
			(xy 191.857174 -126.241246) (xy 191.877143 -126.323558) (xy 191.889198 -126.407396) (xy 191.893228 -126.492)
			(xy 191.889198 -126.576604) (xy 191.877143 -126.660442) (xy 191.857174 -126.742754) (xy 191.829471 -126.822796)
			(xy 191.794285 -126.899841) (xy 191.751934 -126.973193) (xy 191.702802 -127.042187) (xy 191.647335 -127.106199)
			(xy 191.586034 -127.164648) (xy 191.519454 -127.217005) (xy 191.448199 -127.262796) (xy 191.372914 -127.301606)
			(xy 191.29428 -127.333084) (xy 191.213011 -127.356945) (xy 191.129841 -127.372972) (xy 191.045524 -127.381021)
			(xy 191.003174 -127.381508) (xy 191.002666 -127.381508) (xy 190.956335 -127.380876) (xy 190.864178 -127.371212)
			(xy 190.773524 -127.352024) (xy 190.685354 -127.32352) (xy 190.642748 -127.305308) (xy 190.632806 -127.301502)
			(xy 190.611542 -127.301502) (xy 190.6016 -127.305308) (xy 190.559001 -127.323539) (xy 190.470832 -127.352054)
			(xy 190.380175 -127.371244) (xy 190.288015 -127.380901) (xy 190.241682 -127.381508) (xy 190.241174 -127.381508)
			(xy 190.198826 -127.381003) (xy 190.114515 -127.37295) (xy 190.03135 -127.356919) (xy 189.950086 -127.333056)
			(xy 189.871458 -127.301576) (xy 189.796179 -127.262765) (xy 189.724929 -127.216974) (xy 189.658355 -127.164617)
			(xy 189.597059 -127.10617) (xy 189.541596 -127.042161) (xy 189.492469 -126.973169) (xy 189.450122 -126.89982)
			(xy 189.414939 -126.822778) (xy 189.387238 -126.742741) (xy 189.367271 -126.660433) (xy 189.355217 -126.576599)
			(xy 189.351187 -126.492) (xy 179.701228 -126.492) (xy 179.697198 -126.576604) (xy 179.685143 -126.660442)
			(xy 179.665174 -126.742754) (xy 179.637471 -126.822796) (xy 179.602285 -126.899841) (xy 179.559934 -126.973193)
			(xy 179.510802 -127.042187) (xy 179.455335 -127.106199) (xy 179.394034 -127.164648) (xy 179.327454 -127.217005)
			(xy 179.256199 -127.262796) (xy 179.180914 -127.301606) (xy 179.10228 -127.333084) (xy 179.021011 -127.356945)
			(xy 178.937841 -127.372972) (xy 178.853524 -127.381021) (xy 178.811174 -127.381508) (xy 178.810666 -127.381508)
			(xy 178.764335 -127.380876) (xy 178.672178 -127.371212) (xy 178.581524 -127.352024) (xy 178.493354 -127.32352)
			(xy 178.450748 -127.305308) (xy 178.440806 -127.301502) (xy 178.419542 -127.301502) (xy 178.4096 -127.305308)
			(xy 178.367001 -127.323539) (xy 178.278832 -127.352054) (xy 178.188175 -127.371244) (xy 178.096015 -127.380901)
			(xy 178.049682 -127.381508) (xy 178.049174 -127.381508) (xy 178.006826 -127.381003) (xy 177.922515 -127.37295)
			(xy 177.83935 -127.356919) (xy 177.758086 -127.333056) (xy 177.679458 -127.301576) (xy 177.604179 -127.262765)
			(xy 177.532929 -127.216974) (xy 177.466355 -127.164617) (xy 177.405059 -127.10617) (xy 177.349596 -127.042161)
			(xy 177.300469 -126.973169) (xy 177.258122 -126.89982) (xy 177.222939 -126.822778) (xy 177.195238 -126.742741)
			(xy 177.175271 -126.660433) (xy 177.163217 -126.576599) (xy 177.159187 -126.492) (xy 167.509228 -126.492)
			(xy 167.505198 -126.576604) (xy 167.493143 -126.660442) (xy 167.473174 -126.742754) (xy 167.445471 -126.822796)
			(xy 167.410285 -126.899841) (xy 167.367934 -126.973193) (xy 167.318802 -127.042187) (xy 167.263335 -127.106199)
			(xy 167.202034 -127.164648) (xy 167.135454 -127.217005) (xy 167.064199 -127.262796) (xy 166.988914 -127.301606)
			(xy 166.91028 -127.333084) (xy 166.829011 -127.356945) (xy 166.745841 -127.372972) (xy 166.661524 -127.381021)
			(xy 166.619174 -127.381508) (xy 166.618666 -127.381508) (xy 166.572335 -127.380876) (xy 166.480178 -127.371212)
			(xy 166.389524 -127.352024) (xy 166.301354 -127.32352) (xy 166.258748 -127.305308) (xy 166.248806 -127.301502)
			(xy 166.227542 -127.301502) (xy 166.2176 -127.305308) (xy 166.175001 -127.323539) (xy 166.086832 -127.352054)
			(xy 165.996175 -127.371244) (xy 165.904015 -127.380901) (xy 165.857682 -127.381508) (xy 165.857174 -127.381508)
			(xy 165.814826 -127.381003) (xy 165.730515 -127.37295) (xy 165.64735 -127.356919) (xy 165.566086 -127.333056)
			(xy 165.487458 -127.301576) (xy 165.412179 -127.262765) (xy 165.340929 -127.216974) (xy 165.274355 -127.164617)
			(xy 165.213059 -127.10617) (xy 165.157596 -127.042161) (xy 165.108469 -126.973169) (xy 165.066122 -126.89982)
			(xy 165.030939 -126.822778) (xy 165.003238 -126.742741) (xy 164.983271 -126.660433) (xy 164.971217 -126.576599)
			(xy 164.967187 -126.492) (xy 151.893013 -126.492) (xy 151.888982 -126.576601) (xy 151.876929 -126.660436)
			(xy 151.856961 -126.742745) (xy 151.829259 -126.822784) (xy 151.794075 -126.899827) (xy 151.751726 -126.973177)
			(xy 151.702597 -127.042169) (xy 151.647132 -127.106179) (xy 151.585834 -127.164627) (xy 151.519258 -127.216983)
			(xy 151.448006 -127.262773) (xy 151.372725 -127.301584) (xy 151.294095 -127.333063) (xy 151.212828 -127.356924)
			(xy 151.129662 -127.372953) (xy 151.045348 -127.381004) (xy 151.003 -127.381508) (xy 151.002492 -127.381508)
			(xy 150.95616 -127.380902) (xy 150.864002 -127.371231) (xy 150.773348 -127.352035) (xy 150.685179 -127.323523)
			(xy 150.642574 -127.305308) (xy 150.632632 -127.301502) (xy 150.611368 -127.301502) (xy 150.601426 -127.305308)
			(xy 150.558823 -127.32353) (xy 150.470656 -127.352048) (xy 150.38 -127.37124) (xy 150.28784 -127.3809)
			(xy 150.241508 -127.381508) (xy 150.241 -127.381508) (xy 150.198652 -127.381004) (xy 150.114338 -127.372953)
			(xy 150.031172 -127.356924) (xy 149.949905 -127.333063) (xy 149.871275 -127.301584) (xy 149.795994 -127.262773)
			(xy 149.724742 -127.216983) (xy 149.658166 -127.164627) (xy 149.596868 -127.106179) (xy 149.541403 -127.042169)
			(xy 149.492274 -126.973177) (xy 149.449925 -126.899827) (xy 149.414741 -126.822784) (xy 149.387039 -126.742745)
			(xy 149.367071 -126.660436) (xy 149.355018 -126.576601) (xy 149.350988 -126.492) (xy 139.701013 -126.492)
			(xy 139.696982 -126.576601) (xy 139.684929 -126.660436) (xy 139.664961 -126.742745) (xy 139.637259 -126.822784)
			(xy 139.602075 -126.899827) (xy 139.559726 -126.973177) (xy 139.510597 -127.042169) (xy 139.455132 -127.106179)
			(xy 139.393834 -127.164627) (xy 139.327258 -127.216983) (xy 139.256006 -127.262773) (xy 139.180725 -127.301584)
			(xy 139.102095 -127.333063) (xy 139.020828 -127.356924) (xy 138.937662 -127.372953) (xy 138.853348 -127.381004)
			(xy 138.811 -127.381508) (xy 138.810492 -127.381508) (xy 138.76416 -127.380902) (xy 138.672002 -127.371231)
			(xy 138.581348 -127.352035) (xy 138.493179 -127.323523) (xy 138.450574 -127.305308) (xy 138.440632 -127.301502)
			(xy 138.419368 -127.301502) (xy 138.409426 -127.305308) (xy 138.366823 -127.32353) (xy 138.278656 -127.352048)
			(xy 138.188 -127.37124) (xy 138.09584 -127.3809) (xy 138.049508 -127.381508) (xy 138.049 -127.381508)
			(xy 138.006652 -127.381004) (xy 137.922338 -127.372953) (xy 137.839172 -127.356924) (xy 137.757905 -127.333063)
			(xy 137.679275 -127.301584) (xy 137.603994 -127.262773) (xy 137.532742 -127.216983) (xy 137.466166 -127.164627)
			(xy 137.404868 -127.106179) (xy 137.349403 -127.042169) (xy 137.300274 -126.973177) (xy 137.257925 -126.899827)
			(xy 137.222741 -126.822784) (xy 137.195039 -126.742745) (xy 137.175071 -126.660436) (xy 137.163018 -126.576601)
			(xy 137.158988 -126.492) (xy 127.509013 -126.492) (xy 127.504982 -126.576601) (xy 127.492929 -126.660436)
			(xy 127.472961 -126.742745) (xy 127.445259 -126.822784) (xy 127.410075 -126.899827) (xy 127.367726 -126.973177)
			(xy 127.318597 -127.042169) (xy 127.263132 -127.106179) (xy 127.201834 -127.164627) (xy 127.135258 -127.216983)
			(xy 127.064006 -127.262773) (xy 126.988725 -127.301584) (xy 126.910095 -127.333063) (xy 126.828828 -127.356924)
			(xy 126.745662 -127.372953) (xy 126.661348 -127.381004) (xy 126.619 -127.381508) (xy 126.618492 -127.381508)
			(xy 126.57216 -127.380902) (xy 126.480002 -127.371231) (xy 126.389348 -127.352035) (xy 126.301179 -127.323523)
			(xy 126.258574 -127.305308) (xy 126.248632 -127.301502) (xy 126.227368 -127.301502) (xy 126.217426 -127.305308)
			(xy 126.174823 -127.32353) (xy 126.086656 -127.352048) (xy 125.996 -127.37124) (xy 125.90384 -127.3809)
			(xy 125.857508 -127.381508) (xy 125.857 -127.381508) (xy 125.814652 -127.381004) (xy 125.730338 -127.372953)
			(xy 125.647172 -127.356924) (xy 125.565905 -127.333063) (xy 125.487275 -127.301584) (xy 125.411994 -127.262773)
			(xy 125.340742 -127.216983) (xy 125.274166 -127.164627) (xy 125.212868 -127.106179) (xy 125.157403 -127.042169)
			(xy 125.108274 -126.973177) (xy 125.065925 -126.899827) (xy 125.030741 -126.822784) (xy 125.003039 -126.742745)
			(xy 124.983071 -126.660436) (xy 124.971018 -126.576601) (xy 124.966988 -126.492) (xy 111.892813 -126.492)
			(xy 111.888783 -126.576599) (xy 111.876729 -126.660433) (xy 111.856762 -126.742741) (xy 111.829061 -126.822778)
			(xy 111.793878 -126.89982) (xy 111.751531 -126.973169) (xy 111.702404 -127.042161) (xy 111.646941 -127.10617)
			(xy 111.585645 -127.164617) (xy 111.519071 -127.216974) (xy 111.447821 -127.262765) (xy 111.372542 -127.301576)
			(xy 111.293914 -127.333056) (xy 111.21265 -127.356919) (xy 111.129485 -127.37295) (xy 111.045174 -127.381003)
			(xy 111.002826 -127.381508) (xy 111.002318 -127.381508) (xy 110.955986 -127.380893) (xy 110.863829 -127.371224)
			(xy 110.773175 -127.352031) (xy 110.685006 -127.323522) (xy 110.6424 -127.305308) (xy 110.632458 -127.301502)
			(xy 110.611194 -127.301502) (xy 110.601252 -127.305308) (xy 110.558646 -127.323521) (xy 110.470479 -127.352041)
			(xy 110.379825 -127.371236) (xy 110.287666 -127.380899) (xy 110.241334 -127.381508) (xy 110.240826 -127.381508)
			(xy 110.198476 -127.381021) (xy 110.114159 -127.372972) (xy 110.030989 -127.356945) (xy 109.94972 -127.333084)
			(xy 109.871086 -127.301606) (xy 109.795801 -127.262796) (xy 109.724546 -127.217005) (xy 109.657966 -127.164648)
			(xy 109.596665 -127.106199) (xy 109.541198 -127.042187) (xy 109.492066 -126.973193) (xy 109.449715 -126.899841)
			(xy 109.414529 -126.822796) (xy 109.386826 -126.742754) (xy 109.366857 -126.660442) (xy 109.354802 -126.576604)
			(xy 109.350772 -126.492) (xy 99.700813 -126.492) (xy 99.696783 -126.576599) (xy 99.684729 -126.660433)
			(xy 99.664762 -126.742741) (xy 99.637061 -126.822778) (xy 99.601878 -126.89982) (xy 99.559531 -126.973169)
			(xy 99.510404 -127.042161) (xy 99.454941 -127.10617) (xy 99.393645 -127.164617) (xy 99.327071 -127.216974)
			(xy 99.255821 -127.262765) (xy 99.180542 -127.301576) (xy 99.101914 -127.333056) (xy 99.02065 -127.356919)
			(xy 98.937485 -127.37295) (xy 98.853174 -127.381003) (xy 98.810826 -127.381508) (xy 98.810318 -127.381508)
			(xy 98.763986 -127.380893) (xy 98.671829 -127.371224) (xy 98.581175 -127.352031) (xy 98.493006 -127.323522)
			(xy 98.4504 -127.305308) (xy 98.440458 -127.301502) (xy 98.419194 -127.301502) (xy 98.409252 -127.305308)
			(xy 98.366646 -127.323521) (xy 98.278479 -127.352041) (xy 98.187825 -127.371236) (xy 98.095666 -127.380899)
			(xy 98.049334 -127.381508) (xy 98.048826 -127.381508) (xy 98.006476 -127.381021) (xy 97.922159 -127.372972)
			(xy 97.838989 -127.356945) (xy 97.75772 -127.333084) (xy 97.679086 -127.301606) (xy 97.603801 -127.262796)
			(xy 97.532546 -127.217005) (xy 97.465966 -127.164648) (xy 97.404665 -127.106199) (xy 97.349198 -127.042187)
			(xy 97.300066 -126.973193) (xy 97.257715 -126.899841) (xy 97.222529 -126.822796) (xy 97.194826 -126.742754)
			(xy 97.174857 -126.660442) (xy 97.162802 -126.576604) (xy 97.158772 -126.492) (xy 87.508813 -126.492)
			(xy 87.504783 -126.576599) (xy 87.492729 -126.660433) (xy 87.472762 -126.742741) (xy 87.445061 -126.822778)
			(xy 87.409878 -126.89982) (xy 87.367531 -126.973169) (xy 87.318404 -127.042161) (xy 87.262941 -127.10617)
			(xy 87.201645 -127.164617) (xy 87.135071 -127.216974) (xy 87.063821 -127.262765) (xy 86.988542 -127.301576)
			(xy 86.909914 -127.333056) (xy 86.82865 -127.356919) (xy 86.745485 -127.37295) (xy 86.661174 -127.381003)
			(xy 86.618826 -127.381508) (xy 86.618318 -127.381508) (xy 86.571986 -127.380893) (xy 86.479829 -127.371224)
			(xy 86.389175 -127.352031) (xy 86.301006 -127.323522) (xy 86.2584 -127.305308) (xy 86.248458 -127.301502)
			(xy 86.227194 -127.301502) (xy 86.217252 -127.305308) (xy 86.174646 -127.323521) (xy 86.086479 -127.352041)
			(xy 85.995825 -127.371236) (xy 85.903666 -127.380899) (xy 85.857334 -127.381508) (xy 85.856826 -127.381508)
			(xy 85.814476 -127.381021) (xy 85.730159 -127.372972) (xy 85.646989 -127.356945) (xy 85.56572 -127.333084)
			(xy 85.487086 -127.301606) (xy 85.411801 -127.262796) (xy 85.340546 -127.217005) (xy 85.273966 -127.164648)
			(xy 85.212665 -127.106199) (xy 85.157198 -127.042187) (xy 85.108066 -126.973193) (xy 85.065715 -126.899841)
			(xy 85.030529 -126.822796) (xy 85.002826 -126.742754) (xy 84.982857 -126.660442) (xy 84.970802 -126.576604)
			(xy 84.966772 -126.492) (xy 71.892913 -126.492) (xy 71.888882 -126.576601) (xy 71.876829 -126.660435)
			(xy 71.856861 -126.742744) (xy 71.82916 -126.822783) (xy 71.793975 -126.899826) (xy 71.751627 -126.973175)
			(xy 71.702499 -127.042167) (xy 71.647034 -127.106177) (xy 71.585737 -127.164624) (xy 71.519161 -127.216981)
			(xy 71.44791 -127.262771) (xy 71.372629 -127.301582) (xy 71.293999 -127.333061) (xy 71.212733 -127.356923)
			(xy 71.129567 -127.372953) (xy 71.045254 -127.381004) (xy 71.002906 -127.381508) (xy 71.002398 -127.381508)
			(xy 70.956066 -127.3809) (xy 70.863908 -127.371229) (xy 70.773254 -127.352034) (xy 70.685085 -127.323523)
			(xy 70.64248 -127.305308) (xy 70.632538 -127.301502) (xy 70.611274 -127.301502) (xy 70.601332 -127.305308)
			(xy 70.558728 -127.323528) (xy 70.470561 -127.352046) (xy 70.379906 -127.371239) (xy 70.287746 -127.3809)
			(xy 70.241414 -127.381508) (xy 70.240906 -127.381508) (xy 70.198557 -127.38102) (xy 70.114241 -127.37297)
			(xy 70.031073 -127.356941) (xy 69.949805 -127.333079) (xy 69.871173 -127.3016) (xy 69.795889 -127.262789)
			(xy 69.724636 -127.216998) (xy 69.658058 -127.16464) (xy 69.596758 -127.106192) (xy 69.541292 -127.042181)
			(xy 69.492162 -126.973187) (xy 69.449812 -126.899836) (xy 69.414627 -126.822791) (xy 69.386925 -126.742751)
			(xy 69.366956 -126.66044) (xy 69.354902 -126.576603) (xy 69.350872 -126.492) (xy 59.700913 -126.492)
			(xy 59.696882 -126.576601) (xy 59.684829 -126.660435) (xy 59.664861 -126.742744) (xy 59.63716 -126.822783)
			(xy 59.601975 -126.899826) (xy 59.559627 -126.973175) (xy 59.510499 -127.042167) (xy 59.455034 -127.106177)
			(xy 59.393737 -127.164624) (xy 59.327161 -127.216981) (xy 59.25591 -127.262771) (xy 59.180629 -127.301582)
			(xy 59.101999 -127.333061) (xy 59.020733 -127.356923) (xy 58.937567 -127.372953) (xy 58.853254 -127.381004)
			(xy 58.810906 -127.381508) (xy 58.810398 -127.381508) (xy 58.764066 -127.3809) (xy 58.671908 -127.371229)
			(xy 58.581254 -127.352034) (xy 58.493085 -127.323523) (xy 58.45048 -127.305308) (xy 58.440538 -127.301502)
			(xy 58.419274 -127.301502) (xy 58.409332 -127.305308) (xy 58.366728 -127.323528) (xy 58.278561 -127.352046)
			(xy 58.187906 -127.371239) (xy 58.095746 -127.3809) (xy 58.049414 -127.381508) (xy 58.048906 -127.381508)
			(xy 58.006557 -127.38102) (xy 57.922241 -127.37297) (xy 57.839073 -127.356941) (xy 57.757805 -127.333079)
			(xy 57.679173 -127.3016) (xy 57.603889 -127.262789) (xy 57.532636 -127.216998) (xy 57.466058 -127.16464)
			(xy 57.404758 -127.106192) (xy 57.349292 -127.042181) (xy 57.300162 -126.973187) (xy 57.257812 -126.899836)
			(xy 57.222627 -126.822791) (xy 57.194925 -126.742751) (xy 57.174956 -126.66044) (xy 57.162902 -126.576603)
			(xy 57.158872 -126.492) (xy 47.508913 -126.492) (xy 47.504882 -126.576601) (xy 47.492829 -126.660435)
			(xy 47.472861 -126.742744) (xy 47.44516 -126.822783) (xy 47.409975 -126.899826) (xy 47.367627 -126.973175)
			(xy 47.318499 -127.042167) (xy 47.263034 -127.106177) (xy 47.201737 -127.164624) (xy 47.135161 -127.216981)
			(xy 47.06391 -127.262771) (xy 46.988629 -127.301582) (xy 46.909999 -127.333061) (xy 46.828733 -127.356923)
			(xy 46.745567 -127.372953) (xy 46.661254 -127.381004) (xy 46.618906 -127.381508) (xy 46.618398 -127.381508)
			(xy 46.572066 -127.3809) (xy 46.479908 -127.371229) (xy 46.389254 -127.352034) (xy 46.301085 -127.323523)
			(xy 46.25848 -127.305308) (xy 46.248538 -127.301502) (xy 46.227274 -127.301502) (xy 46.217332 -127.305308)
			(xy 46.174728 -127.323528) (xy 46.086561 -127.352046) (xy 45.995906 -127.371239) (xy 45.903746 -127.3809)
			(xy 45.857414 -127.381508) (xy 45.856906 -127.381508) (xy 45.814557 -127.38102) (xy 45.730241 -127.37297)
			(xy 45.647073 -127.356941) (xy 45.565805 -127.333079) (xy 45.487173 -127.3016) (xy 45.411889 -127.262789)
			(xy 45.340636 -127.216998) (xy 45.274058 -127.16464) (xy 45.212758 -127.106192) (xy 45.157292 -127.042181)
			(xy 45.108162 -126.973187) (xy 45.065812 -126.899836) (xy 45.030627 -126.822791) (xy 45.002925 -126.742751)
			(xy 44.982956 -126.66044) (xy 44.970902 -126.576603) (xy 44.966872 -126.492) (xy 40.005 -126.492)
			(xy 40.005 -131.572) (xy 44.966872 -131.572) (xy 44.970902 -131.487397) (xy 44.982956 -131.40356)
			(xy 45.002925 -131.321249) (xy 45.030627 -131.241209) (xy 45.065812 -131.164164) (xy 45.108162 -131.090813)
			(xy 45.157292 -131.021819) (xy 45.212758 -130.957808) (xy 45.274058 -130.89936) (xy 45.340636 -130.847002)
			(xy 45.411889 -130.801211) (xy 45.487173 -130.7624) (xy 45.565805 -130.730921) (xy 45.647073 -130.707059)
			(xy 45.730241 -130.69103) (xy 45.814557 -130.68298) (xy 45.856906 -130.682492) (xy 45.857414 -130.682492)
			(xy 45.903746 -130.683096) (xy 45.995904 -130.692768) (xy 46.086558 -130.711964) (xy 46.174727 -130.740477)
			(xy 46.217332 -130.758692) (xy 46.227274 -130.762498) (xy 46.248538 -130.762498) (xy 46.25848 -130.758692)
			(xy 46.301082 -130.740468) (xy 46.38925 -130.711951) (xy 46.479906 -130.692759) (xy 46.572066 -130.6831)
			(xy 46.618398 -130.682492) (xy 46.618906 -130.682492) (xy 46.661254 -130.682996) (xy 46.745567 -130.691047)
			(xy 46.828733 -130.707077) (xy 46.909999 -130.730939) (xy 46.988629 -130.762418) (xy 47.06391 -130.801229)
			(xy 47.135161 -130.847019) (xy 47.201737 -130.899376) (xy 47.263034 -130.957823) (xy 47.318499 -131.021833)
			(xy 47.367627 -131.090825) (xy 47.409975 -131.164174) (xy 47.44516 -131.241217) (xy 47.472861 -131.321256)
			(xy 47.492829 -131.403565) (xy 47.504882 -131.487399) (xy 47.508913 -131.572) (xy 57.158872 -131.572)
			(xy 57.162902 -131.487397) (xy 57.174956 -131.40356) (xy 57.194925 -131.321249) (xy 57.222627 -131.241209)
			(xy 57.257812 -131.164164) (xy 57.300162 -131.090813) (xy 57.349292 -131.021819) (xy 57.404758 -130.957808)
			(xy 57.466058 -130.89936) (xy 57.532636 -130.847002) (xy 57.603889 -130.801211) (xy 57.679173 -130.7624)
			(xy 57.757805 -130.730921) (xy 57.839073 -130.707059) (xy 57.922241 -130.69103) (xy 58.006557 -130.68298)
			(xy 58.048906 -130.682492) (xy 58.049414 -130.682492) (xy 58.095746 -130.683096) (xy 58.187904 -130.692768)
			(xy 58.278558 -130.711964) (xy 58.366727 -130.740477) (xy 58.409332 -130.758692) (xy 58.419274 -130.762498)
			(xy 58.440538 -130.762498) (xy 58.45048 -130.758692) (xy 58.493082 -130.740468) (xy 58.58125 -130.711951)
			(xy 58.671906 -130.692759) (xy 58.764066 -130.6831) (xy 58.810398 -130.682492) (xy 58.810906 -130.682492)
			(xy 58.853254 -130.682996) (xy 58.937567 -130.691047) (xy 59.020733 -130.707077) (xy 59.101999 -130.730939)
			(xy 59.180629 -130.762418) (xy 59.25591 -130.801229) (xy 59.327161 -130.847019) (xy 59.393737 -130.899376)
			(xy 59.455034 -130.957823) (xy 59.510499 -131.021833) (xy 59.559627 -131.090825) (xy 59.601975 -131.164174)
			(xy 59.63716 -131.241217) (xy 59.664861 -131.321256) (xy 59.684829 -131.403565) (xy 59.696882 -131.487399)
			(xy 59.700913 -131.572) (xy 69.350872 -131.572) (xy 69.354902 -131.487397) (xy 69.366956 -131.40356)
			(xy 69.386925 -131.321249) (xy 69.414627 -131.241209) (xy 69.449812 -131.164164) (xy 69.492162 -131.090813)
			(xy 69.541292 -131.021819) (xy 69.596758 -130.957808) (xy 69.658058 -130.89936) (xy 69.724636 -130.847002)
			(xy 69.795889 -130.801211) (xy 69.871173 -130.7624) (xy 69.949805 -130.730921) (xy 70.031073 -130.707059)
			(xy 70.114241 -130.69103) (xy 70.198557 -130.68298) (xy 70.240906 -130.682492) (xy 70.241414 -130.682492)
			(xy 70.287746 -130.683096) (xy 70.379904 -130.692768) (xy 70.470558 -130.711964) (xy 70.558727 -130.740477)
			(xy 70.601332 -130.758692) (xy 70.611274 -130.762498) (xy 70.632538 -130.762498) (xy 70.64248 -130.758692)
			(xy 70.685082 -130.740468) (xy 70.77325 -130.711951) (xy 70.863906 -130.692759) (xy 70.956066 -130.6831)
			(xy 71.002398 -130.682492) (xy 71.002906 -130.682492) (xy 71.045254 -130.682996) (xy 71.129567 -130.691047)
			(xy 71.212733 -130.707077) (xy 71.293999 -130.730939) (xy 71.372629 -130.762418) (xy 71.44791 -130.801229)
			(xy 71.519161 -130.847019) (xy 71.585737 -130.899376) (xy 71.647034 -130.957823) (xy 71.702499 -131.021833)
			(xy 71.751627 -131.090825) (xy 71.793975 -131.164174) (xy 71.82916 -131.241217) (xy 71.856861 -131.321256)
			(xy 71.876829 -131.403565) (xy 71.888882 -131.487399) (xy 71.892913 -131.572) (xy 84.966772 -131.572)
			(xy 84.970802 -131.487396) (xy 84.982857 -131.403558) (xy 85.002826 -131.321246) (xy 85.030529 -131.241204)
			(xy 85.065715 -131.164159) (xy 85.108066 -131.090807) (xy 85.157198 -131.021813) (xy 85.212665 -130.957801)
			(xy 85.273966 -130.899352) (xy 85.340546 -130.846995) (xy 85.411801 -130.801204) (xy 85.487086 -130.762394)
			(xy 85.56572 -130.730916) (xy 85.646989 -130.707055) (xy 85.730159 -130.691028) (xy 85.814476 -130.682979)
			(xy 85.856826 -130.682492) (xy 85.857334 -130.682492) (xy 85.903665 -130.683124) (xy 85.995822 -130.692788)
			(xy 86.086476 -130.711976) (xy 86.174646 -130.74048) (xy 86.217252 -130.758692) (xy 86.227194 -130.762498)
			(xy 86.248458 -130.762498) (xy 86.2584 -130.758692) (xy 86.300999 -130.740461) (xy 86.389168 -130.711946)
			(xy 86.479825 -130.692756) (xy 86.571985 -130.683099) (xy 86.618318 -130.682492) (xy 86.618826 -130.682492)
			(xy 86.661174 -130.682997) (xy 86.745485 -130.69105) (xy 86.82865 -130.707081) (xy 86.909914 -130.730944)
			(xy 86.988542 -130.762424) (xy 87.063821 -130.801235) (xy 87.135071 -130.847026) (xy 87.201645 -130.899383)
			(xy 87.262941 -130.95783) (xy 87.318404 -131.021839) (xy 87.367531 -131.090831) (xy 87.409878 -131.16418)
			(xy 87.445061 -131.241222) (xy 87.472762 -131.321259) (xy 87.492729 -131.403567) (xy 87.504783 -131.487401)
			(xy 87.508813 -131.572) (xy 97.158772 -131.572) (xy 97.162802 -131.487396) (xy 97.174857 -131.403558)
			(xy 97.194826 -131.321246) (xy 97.222529 -131.241204) (xy 97.257715 -131.164159) (xy 97.300066 -131.090807)
			(xy 97.349198 -131.021813) (xy 97.404665 -130.957801) (xy 97.465966 -130.899352) (xy 97.532546 -130.846995)
			(xy 97.603801 -130.801204) (xy 97.679086 -130.762394) (xy 97.75772 -130.730916) (xy 97.838989 -130.707055)
			(xy 97.922159 -130.691028) (xy 98.006476 -130.682979) (xy 98.048826 -130.682492) (xy 98.049334 -130.682492)
			(xy 98.095665 -130.683124) (xy 98.187822 -130.692788) (xy 98.278476 -130.711976) (xy 98.366646 -130.74048)
			(xy 98.409252 -130.758692) (xy 98.419194 -130.762498) (xy 98.440458 -130.762498) (xy 98.4504 -130.758692)
			(xy 98.492999 -130.740461) (xy 98.581168 -130.711946) (xy 98.671825 -130.692756) (xy 98.763985 -130.683099)
			(xy 98.810318 -130.682492) (xy 98.810826 -130.682492) (xy 98.853174 -130.682997) (xy 98.937485 -130.69105)
			(xy 99.02065 -130.707081) (xy 99.101914 -130.730944) (xy 99.180542 -130.762424) (xy 99.255821 -130.801235)
			(xy 99.327071 -130.847026) (xy 99.393645 -130.899383) (xy 99.454941 -130.95783) (xy 99.510404 -131.021839)
			(xy 99.559531 -131.090831) (xy 99.601878 -131.16418) (xy 99.637061 -131.241222) (xy 99.664762 -131.321259)
			(xy 99.684729 -131.403567) (xy 99.696783 -131.487401) (xy 99.700813 -131.572) (xy 109.350772 -131.572)
			(xy 109.354802 -131.487396) (xy 109.366857 -131.403558) (xy 109.386826 -131.321246) (xy 109.414529 -131.241204)
			(xy 109.449715 -131.164159) (xy 109.492066 -131.090807) (xy 109.541198 -131.021813) (xy 109.596665 -130.957801)
			(xy 109.657966 -130.899352) (xy 109.724546 -130.846995) (xy 109.795801 -130.801204) (xy 109.871086 -130.762394)
			(xy 109.94972 -130.730916) (xy 110.030989 -130.707055) (xy 110.114159 -130.691028) (xy 110.198476 -130.682979)
			(xy 110.240826 -130.682492) (xy 110.241334 -130.682492) (xy 110.287665 -130.683124) (xy 110.379822 -130.692788)
			(xy 110.470476 -130.711976) (xy 110.558646 -130.74048) (xy 110.601252 -130.758692) (xy 110.611194 -130.762498)
			(xy 110.632458 -130.762498) (xy 110.6424 -130.758692) (xy 110.684999 -130.740461) (xy 110.773168 -130.711946)
			(xy 110.863825 -130.692756) (xy 110.955985 -130.683099) (xy 111.002318 -130.682492) (xy 111.002826 -130.682492)
			(xy 111.045174 -130.682997) (xy 111.129485 -130.69105) (xy 111.21265 -130.707081) (xy 111.293914 -130.730944)
			(xy 111.372542 -130.762424) (xy 111.447821 -130.801235) (xy 111.519071 -130.847026) (xy 111.585645 -130.899383)
			(xy 111.646941 -130.95783) (xy 111.702404 -131.021839) (xy 111.751531 -131.090831) (xy 111.793878 -131.16418)
			(xy 111.829061 -131.241222) (xy 111.856762 -131.321259) (xy 111.876729 -131.403567) (xy 111.888783 -131.487401)
			(xy 111.892813 -131.572) (xy 124.966988 -131.572) (xy 124.971018 -131.487399) (xy 124.983071 -131.403564)
			(xy 125.003039 -131.321255) (xy 125.030741 -131.241216) (xy 125.065925 -131.164173) (xy 125.108274 -131.090823)
			(xy 125.157403 -131.021831) (xy 125.212868 -130.957821) (xy 125.274166 -130.899373) (xy 125.340742 -130.847017)
			(xy 125.411994 -130.801227) (xy 125.487275 -130.762416) (xy 125.565905 -130.730937) (xy 125.647172 -130.707076)
			(xy 125.730338 -130.691047) (xy 125.814652 -130.682996) (xy 125.857 -130.682492) (xy 125.857508 -130.682492)
			(xy 125.90384 -130.683098) (xy 125.995998 -130.692769) (xy 126.086652 -130.711965) (xy 126.174821 -130.740477)
			(xy 126.217426 -130.758692) (xy 126.227368 -130.762498) (xy 126.248632 -130.762498) (xy 126.258574 -130.758692)
			(xy 126.301177 -130.74047) (xy 126.389344 -130.711952) (xy 126.48 -130.69276) (xy 126.57216 -130.6831)
			(xy 126.618492 -130.682492) (xy 126.619 -130.682492) (xy 126.661348 -130.682996) (xy 126.745662 -130.691047)
			(xy 126.828828 -130.707076) (xy 126.910095 -130.730937) (xy 126.988725 -130.762416) (xy 127.064006 -130.801227)
			(xy 127.135258 -130.847017) (xy 127.201834 -130.899373) (xy 127.263132 -130.957821) (xy 127.318597 -131.021831)
			(xy 127.367726 -131.090823) (xy 127.410075 -131.164173) (xy 127.445259 -131.241216) (xy 127.472961 -131.321255)
			(xy 127.492929 -131.403564) (xy 127.504982 -131.487399) (xy 127.509013 -131.572) (xy 137.158988 -131.572)
			(xy 137.163018 -131.487399) (xy 137.175071 -131.403564) (xy 137.195039 -131.321255) (xy 137.222741 -131.241216)
			(xy 137.257925 -131.164173) (xy 137.300274 -131.090823) (xy 137.349403 -131.021831) (xy 137.404868 -130.957821)
			(xy 137.466166 -130.899373) (xy 137.532742 -130.847017) (xy 137.603994 -130.801227) (xy 137.679275 -130.762416)
			(xy 137.757905 -130.730937) (xy 137.839172 -130.707076) (xy 137.922338 -130.691047) (xy 138.006652 -130.682996)
			(xy 138.049 -130.682492) (xy 138.049508 -130.682492) (xy 138.09584 -130.683098) (xy 138.187998 -130.692769)
			(xy 138.278652 -130.711965) (xy 138.366821 -130.740477) (xy 138.409426 -130.758692) (xy 138.419368 -130.762498)
			(xy 138.440632 -130.762498) (xy 138.450574 -130.758692) (xy 138.493177 -130.74047) (xy 138.581344 -130.711952)
			(xy 138.672 -130.69276) (xy 138.76416 -130.6831) (xy 138.810492 -130.682492) (xy 138.811 -130.682492)
			(xy 138.853348 -130.682996) (xy 138.937662 -130.691047) (xy 139.020828 -130.707076) (xy 139.102095 -130.730937)
			(xy 139.180725 -130.762416) (xy 139.256006 -130.801227) (xy 139.327258 -130.847017) (xy 139.393834 -130.899373)
			(xy 139.455132 -130.957821) (xy 139.510597 -131.021831) (xy 139.559726 -131.090823) (xy 139.602075 -131.164173)
			(xy 139.637259 -131.241216) (xy 139.664961 -131.321255) (xy 139.684929 -131.403564) (xy 139.696982 -131.487399)
			(xy 139.701013 -131.572) (xy 149.350988 -131.572) (xy 149.355018 -131.487399) (xy 149.367071 -131.403564)
			(xy 149.387039 -131.321255) (xy 149.414741 -131.241216) (xy 149.449925 -131.164173) (xy 149.492274 -131.090823)
			(xy 149.541403 -131.021831) (xy 149.596868 -130.957821) (xy 149.658166 -130.899373) (xy 149.724742 -130.847017)
			(xy 149.795994 -130.801227) (xy 149.871275 -130.762416) (xy 149.949905 -130.730937) (xy 150.031172 -130.707076)
			(xy 150.114338 -130.691047) (xy 150.198652 -130.682996) (xy 150.241 -130.682492) (xy 150.241508 -130.682492)
			(xy 150.28784 -130.683098) (xy 150.379998 -130.692769) (xy 150.470652 -130.711965) (xy 150.558821 -130.740477)
			(xy 150.601426 -130.758692) (xy 150.611368 -130.762498) (xy 150.632632 -130.762498) (xy 150.642574 -130.758692)
			(xy 150.685177 -130.74047) (xy 150.773344 -130.711952) (xy 150.864 -130.69276) (xy 150.95616 -130.6831)
			(xy 151.002492 -130.682492) (xy 151.003 -130.682492) (xy 151.045348 -130.682996) (xy 151.129662 -130.691047)
			(xy 151.212828 -130.707076) (xy 151.294095 -130.730937) (xy 151.372725 -130.762416) (xy 151.448006 -130.801227)
			(xy 151.519258 -130.847017) (xy 151.585834 -130.899373) (xy 151.647132 -130.957821) (xy 151.702597 -131.021831)
			(xy 151.751726 -131.090823) (xy 151.794075 -131.164173) (xy 151.829259 -131.241216) (xy 151.856961 -131.321255)
			(xy 151.876929 -131.403564) (xy 151.888982 -131.487399) (xy 151.893013 -131.572) (xy 164.967187 -131.572)
			(xy 164.971217 -131.487401) (xy 164.983271 -131.403567) (xy 165.003238 -131.321259) (xy 165.030939 -131.241222)
			(xy 165.066122 -131.16418) (xy 165.108469 -131.090831) (xy 165.157596 -131.021839) (xy 165.213059 -130.95783)
			(xy 165.274355 -130.899383) (xy 165.340929 -130.847026) (xy 165.412179 -130.801235) (xy 165.487458 -130.762424)
			(xy 165.566086 -130.730944) (xy 165.64735 -130.707081) (xy 165.730515 -130.69105) (xy 165.814826 -130.682997)
			(xy 165.857174 -130.682492) (xy 165.857682 -130.682492) (xy 165.904014 -130.683107) (xy 165.996171 -130.692776)
			(xy 166.086825 -130.711969) (xy 166.174994 -130.740478) (xy 166.2176 -130.758692) (xy 166.227542 -130.762498)
			(xy 166.248806 -130.762498) (xy 166.258748 -130.758692) (xy 166.301354 -130.740479) (xy 166.389521 -130.711959)
			(xy 166.480175 -130.692764) (xy 166.572334 -130.683101) (xy 166.618666 -130.682492) (xy 166.619174 -130.682492)
			(xy 166.661524 -130.682979) (xy 166.745841 -130.691028) (xy 166.829011 -130.707055) (xy 166.91028 -130.730916)
			(xy 166.988914 -130.762394) (xy 167.064199 -130.801204) (xy 167.135454 -130.846995) (xy 167.202034 -130.899352)
			(xy 167.263335 -130.957801) (xy 167.318802 -131.021813) (xy 167.367934 -131.090807) (xy 167.410285 -131.164159)
			(xy 167.445471 -131.241204) (xy 167.473174 -131.321246) (xy 167.493143 -131.403558) (xy 167.505198 -131.487396)
			(xy 167.509228 -131.572) (xy 177.159187 -131.572) (xy 177.163217 -131.487401) (xy 177.175271 -131.403567)
			(xy 177.195238 -131.321259) (xy 177.222939 -131.241222) (xy 177.258122 -131.16418) (xy 177.300469 -131.090831)
			(xy 177.349596 -131.021839) (xy 177.405059 -130.95783) (xy 177.466355 -130.899383) (xy 177.532929 -130.847026)
			(xy 177.604179 -130.801235) (xy 177.679458 -130.762424) (xy 177.758086 -130.730944) (xy 177.83935 -130.707081)
			(xy 177.922515 -130.69105) (xy 178.006826 -130.682997) (xy 178.049174 -130.682492) (xy 178.049682 -130.682492)
			(xy 178.096014 -130.683107) (xy 178.188171 -130.692776) (xy 178.278825 -130.711969) (xy 178.366994 -130.740478)
			(xy 178.4096 -130.758692) (xy 178.419542 -130.762498) (xy 178.440806 -130.762498) (xy 178.450748 -130.758692)
			(xy 178.493354 -130.740479) (xy 178.581521 -130.711959) (xy 178.672175 -130.692764) (xy 178.764334 -130.683101)
			(xy 178.810666 -130.682492) (xy 178.811174 -130.682492) (xy 178.853524 -130.682979) (xy 178.937841 -130.691028)
			(xy 179.021011 -130.707055) (xy 179.10228 -130.730916) (xy 179.180914 -130.762394) (xy 179.256199 -130.801204)
			(xy 179.327454 -130.846995) (xy 179.394034 -130.899352) (xy 179.455335 -130.957801) (xy 179.510802 -131.021813)
			(xy 179.559934 -131.090807) (xy 179.602285 -131.164159) (xy 179.637471 -131.241204) (xy 179.665174 -131.321246)
			(xy 179.685143 -131.403558) (xy 179.697198 -131.487396) (xy 179.701228 -131.572) (xy 189.351187 -131.572)
			(xy 189.355217 -131.487401) (xy 189.367271 -131.403567) (xy 189.387238 -131.321259) (xy 189.414939 -131.241222)
			(xy 189.450122 -131.16418) (xy 189.492469 -131.090831) (xy 189.541596 -131.021839) (xy 189.597059 -130.95783)
			(xy 189.658355 -130.899383) (xy 189.724929 -130.847026) (xy 189.796179 -130.801235) (xy 189.871458 -130.762424)
			(xy 189.950086 -130.730944) (xy 190.03135 -130.707081) (xy 190.114515 -130.69105) (xy 190.198826 -130.682997)
			(xy 190.241174 -130.682492) (xy 190.241682 -130.682492) (xy 190.288014 -130.683107) (xy 190.380171 -130.692776)
			(xy 190.470825 -130.711969) (xy 190.558994 -130.740478) (xy 190.6016 -130.758692) (xy 190.611542 -130.762498)
			(xy 190.632806 -130.762498) (xy 190.642748 -130.758692) (xy 190.685354 -130.740479) (xy 190.773521 -130.711959)
			(xy 190.864175 -130.692764) (xy 190.956334 -130.683101) (xy 191.002666 -130.682492) (xy 191.003174 -130.682492)
			(xy 191.045524 -130.682979) (xy 191.129841 -130.691028) (xy 191.213011 -130.707055) (xy 191.29428 -130.730916)
			(xy 191.372914 -130.762394) (xy 191.448199 -130.801204) (xy 191.519454 -130.846995) (xy 191.586034 -130.899352)
			(xy 191.647335 -130.957801) (xy 191.702802 -131.021813) (xy 191.751934 -131.090807) (xy 191.794285 -131.164159)
			(xy 191.829471 -131.241204) (xy 191.857174 -131.321246) (xy 191.877143 -131.403558) (xy 191.889198 -131.487396)
			(xy 191.893228 -131.572) (xy 191.889198 -131.656604) (xy 191.877143 -131.740442) (xy 191.857174 -131.822754)
			(xy 191.829471 -131.902796) (xy 191.794285 -131.979841) (xy 191.751934 -132.053193) (xy 191.702802 -132.122187)
			(xy 191.647335 -132.186199) (xy 191.586034 -132.244648) (xy 191.519454 -132.297005) (xy 191.448199 -132.342796)
			(xy 191.372914 -132.381606) (xy 191.29428 -132.413084) (xy 191.213011 -132.436945) (xy 191.129841 -132.452972)
			(xy 191.045524 -132.461021) (xy 191.003174 -132.461508) (xy 191.002666 -132.461508) (xy 190.956335 -132.460876)
			(xy 190.864178 -132.451212) (xy 190.773524 -132.432024) (xy 190.685354 -132.40352) (xy 190.642748 -132.385308)
			(xy 190.632806 -132.381502) (xy 190.611542 -132.381502) (xy 190.6016 -132.385308) (xy 190.559001 -132.403539)
			(xy 190.470832 -132.432054) (xy 190.380175 -132.451244) (xy 190.288015 -132.460901) (xy 190.241682 -132.461508)
			(xy 190.241174 -132.461508) (xy 190.198826 -132.461003) (xy 190.114515 -132.45295) (xy 190.03135 -132.436919)
			(xy 189.950086 -132.413056) (xy 189.871458 -132.381576) (xy 189.796179 -132.342765) (xy 189.724929 -132.296974)
			(xy 189.658355 -132.244617) (xy 189.597059 -132.18617) (xy 189.541596 -132.122161) (xy 189.492469 -132.053169)
			(xy 189.450122 -131.97982) (xy 189.414939 -131.902778) (xy 189.387238 -131.822741) (xy 189.367271 -131.740433)
			(xy 189.355217 -131.656599) (xy 189.351187 -131.572) (xy 179.701228 -131.572) (xy 179.697198 -131.656604)
			(xy 179.685143 -131.740442) (xy 179.665174 -131.822754) (xy 179.637471 -131.902796) (xy 179.602285 -131.979841)
			(xy 179.559934 -132.053193) (xy 179.510802 -132.122187) (xy 179.455335 -132.186199) (xy 179.394034 -132.244648)
			(xy 179.327454 -132.297005) (xy 179.256199 -132.342796) (xy 179.180914 -132.381606) (xy 179.10228 -132.413084)
			(xy 179.021011 -132.436945) (xy 178.937841 -132.452972) (xy 178.853524 -132.461021) (xy 178.811174 -132.461508)
			(xy 178.810666 -132.461508) (xy 178.764335 -132.460876) (xy 178.672178 -132.451212) (xy 178.581524 -132.432024)
			(xy 178.493354 -132.40352) (xy 178.450748 -132.385308) (xy 178.440806 -132.381502) (xy 178.419542 -132.381502)
			(xy 178.4096 -132.385308) (xy 178.367001 -132.403539) (xy 178.278832 -132.432054) (xy 178.188175 -132.451244)
			(xy 178.096015 -132.460901) (xy 178.049682 -132.461508) (xy 178.049174 -132.461508) (xy 178.006826 -132.461003)
			(xy 177.922515 -132.45295) (xy 177.83935 -132.436919) (xy 177.758086 -132.413056) (xy 177.679458 -132.381576)
			(xy 177.604179 -132.342765) (xy 177.532929 -132.296974) (xy 177.466355 -132.244617) (xy 177.405059 -132.18617)
			(xy 177.349596 -132.122161) (xy 177.300469 -132.053169) (xy 177.258122 -131.97982) (xy 177.222939 -131.902778)
			(xy 177.195238 -131.822741) (xy 177.175271 -131.740433) (xy 177.163217 -131.656599) (xy 177.159187 -131.572)
			(xy 167.509228 -131.572) (xy 167.505198 -131.656604) (xy 167.493143 -131.740442) (xy 167.473174 -131.822754)
			(xy 167.445471 -131.902796) (xy 167.410285 -131.979841) (xy 167.367934 -132.053193) (xy 167.318802 -132.122187)
			(xy 167.263335 -132.186199) (xy 167.202034 -132.244648) (xy 167.135454 -132.297005) (xy 167.064199 -132.342796)
			(xy 166.988914 -132.381606) (xy 166.91028 -132.413084) (xy 166.829011 -132.436945) (xy 166.745841 -132.452972)
			(xy 166.661524 -132.461021) (xy 166.619174 -132.461508) (xy 166.618666 -132.461508) (xy 166.572335 -132.460876)
			(xy 166.480178 -132.451212) (xy 166.389524 -132.432024) (xy 166.301354 -132.40352) (xy 166.258748 -132.385308)
			(xy 166.248806 -132.381502) (xy 166.227542 -132.381502) (xy 166.2176 -132.385308) (xy 166.175001 -132.403539)
			(xy 166.086832 -132.432054) (xy 165.996175 -132.451244) (xy 165.904015 -132.460901) (xy 165.857682 -132.461508)
			(xy 165.857174 -132.461508) (xy 165.814826 -132.461003) (xy 165.730515 -132.45295) (xy 165.64735 -132.436919)
			(xy 165.566086 -132.413056) (xy 165.487458 -132.381576) (xy 165.412179 -132.342765) (xy 165.340929 -132.296974)
			(xy 165.274355 -132.244617) (xy 165.213059 -132.18617) (xy 165.157596 -132.122161) (xy 165.108469 -132.053169)
			(xy 165.066122 -131.97982) (xy 165.030939 -131.902778) (xy 165.003238 -131.822741) (xy 164.983271 -131.740433)
			(xy 164.971217 -131.656599) (xy 164.967187 -131.572) (xy 151.893013 -131.572) (xy 151.888982 -131.656601)
			(xy 151.876929 -131.740436) (xy 151.856961 -131.822745) (xy 151.829259 -131.902784) (xy 151.794075 -131.979827)
			(xy 151.751726 -132.053177) (xy 151.702597 -132.122169) (xy 151.647132 -132.186179) (xy 151.585834 -132.244627)
			(xy 151.519258 -132.296983) (xy 151.448006 -132.342773) (xy 151.372725 -132.381584) (xy 151.294095 -132.413063)
			(xy 151.212828 -132.436924) (xy 151.129662 -132.452953) (xy 151.045348 -132.461004) (xy 151.003 -132.461508)
			(xy 151.002492 -132.461508) (xy 150.95616 -132.460902) (xy 150.864002 -132.451231) (xy 150.773348 -132.432035)
			(xy 150.685179 -132.403523) (xy 150.642574 -132.385308) (xy 150.632632 -132.381502) (xy 150.611368 -132.381502)
			(xy 150.601426 -132.385308) (xy 150.558823 -132.40353) (xy 150.470656 -132.432048) (xy 150.38 -132.45124)
			(xy 150.28784 -132.4609) (xy 150.241508 -132.461508) (xy 150.241 -132.461508) (xy 150.198652 -132.461004)
			(xy 150.114338 -132.452953) (xy 150.031172 -132.436924) (xy 149.949905 -132.413063) (xy 149.871275 -132.381584)
			(xy 149.795994 -132.342773) (xy 149.724742 -132.296983) (xy 149.658166 -132.244627) (xy 149.596868 -132.186179)
			(xy 149.541403 -132.122169) (xy 149.492274 -132.053177) (xy 149.449925 -131.979827) (xy 149.414741 -131.902784)
			(xy 149.387039 -131.822745) (xy 149.367071 -131.740436) (xy 149.355018 -131.656601) (xy 149.350988 -131.572)
			(xy 139.701013 -131.572) (xy 139.696982 -131.656601) (xy 139.684929 -131.740436) (xy 139.664961 -131.822745)
			(xy 139.637259 -131.902784) (xy 139.602075 -131.979827) (xy 139.559726 -132.053177) (xy 139.510597 -132.122169)
			(xy 139.455132 -132.186179) (xy 139.393834 -132.244627) (xy 139.327258 -132.296983) (xy 139.256006 -132.342773)
			(xy 139.180725 -132.381584) (xy 139.102095 -132.413063) (xy 139.020828 -132.436924) (xy 138.937662 -132.452953)
			(xy 138.853348 -132.461004) (xy 138.811 -132.461508) (xy 138.810492 -132.461508) (xy 138.76416 -132.460902)
			(xy 138.672002 -132.451231) (xy 138.581348 -132.432035) (xy 138.493179 -132.403523) (xy 138.450574 -132.385308)
			(xy 138.440632 -132.381502) (xy 138.419368 -132.381502) (xy 138.409426 -132.385308) (xy 138.366823 -132.40353)
			(xy 138.278656 -132.432048) (xy 138.188 -132.45124) (xy 138.09584 -132.4609) (xy 138.049508 -132.461508)
			(xy 138.049 -132.461508) (xy 138.006652 -132.461004) (xy 137.922338 -132.452953) (xy 137.839172 -132.436924)
			(xy 137.757905 -132.413063) (xy 137.679275 -132.381584) (xy 137.603994 -132.342773) (xy 137.532742 -132.296983)
			(xy 137.466166 -132.244627) (xy 137.404868 -132.186179) (xy 137.349403 -132.122169) (xy 137.300274 -132.053177)
			(xy 137.257925 -131.979827) (xy 137.222741 -131.902784) (xy 137.195039 -131.822745) (xy 137.175071 -131.740436)
			(xy 137.163018 -131.656601) (xy 137.158988 -131.572) (xy 127.509013 -131.572) (xy 127.504982 -131.656601)
			(xy 127.492929 -131.740436) (xy 127.472961 -131.822745) (xy 127.445259 -131.902784) (xy 127.410075 -131.979827)
			(xy 127.367726 -132.053177) (xy 127.318597 -132.122169) (xy 127.263132 -132.186179) (xy 127.201834 -132.244627)
			(xy 127.135258 -132.296983) (xy 127.064006 -132.342773) (xy 126.988725 -132.381584) (xy 126.910095 -132.413063)
			(xy 126.828828 -132.436924) (xy 126.745662 -132.452953) (xy 126.661348 -132.461004) (xy 126.619 -132.461508)
			(xy 126.618492 -132.461508) (xy 126.57216 -132.460902) (xy 126.480002 -132.451231) (xy 126.389348 -132.432035)
			(xy 126.301179 -132.403523) (xy 126.258574 -132.385308) (xy 126.248632 -132.381502) (xy 126.227368 -132.381502)
			(xy 126.217426 -132.385308) (xy 126.174823 -132.40353) (xy 126.086656 -132.432048) (xy 125.996 -132.45124)
			(xy 125.90384 -132.4609) (xy 125.857508 -132.461508) (xy 125.857 -132.461508) (xy 125.814652 -132.461004)
			(xy 125.730338 -132.452953) (xy 125.647172 -132.436924) (xy 125.565905 -132.413063) (xy 125.487275 -132.381584)
			(xy 125.411994 -132.342773) (xy 125.340742 -132.296983) (xy 125.274166 -132.244627) (xy 125.212868 -132.186179)
			(xy 125.157403 -132.122169) (xy 125.108274 -132.053177) (xy 125.065925 -131.979827) (xy 125.030741 -131.902784)
			(xy 125.003039 -131.822745) (xy 124.983071 -131.740436) (xy 124.971018 -131.656601) (xy 124.966988 -131.572)
			(xy 111.892813 -131.572) (xy 111.888783 -131.656599) (xy 111.876729 -131.740433) (xy 111.856762 -131.822741)
			(xy 111.829061 -131.902778) (xy 111.793878 -131.97982) (xy 111.751531 -132.053169) (xy 111.702404 -132.122161)
			(xy 111.646941 -132.18617) (xy 111.585645 -132.244617) (xy 111.519071 -132.296974) (xy 111.447821 -132.342765)
			(xy 111.372542 -132.381576) (xy 111.293914 -132.413056) (xy 111.21265 -132.436919) (xy 111.129485 -132.45295)
			(xy 111.045174 -132.461003) (xy 111.002826 -132.461508) (xy 111.002318 -132.461508) (xy 110.955986 -132.460893)
			(xy 110.863829 -132.451224) (xy 110.773175 -132.432031) (xy 110.685006 -132.403522) (xy 110.6424 -132.385308)
			(xy 110.632458 -132.381502) (xy 110.611194 -132.381502) (xy 110.601252 -132.385308) (xy 110.558646 -132.403521)
			(xy 110.470479 -132.432041) (xy 110.379825 -132.451236) (xy 110.287666 -132.460899) (xy 110.241334 -132.461508)
			(xy 110.240826 -132.461508) (xy 110.198476 -132.461021) (xy 110.114159 -132.452972) (xy 110.030989 -132.436945)
			(xy 109.94972 -132.413084) (xy 109.871086 -132.381606) (xy 109.795801 -132.342796) (xy 109.724546 -132.297005)
			(xy 109.657966 -132.244648) (xy 109.596665 -132.186199) (xy 109.541198 -132.122187) (xy 109.492066 -132.053193)
			(xy 109.449715 -131.979841) (xy 109.414529 -131.902796) (xy 109.386826 -131.822754) (xy 109.366857 -131.740442)
			(xy 109.354802 -131.656604) (xy 109.350772 -131.572) (xy 99.700813 -131.572) (xy 99.696783 -131.656599)
			(xy 99.684729 -131.740433) (xy 99.664762 -131.822741) (xy 99.637061 -131.902778) (xy 99.601878 -131.97982)
			(xy 99.559531 -132.053169) (xy 99.510404 -132.122161) (xy 99.454941 -132.18617) (xy 99.393645 -132.244617)
			(xy 99.327071 -132.296974) (xy 99.255821 -132.342765) (xy 99.180542 -132.381576) (xy 99.101914 -132.413056)
			(xy 99.02065 -132.436919) (xy 98.937485 -132.45295) (xy 98.853174 -132.461003) (xy 98.810826 -132.461508)
			(xy 98.810318 -132.461508) (xy 98.763986 -132.460893) (xy 98.671829 -132.451224) (xy 98.581175 -132.432031)
			(xy 98.493006 -132.403522) (xy 98.4504 -132.385308) (xy 98.440458 -132.381502) (xy 98.419194 -132.381502)
			(xy 98.409252 -132.385308) (xy 98.366646 -132.403521) (xy 98.278479 -132.432041) (xy 98.187825 -132.451236)
			(xy 98.095666 -132.460899) (xy 98.049334 -132.461508) (xy 98.048826 -132.461508) (xy 98.006476 -132.461021)
			(xy 97.922159 -132.452972) (xy 97.838989 -132.436945) (xy 97.75772 -132.413084) (xy 97.679086 -132.381606)
			(xy 97.603801 -132.342796) (xy 97.532546 -132.297005) (xy 97.465966 -132.244648) (xy 97.404665 -132.186199)
			(xy 97.349198 -132.122187) (xy 97.300066 -132.053193) (xy 97.257715 -131.979841) (xy 97.222529 -131.902796)
			(xy 97.194826 -131.822754) (xy 97.174857 -131.740442) (xy 97.162802 -131.656604) (xy 97.158772 -131.572)
			(xy 87.508813 -131.572) (xy 87.504783 -131.656599) (xy 87.492729 -131.740433) (xy 87.472762 -131.822741)
			(xy 87.445061 -131.902778) (xy 87.409878 -131.97982) (xy 87.367531 -132.053169) (xy 87.318404 -132.122161)
			(xy 87.262941 -132.18617) (xy 87.201645 -132.244617) (xy 87.135071 -132.296974) (xy 87.063821 -132.342765)
			(xy 86.988542 -132.381576) (xy 86.909914 -132.413056) (xy 86.82865 -132.436919) (xy 86.745485 -132.45295)
			(xy 86.661174 -132.461003) (xy 86.618826 -132.461508) (xy 86.618318 -132.461508) (xy 86.571986 -132.460893)
			(xy 86.479829 -132.451224) (xy 86.389175 -132.432031) (xy 86.301006 -132.403522) (xy 86.2584 -132.385308)
			(xy 86.248458 -132.381502) (xy 86.227194 -132.381502) (xy 86.217252 -132.385308) (xy 86.174646 -132.403521)
			(xy 86.086479 -132.432041) (xy 85.995825 -132.451236) (xy 85.903666 -132.460899) (xy 85.857334 -132.461508)
			(xy 85.856826 -132.461508) (xy 85.814476 -132.461021) (xy 85.730159 -132.452972) (xy 85.646989 -132.436945)
			(xy 85.56572 -132.413084) (xy 85.487086 -132.381606) (xy 85.411801 -132.342796) (xy 85.340546 -132.297005)
			(xy 85.273966 -132.244648) (xy 85.212665 -132.186199) (xy 85.157198 -132.122187) (xy 85.108066 -132.053193)
			(xy 85.065715 -131.979841) (xy 85.030529 -131.902796) (xy 85.002826 -131.822754) (xy 84.982857 -131.740442)
			(xy 84.970802 -131.656604) (xy 84.966772 -131.572) (xy 71.892913 -131.572) (xy 71.888882 -131.656601)
			(xy 71.876829 -131.740435) (xy 71.856861 -131.822744) (xy 71.82916 -131.902783) (xy 71.793975 -131.979826)
			(xy 71.751627 -132.053175) (xy 71.702499 -132.122167) (xy 71.647034 -132.186177) (xy 71.585737 -132.244624)
			(xy 71.519161 -132.296981) (xy 71.44791 -132.342771) (xy 71.372629 -132.381582) (xy 71.293999 -132.413061)
			(xy 71.212733 -132.436923) (xy 71.129567 -132.452953) (xy 71.045254 -132.461004) (xy 71.002906 -132.461508)
			(xy 71.002398 -132.461508) (xy 70.956066 -132.4609) (xy 70.863908 -132.451229) (xy 70.773254 -132.432034)
			(xy 70.685085 -132.403523) (xy 70.64248 -132.385308) (xy 70.632538 -132.381502) (xy 70.611274 -132.381502)
			(xy 70.601332 -132.385308) (xy 70.558728 -132.403528) (xy 70.470561 -132.432046) (xy 70.379906 -132.451239)
			(xy 70.287746 -132.4609) (xy 70.241414 -132.461508) (xy 70.240906 -132.461508) (xy 70.198557 -132.46102)
			(xy 70.114241 -132.45297) (xy 70.031073 -132.436941) (xy 69.949805 -132.413079) (xy 69.871173 -132.3816)
			(xy 69.795889 -132.342789) (xy 69.724636 -132.296998) (xy 69.658058 -132.24464) (xy 69.596758 -132.186192)
			(xy 69.541292 -132.122181) (xy 69.492162 -132.053187) (xy 69.449812 -131.979836) (xy 69.414627 -131.902791)
			(xy 69.386925 -131.822751) (xy 69.366956 -131.74044) (xy 69.354902 -131.656603) (xy 69.350872 -131.572)
			(xy 59.700913 -131.572) (xy 59.696882 -131.656601) (xy 59.684829 -131.740435) (xy 59.664861 -131.822744)
			(xy 59.63716 -131.902783) (xy 59.601975 -131.979826) (xy 59.559627 -132.053175) (xy 59.510499 -132.122167)
			(xy 59.455034 -132.186177) (xy 59.393737 -132.244624) (xy 59.327161 -132.296981) (xy 59.25591 -132.342771)
			(xy 59.180629 -132.381582) (xy 59.101999 -132.413061) (xy 59.020733 -132.436923) (xy 58.937567 -132.452953)
			(xy 58.853254 -132.461004) (xy 58.810906 -132.461508) (xy 58.810398 -132.461508) (xy 58.764066 -132.4609)
			(xy 58.671908 -132.451229) (xy 58.581254 -132.432034) (xy 58.493085 -132.403523) (xy 58.45048 -132.385308)
			(xy 58.440538 -132.381502) (xy 58.419274 -132.381502) (xy 58.409332 -132.385308) (xy 58.366728 -132.403528)
			(xy 58.278561 -132.432046) (xy 58.187906 -132.451239) (xy 58.095746 -132.4609) (xy 58.049414 -132.461508)
			(xy 58.048906 -132.461508) (xy 58.006557 -132.46102) (xy 57.922241 -132.45297) (xy 57.839073 -132.436941)
			(xy 57.757805 -132.413079) (xy 57.679173 -132.3816) (xy 57.603889 -132.342789) (xy 57.532636 -132.296998)
			(xy 57.466058 -132.24464) (xy 57.404758 -132.186192) (xy 57.349292 -132.122181) (xy 57.300162 -132.053187)
			(xy 57.257812 -131.979836) (xy 57.222627 -131.902791) (xy 57.194925 -131.822751) (xy 57.174956 -131.74044)
			(xy 57.162902 -131.656603) (xy 57.158872 -131.572) (xy 47.508913 -131.572) (xy 47.504882 -131.656601)
			(xy 47.492829 -131.740435) (xy 47.472861 -131.822744) (xy 47.44516 -131.902783) (xy 47.409975 -131.979826)
			(xy 47.367627 -132.053175) (xy 47.318499 -132.122167) (xy 47.263034 -132.186177) (xy 47.201737 -132.244624)
			(xy 47.135161 -132.296981) (xy 47.06391 -132.342771) (xy 46.988629 -132.381582) (xy 46.909999 -132.413061)
			(xy 46.828733 -132.436923) (xy 46.745567 -132.452953) (xy 46.661254 -132.461004) (xy 46.618906 -132.461508)
			(xy 46.618398 -132.461508) (xy 46.572066 -132.4609) (xy 46.479908 -132.451229) (xy 46.389254 -132.432034)
			(xy 46.301085 -132.403523) (xy 46.25848 -132.385308) (xy 46.248538 -132.381502) (xy 46.227274 -132.381502)
			(xy 46.217332 -132.385308) (xy 46.174728 -132.403528) (xy 46.086561 -132.432046) (xy 45.995906 -132.451239)
			(xy 45.903746 -132.4609) (xy 45.857414 -132.461508) (xy 45.856906 -132.461508) (xy 45.814557 -132.46102)
			(xy 45.730241 -132.45297) (xy 45.647073 -132.436941) (xy 45.565805 -132.413079) (xy 45.487173 -132.3816)
			(xy 45.411889 -132.342789) (xy 45.340636 -132.296998) (xy 45.274058 -132.24464) (xy 45.212758 -132.186192)
			(xy 45.157292 -132.122181) (xy 45.108162 -132.053187) (xy 45.065812 -131.979836) (xy 45.030627 -131.902791)
			(xy 45.002925 -131.822751) (xy 44.982956 -131.74044) (xy 44.970902 -131.656603) (xy 44.966872 -131.572)
			(xy 40.005 -131.572) (xy 40.005 -136.959232) (xy 45.624232 -136.959232) (xy 45.624232 -136.852768)
			(xy 45.632188 -136.746601) (xy 45.648055 -136.641325) (xy 45.671746 -136.53753) (xy 45.703127 -136.435795)
			(xy 45.742023 -136.33669) (xy 45.788216 -136.240768) (xy 45.841449 -136.148567) (xy 45.901422 -136.060602)
			(xy 45.967802 -135.977365) (xy 46.040216 -135.89932) (xy 46.118261 -135.826906) (xy 46.201498 -135.760526)
			(xy 46.289463 -135.700553) (xy 46.381664 -135.64732) (xy 46.477586 -135.601127) (xy 46.576691 -135.562231)
			(xy 46.678426 -135.53085) (xy 46.782221 -135.507159) (xy 46.887497 -135.491292) (xy 46.993664 -135.483336)
			(xy 47.100128 -135.483336) (xy 47.206295 -135.491292) (xy 47.311571 -135.507159) (xy 47.415366 -135.53085)
			(xy 47.517101 -135.562231) (xy 47.616206 -135.601127) (xy 47.712128 -135.64732) (xy 47.804329 -135.700553)
			(xy 47.892294 -135.760526) (xy 47.975531 -135.826906) (xy 48.053576 -135.89932) (xy 48.12599 -135.977365)
			(xy 48.19237 -136.060602) (xy 48.252343 -136.148567) (xy 48.305576 -136.240768) (xy 48.351769 -136.33669)
			(xy 48.390665 -136.435795) (xy 48.422046 -136.53753) (xy 48.445737 -136.641325) (xy 48.461604 -136.746601)
			(xy 48.46956 -136.852768) (xy 48.470058 -136.906) (xy 48.46956 -136.959232) (xy 57.816232 -136.959232)
			(xy 57.816232 -136.852768) (xy 57.824188 -136.746601) (xy 57.840055 -136.641325) (xy 57.863746 -136.53753)
			(xy 57.895127 -136.435795) (xy 57.934023 -136.33669) (xy 57.980216 -136.240768) (xy 58.033449 -136.148567)
			(xy 58.093422 -136.060602) (xy 58.159802 -135.977365) (xy 58.232216 -135.89932) (xy 58.310261 -135.826906)
			(xy 58.393498 -135.760526) (xy 58.481463 -135.700553) (xy 58.573664 -135.64732) (xy 58.669586 -135.601127)
			(xy 58.768691 -135.562231) (xy 58.870426 -135.53085) (xy 58.974221 -135.507159) (xy 59.079497 -135.491292)
			(xy 59.185664 -135.483336) (xy 59.292128 -135.483336) (xy 59.398295 -135.491292) (xy 59.503571 -135.507159)
			(xy 59.607366 -135.53085) (xy 59.709101 -135.562231) (xy 59.808206 -135.601127) (xy 59.904128 -135.64732)
			(xy 59.996329 -135.700553) (xy 60.084294 -135.760526) (xy 60.167531 -135.826906) (xy 60.245576 -135.89932)
			(xy 60.31799 -135.977365) (xy 60.38437 -136.060602) (xy 60.444343 -136.148567) (xy 60.497576 -136.240768)
			(xy 60.543769 -136.33669) (xy 60.582665 -136.435795) (xy 60.614046 -136.53753) (xy 60.637737 -136.641325)
			(xy 60.653604 -136.746601) (xy 60.66156 -136.852768) (xy 60.662058 -136.906) (xy 60.66156 -136.959232)
			(xy 70.008232 -136.959232) (xy 70.008232 -136.852768) (xy 70.016188 -136.746601) (xy 70.032055 -136.641325)
			(xy 70.055746 -136.53753) (xy 70.087127 -136.435795) (xy 70.126023 -136.33669) (xy 70.172216 -136.240768)
			(xy 70.225449 -136.148567) (xy 70.285422 -136.060602) (xy 70.351802 -135.977365) (xy 70.424216 -135.89932)
			(xy 70.502261 -135.826906) (xy 70.585498 -135.760526) (xy 70.673463 -135.700553) (xy 70.765664 -135.64732)
			(xy 70.861586 -135.601127) (xy 70.960691 -135.562231) (xy 71.062426 -135.53085) (xy 71.166221 -135.507159)
			(xy 71.271497 -135.491292) (xy 71.377664 -135.483336) (xy 71.484128 -135.483336) (xy 71.590295 -135.491292)
			(xy 71.695571 -135.507159) (xy 71.799366 -135.53085) (xy 71.901101 -135.562231) (xy 72.000206 -135.601127)
			(xy 72.096128 -135.64732) (xy 72.188329 -135.700553) (xy 72.276294 -135.760526) (xy 72.359531 -135.826906)
			(xy 72.437576 -135.89932) (xy 72.50999 -135.977365) (xy 72.57637 -136.060602) (xy 72.636343 -136.148567)
			(xy 72.689576 -136.240768) (xy 72.735769 -136.33669) (xy 72.774665 -136.435795) (xy 72.806046 -136.53753)
			(xy 72.829737 -136.641325) (xy 72.845604 -136.746601) (xy 72.85356 -136.852768) (xy 72.854058 -136.906)
			(xy 72.85356 -136.959232) (xy 85.624152 -136.959232) (xy 85.624152 -136.852768) (xy 85.632108 -136.746601)
			(xy 85.647975 -136.641325) (xy 85.671666 -136.53753) (xy 85.703047 -136.435795) (xy 85.741943 -136.33669)
			(xy 85.788136 -136.240768) (xy 85.841369 -136.148567) (xy 85.901342 -136.060602) (xy 85.967722 -135.977365)
			(xy 86.040136 -135.89932) (xy 86.118181 -135.826906) (xy 86.201418 -135.760526) (xy 86.289383 -135.700553)
			(xy 86.381584 -135.64732) (xy 86.477506 -135.601127) (xy 86.576611 -135.562231) (xy 86.678346 -135.53085)
			(xy 86.782141 -135.507159) (xy 86.887417 -135.491292) (xy 86.993584 -135.483336) (xy 87.100048 -135.483336)
			(xy 87.206215 -135.491292) (xy 87.311491 -135.507159) (xy 87.415286 -135.53085) (xy 87.517021 -135.562231)
			(xy 87.616126 -135.601127) (xy 87.712048 -135.64732) (xy 87.804249 -135.700553) (xy 87.892214 -135.760526)
			(xy 87.975451 -135.826906) (xy 88.053496 -135.89932) (xy 88.12591 -135.977365) (xy 88.19229 -136.060602)
			(xy 88.252263 -136.148567) (xy 88.305496 -136.240768) (xy 88.351689 -136.33669) (xy 88.390585 -136.435795)
			(xy 88.421966 -136.53753) (xy 88.445657 -136.641325) (xy 88.461524 -136.746601) (xy 88.46948 -136.852768)
			(xy 88.469978 -136.906) (xy 88.46948 -136.959232) (xy 97.816152 -136.959232) (xy 97.816152 -136.852768)
			(xy 97.824108 -136.746601) (xy 97.839975 -136.641325) (xy 97.863666 -136.53753) (xy 97.895047 -136.435795)
			(xy 97.933943 -136.33669) (xy 97.980136 -136.240768) (xy 98.033369 -136.148567) (xy 98.093342 -136.060602)
			(xy 98.159722 -135.977365) (xy 98.232136 -135.89932) (xy 98.310181 -135.826906) (xy 98.393418 -135.760526)
			(xy 98.481383 -135.700553) (xy 98.573584 -135.64732) (xy 98.669506 -135.601127) (xy 98.768611 -135.562231)
			(xy 98.870346 -135.53085) (xy 98.974141 -135.507159) (xy 99.079417 -135.491292) (xy 99.185584 -135.483336)
			(xy 99.292048 -135.483336) (xy 99.398215 -135.491292) (xy 99.503491 -135.507159) (xy 99.607286 -135.53085)
			(xy 99.709021 -135.562231) (xy 99.808126 -135.601127) (xy 99.904048 -135.64732) (xy 99.996249 -135.700553)
			(xy 100.084214 -135.760526) (xy 100.167451 -135.826906) (xy 100.245496 -135.89932) (xy 100.31791 -135.977365)
			(xy 100.38429 -136.060602) (xy 100.444263 -136.148567) (xy 100.497496 -136.240768) (xy 100.543689 -136.33669)
			(xy 100.582585 -136.435795) (xy 100.613966 -136.53753) (xy 100.637657 -136.641325) (xy 100.653524 -136.746601)
			(xy 100.66148 -136.852768) (xy 100.661978 -136.906) (xy 100.66148 -136.959232) (xy 110.008152 -136.959232)
			(xy 110.008152 -136.852768) (xy 110.016108 -136.746601) (xy 110.031975 -136.641325) (xy 110.055666 -136.53753)
			(xy 110.087047 -136.435795) (xy 110.125943 -136.33669) (xy 110.172136 -136.240768) (xy 110.225369 -136.148567)
			(xy 110.285342 -136.060602) (xy 110.351722 -135.977365) (xy 110.424136 -135.89932) (xy 110.502181 -135.826906)
			(xy 110.585418 -135.760526) (xy 110.673383 -135.700553) (xy 110.765584 -135.64732) (xy 110.861506 -135.601127)
			(xy 110.960611 -135.562231) (xy 111.062346 -135.53085) (xy 111.166141 -135.507159) (xy 111.271417 -135.491292)
			(xy 111.377584 -135.483336) (xy 111.484048 -135.483336) (xy 111.590215 -135.491292) (xy 111.695491 -135.507159)
			(xy 111.799286 -135.53085) (xy 111.901021 -135.562231) (xy 112.000126 -135.601127) (xy 112.096048 -135.64732)
			(xy 112.188249 -135.700553) (xy 112.276214 -135.760526) (xy 112.359451 -135.826906) (xy 112.437496 -135.89932)
			(xy 112.50991 -135.977365) (xy 112.57629 -136.060602) (xy 112.636263 -136.148567) (xy 112.689496 -136.240768)
			(xy 112.735689 -136.33669) (xy 112.774585 -136.435795) (xy 112.805966 -136.53753) (xy 112.829657 -136.641325)
			(xy 112.845524 -136.746601) (xy 112.85348 -136.852768) (xy 112.853978 -136.906) (xy 112.85348 -136.959232)
			(xy 125.624326 -136.959232) (xy 125.624326 -136.852768) (xy 125.632282 -136.746601) (xy 125.648149 -136.641325)
			(xy 125.67184 -136.53753) (xy 125.703221 -136.435795) (xy 125.742117 -136.33669) (xy 125.78831 -136.240768)
			(xy 125.841543 -136.148567) (xy 125.901516 -136.060602) (xy 125.967896 -135.977365) (xy 126.04031 -135.89932)
			(xy 126.118355 -135.826906) (xy 126.201592 -135.760526) (xy 126.289557 -135.700553) (xy 126.381758 -135.64732)
			(xy 126.47768 -135.601127) (xy 126.576785 -135.562231) (xy 126.67852 -135.53085) (xy 126.782315 -135.507159)
			(xy 126.887591 -135.491292) (xy 126.993758 -135.483336) (xy 127.100222 -135.483336) (xy 127.206389 -135.491292)
			(xy 127.311665 -135.507159) (xy 127.41546 -135.53085) (xy 127.517195 -135.562231) (xy 127.6163 -135.601127)
			(xy 127.712222 -135.64732) (xy 127.804423 -135.700553) (xy 127.892388 -135.760526) (xy 127.975625 -135.826906)
			(xy 128.05367 -135.89932) (xy 128.126084 -135.977365) (xy 128.192464 -136.060602) (xy 128.252437 -136.148567)
			(xy 128.30567 -136.240768) (xy 128.351863 -136.33669) (xy 128.390759 -136.435795) (xy 128.42214 -136.53753)
			(xy 128.445831 -136.641325) (xy 128.461698 -136.746601) (xy 128.469654 -136.852768) (xy 128.470152 -136.906)
			(xy 128.469654 -136.959232) (xy 137.816326 -136.959232) (xy 137.816326 -136.852768) (xy 137.824282 -136.746601)
			(xy 137.840149 -136.641325) (xy 137.86384 -136.53753) (xy 137.895221 -136.435795) (xy 137.934117 -136.33669)
			(xy 137.98031 -136.240768) (xy 138.033543 -136.148567) (xy 138.093516 -136.060602) (xy 138.159896 -135.977365)
			(xy 138.23231 -135.89932) (xy 138.310355 -135.826906) (xy 138.393592 -135.760526) (xy 138.481557 -135.700553)
			(xy 138.573758 -135.64732) (xy 138.66968 -135.601127) (xy 138.768785 -135.562231) (xy 138.87052 -135.53085)
			(xy 138.974315 -135.507159) (xy 139.079591 -135.491292) (xy 139.185758 -135.483336) (xy 139.292222 -135.483336)
			(xy 139.398389 -135.491292) (xy 139.503665 -135.507159) (xy 139.60746 -135.53085) (xy 139.709195 -135.562231)
			(xy 139.8083 -135.601127) (xy 139.904222 -135.64732) (xy 139.996423 -135.700553) (xy 140.084388 -135.760526)
			(xy 140.167625 -135.826906) (xy 140.24567 -135.89932) (xy 140.318084 -135.977365) (xy 140.384464 -136.060602)
			(xy 140.444437 -136.148567) (xy 140.49767 -136.240768) (xy 140.543863 -136.33669) (xy 140.582759 -136.435795)
			(xy 140.61414 -136.53753) (xy 140.637831 -136.641325) (xy 140.653698 -136.746601) (xy 140.661654 -136.852768)
			(xy 140.662152 -136.906) (xy 140.661654 -136.959232) (xy 150.008326 -136.959232) (xy 150.008326 -136.852768)
			(xy 150.016282 -136.746601) (xy 150.032149 -136.641325) (xy 150.05584 -136.53753) (xy 150.087221 -136.435795)
			(xy 150.126117 -136.33669) (xy 150.17231 -136.240768) (xy 150.225543 -136.148567) (xy 150.285516 -136.060602)
			(xy 150.351896 -135.977365) (xy 150.42431 -135.89932) (xy 150.502355 -135.826906) (xy 150.585592 -135.760526)
			(xy 150.673557 -135.700553) (xy 150.765758 -135.64732) (xy 150.86168 -135.601127) (xy 150.960785 -135.562231)
			(xy 151.06252 -135.53085) (xy 151.166315 -135.507159) (xy 151.271591 -135.491292) (xy 151.377758 -135.483336)
			(xy 151.484222 -135.483336) (xy 151.590389 -135.491292) (xy 151.695665 -135.507159) (xy 151.79946 -135.53085)
			(xy 151.901195 -135.562231) (xy 152.0003 -135.601127) (xy 152.096222 -135.64732) (xy 152.188423 -135.700553)
			(xy 152.276388 -135.760526) (xy 152.359625 -135.826906) (xy 152.43767 -135.89932) (xy 152.510084 -135.977365)
			(xy 152.576464 -136.060602) (xy 152.636437 -136.148567) (xy 152.68967 -136.240768) (xy 152.735863 -136.33669)
			(xy 152.774759 -136.435795) (xy 152.80614 -136.53753) (xy 152.829831 -136.641325) (xy 152.845698 -136.746601)
			(xy 152.853654 -136.852768) (xy 152.854152 -136.906) (xy 152.853654 -136.959232) (xy 165.6245 -136.959232)
			(xy 165.6245 -136.852768) (xy 165.632456 -136.746601) (xy 165.648323 -136.641325) (xy 165.672014 -136.53753)
			(xy 165.703395 -136.435795) (xy 165.742291 -136.33669) (xy 165.788484 -136.240768) (xy 165.841717 -136.148567)
			(xy 165.90169 -136.060602) (xy 165.96807 -135.977365) (xy 166.040484 -135.89932) (xy 166.118529 -135.826906)
			(xy 166.201766 -135.760526) (xy 166.289731 -135.700553) (xy 166.381932 -135.64732) (xy 166.477854 -135.601127)
			(xy 166.576959 -135.562231) (xy 166.678694 -135.53085) (xy 166.782489 -135.507159) (xy 166.887765 -135.491292)
			(xy 166.993932 -135.483336) (xy 167.100396 -135.483336) (xy 167.206563 -135.491292) (xy 167.311839 -135.507159)
			(xy 167.415634 -135.53085) (xy 167.517369 -135.562231) (xy 167.616474 -135.601127) (xy 167.712396 -135.64732)
			(xy 167.804597 -135.700553) (xy 167.892562 -135.760526) (xy 167.975799 -135.826906) (xy 168.053844 -135.89932)
			(xy 168.126258 -135.977365) (xy 168.192638 -136.060602) (xy 168.252611 -136.148567) (xy 168.305844 -136.240768)
			(xy 168.352037 -136.33669) (xy 168.390933 -136.435795) (xy 168.422314 -136.53753) (xy 168.446005 -136.641325)
			(xy 168.461872 -136.746601) (xy 168.469828 -136.852768) (xy 168.470326 -136.906) (xy 168.469828 -136.959232)
			(xy 177.8165 -136.959232) (xy 177.8165 -136.852768) (xy 177.824456 -136.746601) (xy 177.840323 -136.641325)
			(xy 177.864014 -136.53753) (xy 177.895395 -136.435795) (xy 177.934291 -136.33669) (xy 177.980484 -136.240768)
			(xy 178.033717 -136.148567) (xy 178.09369 -136.060602) (xy 178.16007 -135.977365) (xy 178.232484 -135.89932)
			(xy 178.310529 -135.826906) (xy 178.393766 -135.760526) (xy 178.481731 -135.700553) (xy 178.573932 -135.64732)
			(xy 178.669854 -135.601127) (xy 178.768959 -135.562231) (xy 178.870694 -135.53085) (xy 178.974489 -135.507159)
			(xy 179.079765 -135.491292) (xy 179.185932 -135.483336) (xy 179.292396 -135.483336) (xy 179.398563 -135.491292)
			(xy 179.503839 -135.507159) (xy 179.607634 -135.53085) (xy 179.709369 -135.562231) (xy 179.808474 -135.601127)
			(xy 179.904396 -135.64732) (xy 179.996597 -135.700553) (xy 180.084562 -135.760526) (xy 180.167799 -135.826906)
			(xy 180.245844 -135.89932) (xy 180.318258 -135.977365) (xy 180.384638 -136.060602) (xy 180.444611 -136.148567)
			(xy 180.497844 -136.240768) (xy 180.544037 -136.33669) (xy 180.582933 -136.435795) (xy 180.614314 -136.53753)
			(xy 180.638005 -136.641325) (xy 180.653872 -136.746601) (xy 180.661828 -136.852768) (xy 180.662326 -136.906)
			(xy 180.661828 -136.959232) (xy 190.0085 -136.959232) (xy 190.0085 -136.852768) (xy 190.016456 -136.746601)
			(xy 190.032323 -136.641325) (xy 190.056014 -136.53753) (xy 190.087395 -136.435795) (xy 190.126291 -136.33669)
			(xy 190.172484 -136.240768) (xy 190.225717 -136.148567) (xy 190.28569 -136.060602) (xy 190.35207 -135.977365)
			(xy 190.424484 -135.89932) (xy 190.502529 -135.826906) (xy 190.585766 -135.760526) (xy 190.673731 -135.700553)
			(xy 190.765932 -135.64732) (xy 190.861854 -135.601127) (xy 190.960959 -135.562231) (xy 191.062694 -135.53085)
			(xy 191.166489 -135.507159) (xy 191.271765 -135.491292) (xy 191.377932 -135.483336) (xy 191.484396 -135.483336)
			(xy 191.590563 -135.491292) (xy 191.695839 -135.507159) (xy 191.799634 -135.53085) (xy 191.901369 -135.562231)
			(xy 192.000474 -135.601127) (xy 192.096396 -135.64732) (xy 192.188597 -135.700553) (xy 192.276562 -135.760526)
			(xy 192.359799 -135.826906) (xy 192.437844 -135.89932) (xy 192.510258 -135.977365) (xy 192.576638 -136.060602)
			(xy 192.636611 -136.148567) (xy 192.689844 -136.240768) (xy 192.736037 -136.33669) (xy 192.774933 -136.435795)
			(xy 192.806314 -136.53753) (xy 192.830005 -136.641325) (xy 192.845872 -136.746601) (xy 192.853828 -136.852768)
			(xy 192.854326 -136.906) (xy 192.853828 -136.959232) (xy 192.845872 -137.065399) (xy 192.830005 -137.170675)
			(xy 192.806314 -137.27447) (xy 192.774933 -137.376205) (xy 192.736037 -137.47531) (xy 192.689844 -137.571232)
			(xy 192.636611 -137.663433) (xy 192.576638 -137.751398) (xy 192.510258 -137.834635) (xy 192.437844 -137.91268)
			(xy 192.359799 -137.985094) (xy 192.276562 -138.051474) (xy 192.188597 -138.111447) (xy 192.096396 -138.16468)
			(xy 192.000474 -138.210873) (xy 191.901369 -138.249769) (xy 191.799634 -138.28115) (xy 191.695839 -138.304841)
			(xy 191.590563 -138.320708) (xy 191.484396 -138.328664) (xy 191.377932 -138.328664) (xy 191.271765 -138.320708)
			(xy 191.166489 -138.304841) (xy 191.062694 -138.28115) (xy 190.960959 -138.249769) (xy 190.861854 -138.210873)
			(xy 190.765932 -138.16468) (xy 190.673731 -138.111447) (xy 190.585766 -138.051474) (xy 190.502529 -137.985094)
			(xy 190.424484 -137.91268) (xy 190.35207 -137.834635) (xy 190.28569 -137.751398) (xy 190.225717 -137.663433)
			(xy 190.172484 -137.571232) (xy 190.126291 -137.47531) (xy 190.087395 -137.376205) (xy 190.056014 -137.27447)
			(xy 190.032323 -137.170675) (xy 190.016456 -137.065399) (xy 190.0085 -136.959232) (xy 180.661828 -136.959232)
			(xy 180.653872 -137.065399) (xy 180.638005 -137.170675) (xy 180.614314 -137.27447) (xy 180.582933 -137.376205)
			(xy 180.544037 -137.47531) (xy 180.497844 -137.571232) (xy 180.444611 -137.663433) (xy 180.384638 -137.751398)
			(xy 180.318258 -137.834635) (xy 180.245844 -137.91268) (xy 180.167799 -137.985094) (xy 180.084562 -138.051474)
			(xy 179.996597 -138.111447) (xy 179.904396 -138.16468) (xy 179.808474 -138.210873) (xy 179.709369 -138.249769)
			(xy 179.607634 -138.28115) (xy 179.503839 -138.304841) (xy 179.398563 -138.320708) (xy 179.292396 -138.328664)
			(xy 179.185932 -138.328664) (xy 179.079765 -138.320708) (xy 178.974489 -138.304841) (xy 178.870694 -138.28115)
			(xy 178.768959 -138.249769) (xy 178.669854 -138.210873) (xy 178.573932 -138.16468) (xy 178.481731 -138.111447)
			(xy 178.393766 -138.051474) (xy 178.310529 -137.985094) (xy 178.232484 -137.91268) (xy 178.16007 -137.834635)
			(xy 178.09369 -137.751398) (xy 178.033717 -137.663433) (xy 177.980484 -137.571232) (xy 177.934291 -137.47531)
			(xy 177.895395 -137.376205) (xy 177.864014 -137.27447) (xy 177.840323 -137.170675) (xy 177.824456 -137.065399)
			(xy 177.8165 -136.959232) (xy 168.469828 -136.959232) (xy 168.461872 -137.065399) (xy 168.446005 -137.170675)
			(xy 168.422314 -137.27447) (xy 168.390933 -137.376205) (xy 168.352037 -137.47531) (xy 168.305844 -137.571232)
			(xy 168.252611 -137.663433) (xy 168.192638 -137.751398) (xy 168.126258 -137.834635) (xy 168.053844 -137.91268)
			(xy 167.975799 -137.985094) (xy 167.892562 -138.051474) (xy 167.804597 -138.111447) (xy 167.712396 -138.16468)
			(xy 167.616474 -138.210873) (xy 167.517369 -138.249769) (xy 167.415634 -138.28115) (xy 167.311839 -138.304841)
			(xy 167.206563 -138.320708) (xy 167.100396 -138.328664) (xy 166.993932 -138.328664) (xy 166.887765 -138.320708)
			(xy 166.782489 -138.304841) (xy 166.678694 -138.28115) (xy 166.576959 -138.249769) (xy 166.477854 -138.210873)
			(xy 166.381932 -138.16468) (xy 166.289731 -138.111447) (xy 166.201766 -138.051474) (xy 166.118529 -137.985094)
			(xy 166.040484 -137.91268) (xy 165.96807 -137.834635) (xy 165.90169 -137.751398) (xy 165.841717 -137.663433)
			(xy 165.788484 -137.571232) (xy 165.742291 -137.47531) (xy 165.703395 -137.376205) (xy 165.672014 -137.27447)
			(xy 165.648323 -137.170675) (xy 165.632456 -137.065399) (xy 165.6245 -136.959232) (xy 152.853654 -136.959232)
			(xy 152.845698 -137.065399) (xy 152.829831 -137.170675) (xy 152.80614 -137.27447) (xy 152.774759 -137.376205)
			(xy 152.735863 -137.47531) (xy 152.68967 -137.571232) (xy 152.636437 -137.663433) (xy 152.576464 -137.751398)
			(xy 152.510084 -137.834635) (xy 152.43767 -137.91268) (xy 152.359625 -137.985094) (xy 152.276388 -138.051474)
			(xy 152.188423 -138.111447) (xy 152.096222 -138.16468) (xy 152.0003 -138.210873) (xy 151.901195 -138.249769)
			(xy 151.79946 -138.28115) (xy 151.695665 -138.304841) (xy 151.590389 -138.320708) (xy 151.484222 -138.328664)
			(xy 151.377758 -138.328664) (xy 151.271591 -138.320708) (xy 151.166315 -138.304841) (xy 151.06252 -138.28115)
			(xy 150.960785 -138.249769) (xy 150.86168 -138.210873) (xy 150.765758 -138.16468) (xy 150.673557 -138.111447)
			(xy 150.585592 -138.051474) (xy 150.502355 -137.985094) (xy 150.42431 -137.91268) (xy 150.351896 -137.834635)
			(xy 150.285516 -137.751398) (xy 150.225543 -137.663433) (xy 150.17231 -137.571232) (xy 150.126117 -137.47531)
			(xy 150.087221 -137.376205) (xy 150.05584 -137.27447) (xy 150.032149 -137.170675) (xy 150.016282 -137.065399)
			(xy 150.008326 -136.959232) (xy 140.661654 -136.959232) (xy 140.653698 -137.065399) (xy 140.637831 -137.170675)
			(xy 140.61414 -137.27447) (xy 140.582759 -137.376205) (xy 140.543863 -137.47531) (xy 140.49767 -137.571232)
			(xy 140.444437 -137.663433) (xy 140.384464 -137.751398) (xy 140.318084 -137.834635) (xy 140.24567 -137.91268)
			(xy 140.167625 -137.985094) (xy 140.084388 -138.051474) (xy 139.996423 -138.111447) (xy 139.904222 -138.16468)
			(xy 139.8083 -138.210873) (xy 139.709195 -138.249769) (xy 139.60746 -138.28115) (xy 139.503665 -138.304841)
			(xy 139.398389 -138.320708) (xy 139.292222 -138.328664) (xy 139.185758 -138.328664) (xy 139.079591 -138.320708)
			(xy 138.974315 -138.304841) (xy 138.87052 -138.28115) (xy 138.768785 -138.249769) (xy 138.66968 -138.210873)
			(xy 138.573758 -138.16468) (xy 138.481557 -138.111447) (xy 138.393592 -138.051474) (xy 138.310355 -137.985094)
			(xy 138.23231 -137.91268) (xy 138.159896 -137.834635) (xy 138.093516 -137.751398) (xy 138.033543 -137.663433)
			(xy 137.98031 -137.571232) (xy 137.934117 -137.47531) (xy 137.895221 -137.376205) (xy 137.86384 -137.27447)
			(xy 137.840149 -137.170675) (xy 137.824282 -137.065399) (xy 137.816326 -136.959232) (xy 128.469654 -136.959232)
			(xy 128.461698 -137.065399) (xy 128.445831 -137.170675) (xy 128.42214 -137.27447) (xy 128.390759 -137.376205)
			(xy 128.351863 -137.47531) (xy 128.30567 -137.571232) (xy 128.252437 -137.663433) (xy 128.192464 -137.751398)
			(xy 128.126084 -137.834635) (xy 128.05367 -137.91268) (xy 127.975625 -137.985094) (xy 127.892388 -138.051474)
			(xy 127.804423 -138.111447) (xy 127.712222 -138.16468) (xy 127.6163 -138.210873) (xy 127.517195 -138.249769)
			(xy 127.41546 -138.28115) (xy 127.311665 -138.304841) (xy 127.206389 -138.320708) (xy 127.100222 -138.328664)
			(xy 126.993758 -138.328664) (xy 126.887591 -138.320708) (xy 126.782315 -138.304841) (xy 126.67852 -138.28115)
			(xy 126.576785 -138.249769) (xy 126.47768 -138.210873) (xy 126.381758 -138.16468) (xy 126.289557 -138.111447)
			(xy 126.201592 -138.051474) (xy 126.118355 -137.985094) (xy 126.04031 -137.91268) (xy 125.967896 -137.834635)
			(xy 125.901516 -137.751398) (xy 125.841543 -137.663433) (xy 125.78831 -137.571232) (xy 125.742117 -137.47531)
			(xy 125.703221 -137.376205) (xy 125.67184 -137.27447) (xy 125.648149 -137.170675) (xy 125.632282 -137.065399)
			(xy 125.624326 -136.959232) (xy 112.85348 -136.959232) (xy 112.845524 -137.065399) (xy 112.829657 -137.170675)
			(xy 112.805966 -137.27447) (xy 112.774585 -137.376205) (xy 112.735689 -137.47531) (xy 112.689496 -137.571232)
			(xy 112.636263 -137.663433) (xy 112.57629 -137.751398) (xy 112.50991 -137.834635) (xy 112.437496 -137.91268)
			(xy 112.359451 -137.985094) (xy 112.276214 -138.051474) (xy 112.188249 -138.111447) (xy 112.096048 -138.16468)
			(xy 112.000126 -138.210873) (xy 111.901021 -138.249769) (xy 111.799286 -138.28115) (xy 111.695491 -138.304841)
			(xy 111.590215 -138.320708) (xy 111.484048 -138.328664) (xy 111.377584 -138.328664) (xy 111.271417 -138.320708)
			(xy 111.166141 -138.304841) (xy 111.062346 -138.28115) (xy 110.960611 -138.249769) (xy 110.861506 -138.210873)
			(xy 110.765584 -138.16468) (xy 110.673383 -138.111447) (xy 110.585418 -138.051474) (xy 110.502181 -137.985094)
			(xy 110.424136 -137.91268) (xy 110.351722 -137.834635) (xy 110.285342 -137.751398) (xy 110.225369 -137.663433)
			(xy 110.172136 -137.571232) (xy 110.125943 -137.47531) (xy 110.087047 -137.376205) (xy 110.055666 -137.27447)
			(xy 110.031975 -137.170675) (xy 110.016108 -137.065399) (xy 110.008152 -136.959232) (xy 100.66148 -136.959232)
			(xy 100.653524 -137.065399) (xy 100.637657 -137.170675) (xy 100.613966 -137.27447) (xy 100.582585 -137.376205)
			(xy 100.543689 -137.47531) (xy 100.497496 -137.571232) (xy 100.444263 -137.663433) (xy 100.38429 -137.751398)
			(xy 100.31791 -137.834635) (xy 100.245496 -137.91268) (xy 100.167451 -137.985094) (xy 100.084214 -138.051474)
			(xy 99.996249 -138.111447) (xy 99.904048 -138.16468) (xy 99.808126 -138.210873) (xy 99.709021 -138.249769)
			(xy 99.607286 -138.28115) (xy 99.503491 -138.304841) (xy 99.398215 -138.320708) (xy 99.292048 -138.328664)
			(xy 99.185584 -138.328664) (xy 99.079417 -138.320708) (xy 98.974141 -138.304841) (xy 98.870346 -138.28115)
			(xy 98.768611 -138.249769) (xy 98.669506 -138.210873) (xy 98.573584 -138.16468) (xy 98.481383 -138.111447)
			(xy 98.393418 -138.051474) (xy 98.310181 -137.985094) (xy 98.232136 -137.91268) (xy 98.159722 -137.834635)
			(xy 98.093342 -137.751398) (xy 98.033369 -137.663433) (xy 97.980136 -137.571232) (xy 97.933943 -137.47531)
			(xy 97.895047 -137.376205) (xy 97.863666 -137.27447) (xy 97.839975 -137.170675) (xy 97.824108 -137.065399)
			(xy 97.816152 -136.959232) (xy 88.46948 -136.959232) (xy 88.461524 -137.065399) (xy 88.445657 -137.170675)
			(xy 88.421966 -137.27447) (xy 88.390585 -137.376205) (xy 88.351689 -137.47531) (xy 88.305496 -137.571232)
			(xy 88.252263 -137.663433) (xy 88.19229 -137.751398) (xy 88.12591 -137.834635) (xy 88.053496 -137.91268)
			(xy 87.975451 -137.985094) (xy 87.892214 -138.051474) (xy 87.804249 -138.111447) (xy 87.712048 -138.16468)
			(xy 87.616126 -138.210873) (xy 87.517021 -138.249769) (xy 87.415286 -138.28115) (xy 87.311491 -138.304841)
			(xy 87.206215 -138.320708) (xy 87.100048 -138.328664) (xy 86.993584 -138.328664) (xy 86.887417 -138.320708)
			(xy 86.782141 -138.304841) (xy 86.678346 -138.28115) (xy 86.576611 -138.249769) (xy 86.477506 -138.210873)
			(xy 86.381584 -138.16468) (xy 86.289383 -138.111447) (xy 86.201418 -138.051474) (xy 86.118181 -137.985094)
			(xy 86.040136 -137.91268) (xy 85.967722 -137.834635) (xy 85.901342 -137.751398) (xy 85.841369 -137.663433)
			(xy 85.788136 -137.571232) (xy 85.741943 -137.47531) (xy 85.703047 -137.376205) (xy 85.671666 -137.27447)
			(xy 85.647975 -137.170675) (xy 85.632108 -137.065399) (xy 85.624152 -136.959232) (xy 72.85356 -136.959232)
			(xy 72.845604 -137.065399) (xy 72.829737 -137.170675) (xy 72.806046 -137.27447) (xy 72.774665 -137.376205)
			(xy 72.735769 -137.47531) (xy 72.689576 -137.571232) (xy 72.636343 -137.663433) (xy 72.57637 -137.751398)
			(xy 72.50999 -137.834635) (xy 72.437576 -137.91268) (xy 72.359531 -137.985094) (xy 72.276294 -138.051474)
			(xy 72.188329 -138.111447) (xy 72.096128 -138.16468) (xy 72.000206 -138.210873) (xy 71.901101 -138.249769)
			(xy 71.799366 -138.28115) (xy 71.695571 -138.304841) (xy 71.590295 -138.320708) (xy 71.484128 -138.328664)
			(xy 71.377664 -138.328664) (xy 71.271497 -138.320708) (xy 71.166221 -138.304841) (xy 71.062426 -138.28115)
			(xy 70.960691 -138.249769) (xy 70.861586 -138.210873) (xy 70.765664 -138.16468) (xy 70.673463 -138.111447)
			(xy 70.585498 -138.051474) (xy 70.502261 -137.985094) (xy 70.424216 -137.91268) (xy 70.351802 -137.834635)
			(xy 70.285422 -137.751398) (xy 70.225449 -137.663433) (xy 70.172216 -137.571232) (xy 70.126023 -137.47531)
			(xy 70.087127 -137.376205) (xy 70.055746 -137.27447) (xy 70.032055 -137.170675) (xy 70.016188 -137.065399)
			(xy 70.008232 -136.959232) (xy 60.66156 -136.959232) (xy 60.653604 -137.065399) (xy 60.637737 -137.170675)
			(xy 60.614046 -137.27447) (xy 60.582665 -137.376205) (xy 60.543769 -137.47531) (xy 60.497576 -137.571232)
			(xy 60.444343 -137.663433) (xy 60.38437 -137.751398) (xy 60.31799 -137.834635) (xy 60.245576 -137.91268)
			(xy 60.167531 -137.985094) (xy 60.084294 -138.051474) (xy 59.996329 -138.111447) (xy 59.904128 -138.16468)
			(xy 59.808206 -138.210873) (xy 59.709101 -138.249769) (xy 59.607366 -138.28115) (xy 59.503571 -138.304841)
			(xy 59.398295 -138.320708) (xy 59.292128 -138.328664) (xy 59.185664 -138.328664) (xy 59.079497 -138.320708)
			(xy 58.974221 -138.304841) (xy 58.870426 -138.28115) (xy 58.768691 -138.249769) (xy 58.669586 -138.210873)
			(xy 58.573664 -138.16468) (xy 58.481463 -138.111447) (xy 58.393498 -138.051474) (xy 58.310261 -137.985094)
			(xy 58.232216 -137.91268) (xy 58.159802 -137.834635) (xy 58.093422 -137.751398) (xy 58.033449 -137.663433)
			(xy 57.980216 -137.571232) (xy 57.934023 -137.47531) (xy 57.895127 -137.376205) (xy 57.863746 -137.27447)
			(xy 57.840055 -137.170675) (xy 57.824188 -137.065399) (xy 57.816232 -136.959232) (xy 48.46956 -136.959232)
			(xy 48.461604 -137.065399) (xy 48.445737 -137.170675) (xy 48.422046 -137.27447) (xy 48.390665 -137.376205)
			(xy 48.351769 -137.47531) (xy 48.305576 -137.571232) (xy 48.252343 -137.663433) (xy 48.19237 -137.751398)
			(xy 48.12599 -137.834635) (xy 48.053576 -137.91268) (xy 47.975531 -137.985094) (xy 47.892294 -138.051474)
			(xy 47.804329 -138.111447) (xy 47.712128 -138.16468) (xy 47.616206 -138.210873) (xy 47.517101 -138.249769)
			(xy 47.415366 -138.28115) (xy 47.311571 -138.304841) (xy 47.206295 -138.320708) (xy 47.100128 -138.328664)
			(xy 46.993664 -138.328664) (xy 46.887497 -138.320708) (xy 46.782221 -138.304841) (xy 46.678426 -138.28115)
			(xy 46.576691 -138.249769) (xy 46.477586 -138.210873) (xy 46.381664 -138.16468) (xy 46.289463 -138.111447)
			(xy 46.201498 -138.051474) (xy 46.118261 -137.985094) (xy 46.040216 -137.91268) (xy 45.967802 -137.834635)
			(xy 45.901422 -137.751398) (xy 45.841449 -137.663433) (xy 45.788216 -137.571232) (xy 45.742023 -137.47531)
			(xy 45.703127 -137.376205) (xy 45.671746 -137.27447) (xy 45.648055 -137.170675) (xy 45.632188 -137.065399)
			(xy 45.624232 -136.959232) (xy 40.005 -136.959232) (xy 40.005 -144.86255) (xy 40.005432 -144.872616)
			(xy 40.01316 -144.891207) (xy 40.019986 -144.898618) (xy 41.090342 -145.968974) (xy 41.097741 -145.975817)
			(xy 41.11634 -145.98354) (xy 41.12641 -145.98396)
		)
		(stroke
			(width 0)
			(type solid)
		)
		(fill yes)
		(layer "In4.Cu")
		(net "P52V_HS_FILTER")
	)
	(gr_poly
		(pts
			(xy 78.2447 -74.324972) (xy 78.25477 -74.324548) (xy 78.273371 -74.316831) (xy 78.280768 -74.309986)
			(xy 86.573614 -66.01714) (xy 86.597493 -65.993982) (xy 86.650256 -65.953473) (xy 86.707857 -65.9202)
			(xy 86.769309 -65.894732) (xy 86.83356 -65.877506) (xy 86.89951 -65.868817) (xy 86.93277 -65.868296)
			(xy 199.728074 -65.868296) (xy 199.737215 -65.867916) (xy 199.754331 -65.861495) (xy 199.768094 -65.849463)
			(xy 199.776746 -65.833359) (xy 199.778366 -65.824354) (xy 199.778366 -65.8241) (xy 199.784492 -65.781884)
			(xy 199.803793 -65.698787) (xy 199.830963 -65.617919) (xy 199.86575 -65.540024) (xy 199.907836 -65.465818)
			(xy 199.956834 -65.395983) (xy 200.012294 -65.33116) (xy 200.073706 -65.271946) (xy 200.140505 -65.218883)
			(xy 200.212079 -65.172461) (xy 200.287768 -65.133105) (xy 200.366878 -65.101178) (xy 200.448682 -65.076972)
			(xy 200.532427 -65.06071) (xy 200.617345 -65.052541) (xy 200.702655 -65.052541) (xy 200.787573 -65.06071)
			(xy 200.871318 -65.076972) (xy 200.953122 -65.101178) (xy 201.032232 -65.133105) (xy 201.107921 -65.172461)
			(xy 201.179495 -65.218883) (xy 201.246294 -65.271946) (xy 201.307706 -65.33116) (xy 201.363166 -65.395983)
			(xy 201.412164 -65.465818) (xy 201.45425 -65.540024) (xy 201.489037 -65.617919) (xy 201.516207 -65.698787)
			(xy 201.535508 -65.781884) (xy 201.541634 -65.8241) (xy 201.541634 -65.824354) (xy 201.543245 -65.833361)
			(xy 201.55191 -65.84946) (xy 201.565674 -65.861495) (xy 201.582785 -65.867935) (xy 201.591926 -65.868296)
			(xy 201.72045 -65.868296) (xy 201.729754 -65.867878) (xy 201.747133 -65.861227) (xy 201.761 -65.848819)
			(xy 201.769533 -65.832282) (xy 201.770996 -65.823084) (xy 201.776348 -65.780154) (xy 201.794329 -65.695526)
			(xy 201.820443 -65.613043) (xy 201.854441 -65.533485) (xy 201.896004 -65.457604) (xy 201.944737 -65.386117)
			(xy 202.000182 -65.3197) (xy 202.061813 -65.25898) (xy 202.129048 -65.20453) (xy 202.201252 -65.156866)
			(xy 202.277743 -65.116438) (xy 202.357799 -65.083627) (xy 202.440661 -65.058745) (xy 202.525548 -65.042025)
			(xy 202.611657 -65.033626) (xy 202.654916 -65.033144) (xy 202.694779 -65.033603) (xy 202.774183 -65.040763)
			(xy 202.852627 -65.054998) (xy 202.929484 -65.076194) (xy 203.004137 -65.10418) (xy 203.075986 -65.138732)
			(xy 203.144457 -65.179574) (xy 203.208999 -65.226377) (xy 203.269095 -65.278766) (xy 203.297028 -65.30721)
			(xy 203.304394 -65.31483) (xy 203.32319 -65.322958) (xy 203.407518 -65.32245) (xy 203.417786 -65.321924)
			(xy 203.436651 -65.313795) (xy 203.444094 -65.306702) (xy 203.472023 -65.277941) (xy 203.532248 -65.225017)
			(xy 203.596992 -65.177728) (xy 203.665729 -65.136457) (xy 203.737902 -65.10154) (xy 203.812924 -65.07326)
			(xy 203.890186 -65.051847) (xy 203.969063 -65.037474) (xy 204.048912 -65.030259) (xy 204.089 -65.029842)
			(xy 204.131568 -65.03034) (xy 204.216314 -65.038471) (xy 204.299896 -65.054659) (xy 204.38155 -65.078755)
			(xy 204.460529 -65.11054) (xy 204.536111 -65.149723) (xy 204.607606 -65.195946) (xy 204.67436 -65.248785)
			(xy 204.735761 -65.307758) (xy 204.763878 -65.339722) (xy 204.771244 -65.348612) (xy 204.791818 -65.357756)
			(xy 204.881226 -65.356486) (xy 204.892449 -65.355733) (xy 204.912625 -65.345851) (xy 204.920088 -65.337436)
			(xy 204.948188 -65.303391) (xy 205.010086 -65.240443) (xy 205.077914 -65.183937) (xy 205.151007 -65.134427)
			(xy 205.228644 -65.092403) (xy 205.310063 -65.058276) (xy 205.394462 -65.032383) (xy 205.481012 -65.014977)
			(xy 205.568859 -65.006232) (xy 205.613 -65.005712) (xy 205.65438 -65.006185) (xy 205.736782 -65.01387)
			(xy 205.818114 -65.029173) (xy 205.897674 -65.051963) (xy 205.974774 -65.082042) (xy 206.048748 -65.119151)
			(xy 206.118956 -65.162969) (xy 206.184792 -65.213116) (xy 206.245687 -65.269161) (xy 206.301115 -65.330617)
			(xy 206.350596 -65.396956) (xy 206.393703 -65.467602) (xy 206.430064 -65.541946) (xy 206.459364 -65.619346)
			(xy 206.481351 -65.699131) (xy 206.495834 -65.780614) (xy 206.499714 -65.821814) (xy 206.501238 -65.841372)
			(xy 206.530448 -65.868296) (xy 208.933542 -65.868296) (xy 208.943583 -65.867864) (xy 208.962124 -65.860148)
			(xy 208.976289 -65.845913) (xy 208.980532 -65.8368) (xy 208.997602 -65.796398) (xy 209.038597 -65.718854)
			(xy 209.087025 -65.645721) (xy 209.142416 -65.57771) (xy 209.204233 -65.515482) (xy 209.271875 -65.45964)
			(xy 209.344685 -65.410728) (xy 209.421955 -65.369219) (xy 209.502936 -65.335518) (xy 209.586841 -65.309952)
			(xy 209.672855 -65.292769) (xy 209.760143 -65.284135) (xy 209.804 -65.283588) (xy 209.843758 -65.284041)
			(xy 209.922955 -65.29116) (xy 210.001201 -65.305316) (xy 210.077873 -65.326394) (xy 210.152359 -65.354228)
			(xy 210.224065 -65.388594) (xy 210.29242 -65.42922) (xy 210.356879 -65.475781) (xy 210.387184 -65.50152)
			(xy 210.394414 -65.507271) (xy 210.411733 -65.513666) (xy 210.420966 -65.513966) (xy 210.450684 -65.513966)
			(xy 210.459837 -65.513498) (xy 210.476904 -65.506862) (xy 210.483958 -65.501012) (xy 210.514416 -65.474635)
			(xy 210.57932 -65.426881) (xy 210.64828 -65.385199) (xy 210.720729 -65.349928) (xy 210.796073 -65.32136)
			(xy 210.873694 -65.299728) (xy 210.952954 -65.28521) (xy 211.033203 -65.277925) (xy 211.073492 -65.277492)
			(xy 211.074 -65.277492) (xy 211.114047 -65.277919) (xy 211.193819 -65.285094) (xy 211.272623 -65.299414)
			(xy 211.34982 -65.320763) (xy 211.424784 -65.348967) (xy 211.496908 -65.383798) (xy 211.565608 -65.424974)
			(xy 211.630326 -65.47216) (xy 211.66074 -65.498218) (xy 211.667841 -65.503964) (xy 211.684891 -65.510484)
			(xy 211.694014 -65.510918) (xy 211.723986 -65.510918) (xy 211.733114 -65.510495) (xy 211.750171 -65.503983)
			(xy 211.75726 -65.498218) (xy 211.787665 -65.472151) (xy 211.852395 -65.424982) (xy 211.9211 -65.383818)
			(xy 211.993227 -65.348994) (xy 212.06819 -65.32079) (xy 212.145384 -65.299436) (xy 212.224184 -65.285102)
			(xy 212.303953 -65.277907) (xy 212.344 -65.277492) (xy 212.344254 -65.277492) (xy 212.390518 -65.278083)
			(xy 212.482547 -65.287689) (xy 212.57308 -65.306803) (xy 212.661139 -65.335216) (xy 212.745769 -65.372622)
			(xy 212.786214 -65.395094) (xy 212.796128 -65.400189) (xy 212.818305 -65.402142) (xy 212.839213 -65.394496)
			(xy 212.847428 -65.386966) (xy 213.627462 -64.606932) (xy 213.634302 -64.599532) (xy 213.642018 -64.580933)
			(xy 213.642448 -64.570864) (xy 213.642448 -47.915068) (xy 213.642018 -47.905002) (xy 213.634289 -47.88641)
			(xy 213.627462 -47.879) (xy 212.403182 -46.65472) (xy 212.395783 -46.647874) (xy 212.377185 -46.640143)
			(xy 212.367114 -46.639734) (xy 205.121002 -46.639734) (xy 205.087742 -46.639213) (xy 205.021791 -46.630526)
			(xy 204.957539 -46.613302) (xy 204.896087 -46.587834) (xy 204.838486 -46.55456) (xy 204.785725 -46.514049)
			(xy 204.761846 -46.49089) (xy 203.856844 -45.585888) (xy 203.833686 -45.562009) (xy 203.793176 -45.509246)
			(xy 203.759902 -45.451646) (xy 203.734434 -45.390194) (xy 203.717208 -45.325942) (xy 203.708518 -45.259992)
			(xy 203.708 -45.226732) (xy 203.708 -25.885394) (xy 203.707576 -25.875324) (xy 203.69986 -25.856721)
			(xy 203.693014 -25.849326) (xy 202.194668 -24.35098) (xy 202.187272 -24.34413) (xy 202.168673 -24.336394)
			(xy 202.1586 -24.335994) (xy 57.762394 -24.335994) (xy 57.752324 -24.336418) (xy 57.733721 -24.344133)
			(xy 57.726326 -24.35098) (xy 49.137316 -32.93999) (xy 59.169563 -32.93999) (xy 59.173559 -32.758124)
			(xy 59.185539 -32.576609) (xy 59.205481 -32.395796) (xy 59.233346 -32.216033) (xy 59.26908 -32.037668)
			(xy 59.312613 -31.861044) (xy 59.363863 -31.686503) (xy 59.42273 -31.514381) (xy 59.489101 -31.345011)
			(xy 59.562847 -31.17872) (xy 59.643826 -31.015829) (xy 59.731881 -30.856652) (xy 59.826844 -30.701496)
			(xy 59.928529 -30.550661) (xy 60.036742 -30.404439) (xy 60.151274 -30.26311) (xy 60.271902 -30.126949)
			(xy 60.398395 -29.996217) (xy 60.530508 -29.871168) (xy 60.667986 -29.752042) (xy 60.810564 -29.63907)
			(xy 60.957967 -29.53247) (xy 61.10991 -29.432447) (xy 61.266099 -29.339195) (xy 61.426234 -29.252893)
			(xy 61.590005 -29.173708) (xy 61.757096 -29.101793) (xy 61.927184 -29.037287) (xy 62.099942 -28.980315)
			(xy 62.275036 -28.930985) (xy 62.452127 -28.889394) (xy 62.630874 -28.855621) (xy 62.810932 -28.829733)
			(xy 62.991954 -28.811778) (xy 63.173589 -28.801792) (xy 63.355488 -28.799794) (xy 63.537299 -28.805788)
			(xy 63.718671 -28.819761) (xy 63.899255 -28.841688) (xy 64.078701 -28.871526) (xy 64.256663 -28.909217)
			(xy 64.432798 -28.954688) (xy 64.606766 -29.007852) (xy 64.77823 -29.068606) (xy 64.946861 -29.136833)
			(xy 65.112332 -29.212401) (xy 65.274324 -29.295164) (xy 65.432524 -29.384963) (xy 65.586627 -29.481624)
			(xy 65.736336 -29.584961) (xy 65.881361 -29.694773) (xy 66.021423 -29.81085) (xy 66.156251 -29.932967)
			(xy 66.285585 -30.060888) (xy 66.409176 -30.194367) (xy 66.526784 -30.333145) (xy 66.638183 -30.476956)
			(xy 66.743158 -30.62552) (xy 66.841506 -30.778552) (xy 66.933037 -30.935757) (xy 67.017575 -31.09683)
			(xy 67.094956 -31.261461) (xy 67.165031 -31.429332) (xy 67.227665 -31.600119) (xy 67.282736 -31.773492)
			(xy 67.33014 -31.949117) (xy 67.369783 -32.126654) (xy 67.40159 -32.305761) (xy 67.425499 -32.486093)
			(xy 67.441464 -32.667301) (xy 67.449454 -32.849035) (xy 67.449954 -32.93999) (xy 67.449454 -33.030945)
			(xy 67.441464 -33.212679) (xy 67.425499 -33.393887) (xy 67.40159 -33.574219) (xy 67.369783 -33.753326)
			(xy 67.33014 -33.930863) (xy 67.282736 -34.106488) (xy 67.227665 -34.279861) (xy 67.165031 -34.450648)
			(xy 67.094956 -34.618519) (xy 67.017575 -34.78315) (xy 66.933037 -34.944223) (xy 66.841506 -35.101428)
			(xy 66.743158 -35.25446) (xy 66.638183 -35.403024) (xy 66.526784 -35.546835) (xy 66.409176 -35.685613)
			(xy 66.285585 -35.819092) (xy 66.156251 -35.947013) (xy 66.021423 -36.06913) (xy 65.881361 -36.185207)
			(xy 65.736336 -36.295019) (xy 65.586627 -36.398356) (xy 65.432524 -36.495017) (xy 65.274324 -36.584816)
			(xy 65.112332 -36.667579) (xy 64.946861 -36.743147) (xy 64.77823 -36.811374) (xy 64.606766 -36.872128)
			(xy 64.432798 -36.925292) (xy 64.256663 -36.970763) (xy 64.078701 -37.008454) (xy 63.899255 -37.038292)
			(xy 63.718671 -37.060219) (xy 63.537299 -37.074192) (xy 63.355488 -37.080186) (xy 63.173589 -37.078188)
			(xy 62.991954 -37.068202) (xy 62.810932 -37.050247) (xy 62.630874 -37.024359) (xy 62.452127 -36.990586)
			(xy 62.275036 -36.948995) (xy 62.099942 -36.899665) (xy 61.927184 -36.842693) (xy 61.757096 -36.778187)
			(xy 61.590005 -36.706272) (xy 61.426234 -36.627087) (xy 61.266099 -36.540785) (xy 61.10991 -36.447533)
			(xy 60.957967 -36.34751) (xy 60.810564 -36.24091) (xy 60.667986 -36.127938) (xy 60.530508 -36.008812)
			(xy 60.398395 -35.883763) (xy 60.271902 -35.753031) (xy 60.151274 -35.61687) (xy 60.036742 -35.475541)
			(xy 59.928529 -35.329319) (xy 59.826844 -35.178484) (xy 59.731881 -35.023328) (xy 59.643826 -34.864151)
			(xy 59.562847 -34.70126) (xy 59.489101 -34.534969) (xy 59.42273 -34.365599) (xy 59.363863 -34.193477)
			(xy 59.312613 -34.018936) (xy 59.26908 -33.842312) (xy 59.233346 -33.663947) (xy 59.205481 -33.484184)
			(xy 59.185539 -33.303371) (xy 59.173559 -33.121856) (xy 59.169563 -32.93999) (xy 49.137316 -32.93999)
			(xy 44.057311 -38.019995) (xy 73.97362 -38.019995) (xy 73.977556 -37.915031) (xy 73.989341 -37.810656)
			(xy 74.008909 -37.707458) (xy 74.03615 -37.606014) (xy 74.070911 -37.506895) (xy 74.112997 -37.410657)
			(xy 74.162172 -37.317842) (xy 74.218159 -37.228969) (xy 74.280644 -37.144538) (xy 74.349276 -37.065024)
			(xy 74.423669 -36.990872) (xy 74.503407 -36.922499) (xy 74.58804 -36.860289) (xy 74.632312 -36.832032)
			(xy 74.639413 -36.827227) (xy 74.650103 -36.813832) (xy 74.655815 -36.797673) (xy 74.656188 -36.789106)
			(xy 74.656188 -36.710874) (xy 74.65584 -36.702302) (xy 74.650147 -36.68613) (xy 74.639414 -36.67276)
			(xy 74.632312 -36.667948) (xy 74.588032 -36.639705) (xy 74.503398 -36.577494) (xy 74.423661 -36.509121)
			(xy 74.349268 -36.434969) (xy 74.280637 -36.355454) (xy 74.218153 -36.271022) (xy 74.162167 -36.182149)
			(xy 74.112993 -36.089333) (xy 74.070908 -35.993095) (xy 74.036147 -35.893976) (xy 74.008907 -35.792532)
			(xy 73.98934 -35.689333) (xy 73.977555 -35.584959) (xy 73.97362 -35.479995) (xy 73.977556 -35.375031)
			(xy 73.989341 -35.270656) (xy 74.008909 -35.167458) (xy 74.03615 -35.066014) (xy 74.070911 -34.966895)
			(xy 74.112997 -34.870657) (xy 74.162172 -34.777842) (xy 74.218159 -34.688969) (xy 74.280644 -34.604538)
			(xy 74.349276 -34.525024) (xy 74.423669 -34.450872) (xy 74.503407 -34.382499) (xy 74.58804 -34.320289)
			(xy 74.632312 -34.292032) (xy 74.639413 -34.287227) (xy 74.650103 -34.273832) (xy 74.655815 -34.257673)
			(xy 74.656188 -34.249106) (xy 74.656188 -34.170874) (xy 74.65584 -34.162302) (xy 74.650147 -34.14613)
			(xy 74.639414 -34.13276) (xy 74.632312 -34.127948) (xy 74.586358 -34.098574) (xy 74.498662 -34.033715)
			(xy 74.416276 -33.962234) (xy 74.339696 -33.884563) (xy 74.269388 -33.801173) (xy 74.205776 -33.712568)
			(xy 74.149246 -33.619286) (xy 74.100141 -33.521891) (xy 74.058757 -33.420972) (xy 74.025346 -33.317141)
			(xy 74.000109 -33.211027) (xy 73.983199 -33.103271) (xy 73.974718 -32.994527) (xy 73.974198 -32.93999)
			(xy 73.97467 -32.887593) (xy 73.982502 -32.783093) (xy 73.998122 -32.679471) (xy 74.021441 -32.577305)
			(xy 74.05233 -32.477168) (xy 74.090616 -32.379619) (xy 74.136085 -32.285204) (xy 74.188482 -32.19445)
			(xy 74.247515 -32.107866) (xy 74.312853 -32.025936) (xy 74.384131 -31.949118) (xy 74.46095 -31.877841)
			(xy 74.542881 -31.812504) (xy 74.629466 -31.753472) (xy 74.720219 -31.701076) (xy 74.814635 -31.655609)
			(xy 74.912185 -31.617324) (xy 75.012322 -31.586436) (xy 75.114488 -31.563118) (xy 75.218111 -31.5475)
			(xy 75.322611 -31.53967) (xy 75.375008 -31.53918) (xy 75.429545 -31.539695) (xy 75.538287 -31.548183)
			(xy 75.646041 -31.565099) (xy 75.752154 -31.590341) (xy 75.855983 -31.623756) (xy 75.9569 -31.665141)
			(xy 76.054294 -31.714246) (xy 76.147577 -31.770775) (xy 76.236182 -31.834384) (xy 76.319574 -31.904689)
			(xy 76.397248 -31.981264) (xy 76.468734 -32.063646) (xy 76.533599 -32.151336) (xy 76.562966 -32.197294)
			(xy 76.567777 -32.20439) (xy 76.581169 -32.215083) (xy 76.597326 -32.220796) (xy 76.605892 -32.22117)
			(xy 76.684124 -32.22117) (xy 76.692697 -32.220829) (xy 76.70887 -32.215134) (xy 76.722239 -32.204398)
			(xy 76.72705 -32.197294) (xy 76.756418 -32.151337) (xy 76.821278 -32.063642) (xy 76.89276 -31.981255)
			(xy 76.970432 -31.904676) (xy 77.053823 -31.834368) (xy 77.142428 -31.770757) (xy 77.235711 -31.714228)
			(xy 77.333106 -31.665123) (xy 77.434025 -31.623739) (xy 77.537856 -31.590328) (xy 77.643971 -31.565091)
			(xy 77.751727 -31.548181) (xy 77.860471 -31.539701) (xy 77.915008 -31.53918) (xy 77.967404 -31.539672)
			(xy 78.071903 -31.547504) (xy 78.175525 -31.563123) (xy 78.27769 -31.586442) (xy 78.377827 -31.61733)
			(xy 78.475375 -31.655615) (xy 78.569789 -31.701083) (xy 78.660542 -31.753479) (xy 78.747126 -31.812511)
			(xy 78.829055 -31.877848) (xy 78.905874 -31.949125) (xy 78.977151 -32.025943) (xy 79.042488 -32.107873)
			(xy 79.101519 -32.194456) (xy 79.153916 -32.285209) (xy 79.199384 -32.379623) (xy 79.237669 -32.477172)
			(xy 79.268558 -32.577308) (xy 79.291877 -32.679473) (xy 79.307496 -32.783095) (xy 79.315328 -32.887594)
			(xy 79.315818 -32.93999) (xy 79.315289 -32.994526) (xy 79.306803 -33.103269) (xy 79.289888 -33.211022)
			(xy 79.264647 -33.317135) (xy 79.231234 -33.420964) (xy 79.18985 -33.521881) (xy 79.140746 -33.619275)
			(xy 79.084218 -33.712557) (xy 79.02061 -33.801163) (xy 78.950306 -33.884555) (xy 78.873732 -33.962229)
			(xy 78.79135 -34.033715) (xy 78.703661 -34.098581) (xy 78.657704 -34.127948) (xy 78.650616 -34.132769)
			(xy 78.639922 -34.146157) (xy 78.634205 -34.162309) (xy 78.633828 -34.170874) (xy 78.633828 -34.249106)
			(xy 78.634182 -34.257678) (xy 78.639871 -34.27385) (xy 78.650602 -34.28722) (xy 78.657704 -34.292032)
			(xy 78.701968 -34.320302) (xy 78.786605 -34.382508) (xy 78.866346 -34.450878) (xy 78.940743 -34.525027)
			(xy 79.009379 -34.604539) (xy 79.071867 -34.688969) (xy 79.127856 -34.77784) (xy 79.177033 -34.870656)
			(xy 79.219122 -34.966893) (xy 79.253885 -35.066012) (xy 79.281127 -35.167456) (xy 79.300696 -35.270655)
			(xy 79.312482 -35.37503) (xy 79.316418 -35.479995) (xy 79.312483 -35.584959) (xy 79.300698 -35.689334)
			(xy 79.28113 -35.792534) (xy 79.253888 -35.893978) (xy 79.219126 -35.993097) (xy 79.177038 -36.089335)
			(xy 79.127862 -36.18215) (xy 79.071873 -36.271023) (xy 79.009385 -36.355452) (xy 78.940751 -36.434965)
			(xy 78.866354 -36.509115) (xy 78.786614 -36.577486) (xy 78.701977 -36.639692) (xy 78.657704 -36.667948)
			(xy 78.650616 -36.672769) (xy 78.639922 -36.686157) (xy 78.634205 -36.702309) (xy 78.633828 -36.710874)
			(xy 78.633828 -36.789106) (xy 78.634182 -36.797678) (xy 78.639871 -36.81385) (xy 78.650602 -36.82722)
			(xy 78.657704 -36.832032) (xy 78.701968 -36.860302) (xy 78.786605 -36.922508) (xy 78.866346 -36.990878)
			(xy 78.940743 -37.065027) (xy 79.009379 -37.144539) (xy 79.071867 -37.228969) (xy 79.127856 -37.31784)
			(xy 79.177033 -37.410656) (xy 79.219122 -37.506893) (xy 79.253885 -37.606012) (xy 79.281127 -37.707456)
			(xy 79.300696 -37.810655) (xy 79.312482 -37.91503) (xy 79.316418 -38.019995) (xy 82.86362 -38.019995)
			(xy 82.867556 -37.915031) (xy 82.879341 -37.810656) (xy 82.898909 -37.707458) (xy 82.92615 -37.606014)
			(xy 82.960911 -37.506895) (xy 83.002997 -37.410657) (xy 83.052172 -37.317842) (xy 83.108159 -37.228969)
			(xy 83.170644 -37.144538) (xy 83.239276 -37.065024) (xy 83.313669 -36.990872) (xy 83.393407 -36.922499)
			(xy 83.47804 -36.860289) (xy 83.522312 -36.832032) (xy 83.529413 -36.827227) (xy 83.540103 -36.813832)
			(xy 83.545815 -36.797673) (xy 83.546188 -36.789106) (xy 83.546188 -36.710874) (xy 83.54584 -36.702302)
			(xy 83.540147 -36.68613) (xy 83.529414 -36.67276) (xy 83.522312 -36.667948) (xy 83.478032 -36.639705)
			(xy 83.393398 -36.577494) (xy 83.313661 -36.509121) (xy 83.239268 -36.434969) (xy 83.170637 -36.355454)
			(xy 83.108153 -36.271022) (xy 83.052167 -36.182149) (xy 83.002993 -36.089333) (xy 82.960908 -35.993095)
			(xy 82.926147 -35.893976) (xy 82.898907 -35.792532) (xy 82.87934 -35.689333) (xy 82.867555 -35.584959)
			(xy 82.86362 -35.479995) (xy 82.867556 -35.375031) (xy 82.879341 -35.270656) (xy 82.898909 -35.167458)
			(xy 82.92615 -35.066014) (xy 82.960911 -34.966895) (xy 83.002997 -34.870657) (xy 83.052172 -34.777842)
			(xy 83.108159 -34.688969) (xy 83.170644 -34.604538) (xy 83.239276 -34.525024) (xy 83.313669 -34.450872)
			(xy 83.393407 -34.382499) (xy 83.47804 -34.320289) (xy 83.522312 -34.292032) (xy 83.529413 -34.287227)
			(xy 83.540103 -34.273832) (xy 83.545815 -34.257673) (xy 83.546188 -34.249106) (xy 83.546188 -34.170874)
			(xy 83.54584 -34.162302) (xy 83.540147 -34.14613) (xy 83.529414 -34.13276) (xy 83.522312 -34.127948)
			(xy 83.476358 -34.098574) (xy 83.388662 -34.033715) (xy 83.306276 -33.962234) (xy 83.229696 -33.884563)
			(xy 83.159388 -33.801173) (xy 83.095776 -33.712568) (xy 83.039246 -33.619286) (xy 82.990141 -33.521891)
			(xy 82.948757 -33.420972) (xy 82.915346 -33.317141) (xy 82.890109 -33.211027) (xy 82.873199 -33.103271)
			(xy 82.864718 -32.994527) (xy 82.864198 -32.93999) (xy 82.86467 -32.887593) (xy 82.872502 -32.783093)
			(xy 82.888122 -32.679471) (xy 82.911441 -32.577305) (xy 82.94233 -32.477168) (xy 82.980616 -32.379619)
			(xy 83.026085 -32.285204) (xy 83.078482 -32.19445) (xy 83.137515 -32.107866) (xy 83.202853 -32.025936)
			(xy 83.274131 -31.949118) (xy 83.35095 -31.877841) (xy 83.432881 -31.812504) (xy 83.519466 -31.753472)
			(xy 83.610219 -31.701076) (xy 83.704635 -31.655609) (xy 83.802185 -31.617324) (xy 83.902322 -31.586436)
			(xy 84.004488 -31.563118) (xy 84.108111 -31.5475) (xy 84.212611 -31.53967) (xy 84.265008 -31.53918)
			(xy 84.319545 -31.539695) (xy 84.428287 -31.548183) (xy 84.536041 -31.565099) (xy 84.642154 -31.590341)
			(xy 84.745983 -31.623756) (xy 84.8469 -31.665141) (xy 84.944294 -31.714246) (xy 85.037577 -31.770775)
			(xy 85.126182 -31.834384) (xy 85.209574 -31.904689) (xy 85.287248 -31.981264) (xy 85.358734 -32.063646)
			(xy 85.423599 -32.151336) (xy 85.452966 -32.197294) (xy 85.457777 -32.20439) (xy 85.471169 -32.215083)
			(xy 85.487326 -32.220796) (xy 85.495892 -32.22117) (xy 85.574124 -32.22117) (xy 85.582697 -32.220829)
			(xy 85.59887 -32.215134) (xy 85.612239 -32.204398) (xy 85.61705 -32.197294) (xy 85.646418 -32.151337)
			(xy 85.711278 -32.063642) (xy 85.78276 -31.981255) (xy 85.860432 -31.904676) (xy 85.943823 -31.834368)
			(xy 86.032428 -31.770757) (xy 86.125711 -31.714228) (xy 86.223106 -31.665123) (xy 86.324025 -31.623739)
			(xy 86.427856 -31.590328) (xy 86.533971 -31.565091) (xy 86.641727 -31.548181) (xy 86.750471 -31.539701)
			(xy 86.805008 -31.53918) (xy 86.857404 -31.539672) (xy 86.961903 -31.547504) (xy 87.065525 -31.563123)
			(xy 87.16769 -31.586442) (xy 87.267827 -31.61733) (xy 87.365375 -31.655615) (xy 87.459789 -31.701083)
			(xy 87.550542 -31.753479) (xy 87.637126 -31.812511) (xy 87.719055 -31.877848) (xy 87.795874 -31.949125)
			(xy 87.867151 -32.025943) (xy 87.932488 -32.107873) (xy 87.991519 -32.194456) (xy 88.043916 -32.285209)
			(xy 88.089384 -32.379623) (xy 88.127669 -32.477172) (xy 88.158558 -32.577308) (xy 88.181877 -32.679473)
			(xy 88.197496 -32.783095) (xy 88.205328 -32.887594) (xy 88.205818 -32.93999) (xy 88.205289 -32.994526)
			(xy 88.196803 -33.103269) (xy 88.179888 -33.211022) (xy 88.154647 -33.317135) (xy 88.121234 -33.420964)
			(xy 88.07985 -33.521881) (xy 88.030746 -33.619275) (xy 87.974218 -33.712557) (xy 87.91061 -33.801163)
			(xy 87.840306 -33.884555) (xy 87.763732 -33.962229) (xy 87.68135 -34.033715) (xy 87.593661 -34.098581)
			(xy 87.547704 -34.127948) (xy 87.540616 -34.132769) (xy 87.529922 -34.146157) (xy 87.524205 -34.162309)
			(xy 87.523828 -34.170874) (xy 87.523828 -34.249106) (xy 87.524182 -34.257678) (xy 87.529871 -34.27385)
			(xy 87.540602 -34.28722) (xy 87.547704 -34.292032) (xy 87.591968 -34.320302) (xy 87.676605 -34.382508)
			(xy 87.756346 -34.450878) (xy 87.830743 -34.525027) (xy 87.899379 -34.604539) (xy 87.961867 -34.688969)
			(xy 88.017856 -34.77784) (xy 88.067033 -34.870656) (xy 88.109122 -34.966893) (xy 88.143885 -35.066012)
			(xy 88.171127 -35.167456) (xy 88.190696 -35.270655) (xy 88.202482 -35.37503) (xy 88.206418 -35.479995)
			(xy 88.202483 -35.584959) (xy 88.190698 -35.689334) (xy 88.17113 -35.792534) (xy 88.143888 -35.893978)
			(xy 88.109126 -35.993097) (xy 88.067038 -36.089335) (xy 88.017862 -36.18215) (xy 87.961873 -36.271023)
			(xy 87.899385 -36.355452) (xy 87.830751 -36.434965) (xy 87.756354 -36.509115) (xy 87.676614 -36.577486)
			(xy 87.591977 -36.639692) (xy 87.547704 -36.667948) (xy 87.540616 -36.672769) (xy 87.529922 -36.686157)
			(xy 87.524205 -36.702309) (xy 87.523828 -36.710874) (xy 87.523828 -36.789106) (xy 87.524182 -36.797678)
			(xy 87.529871 -36.81385) (xy 87.540602 -36.82722) (xy 87.547704 -36.832032) (xy 87.591968 -36.860302)
			(xy 87.676605 -36.922508) (xy 87.756346 -36.990878) (xy 87.830743 -37.065027) (xy 87.899379 -37.144539)
			(xy 87.961867 -37.228969) (xy 88.017856 -37.31784) (xy 88.067033 -37.410656) (xy 88.109122 -37.506893)
			(xy 88.143885 -37.606012) (xy 88.171127 -37.707456) (xy 88.190696 -37.810655) (xy 88.202482 -37.91503)
			(xy 88.206418 -38.019995) (xy 91.75362 -38.019995) (xy 91.757556 -37.915031) (xy 91.769341 -37.810656)
			(xy 91.788909 -37.707458) (xy 91.81615 -37.606014) (xy 91.850911 -37.506895) (xy 91.892997 -37.410657)
			(xy 91.942172 -37.317842) (xy 91.998159 -37.228969) (xy 92.060644 -37.144538) (xy 92.129276 -37.065024)
			(xy 92.203669 -36.990872) (xy 92.283407 -36.922499) (xy 92.36804 -36.860289) (xy 92.412312 -36.832032)
			(xy 92.419413 -36.827227) (xy 92.430103 -36.813832) (xy 92.435815 -36.797673) (xy 92.436188 -36.789106)
			(xy 92.436188 -36.710874) (xy 92.43584 -36.702302) (xy 92.430147 -36.68613) (xy 92.419414 -36.67276)
			(xy 92.412312 -36.667948) (xy 92.368032 -36.639705) (xy 92.283398 -36.577494) (xy 92.203661 -36.509121)
			(xy 92.129268 -36.434969) (xy 92.060637 -36.355454) (xy 91.998153 -36.271022) (xy 91.942167 -36.182149)
			(xy 91.892993 -36.089333) (xy 91.850908 -35.993095) (xy 91.816147 -35.893976) (xy 91.788907 -35.792532)
			(xy 91.76934 -35.689333) (xy 91.757555 -35.584959) (xy 91.75362 -35.479995) (xy 91.757556 -35.375031)
			(xy 91.769341 -35.270656) (xy 91.788909 -35.167458) (xy 91.81615 -35.066014) (xy 91.850911 -34.966895)
			(xy 91.892997 -34.870657) (xy 91.942172 -34.777842) (xy 91.998159 -34.688969) (xy 92.060644 -34.604538)
			(xy 92.129276 -34.525024) (xy 92.203669 -34.450872) (xy 92.283407 -34.382499) (xy 92.36804 -34.320289)
			(xy 92.412312 -34.292032) (xy 92.419413 -34.287227) (xy 92.430103 -34.273832) (xy 92.435815 -34.257673)
			(xy 92.436188 -34.249106) (xy 92.436188 -34.170874) (xy 92.43584 -34.162302) (xy 92.430147 -34.14613)
			(xy 92.419414 -34.13276) (xy 92.412312 -34.127948) (xy 92.366358 -34.098574) (xy 92.278662 -34.033715)
			(xy 92.196276 -33.962234) (xy 92.119696 -33.884563) (xy 92.049388 -33.801173) (xy 91.985776 -33.712568)
			(xy 91.929246 -33.619286) (xy 91.880141 -33.521891) (xy 91.838757 -33.420972) (xy 91.805346 -33.317141)
			(xy 91.780109 -33.211027) (xy 91.763199 -33.103271) (xy 91.754718 -32.994527) (xy 91.754198 -32.93999)
			(xy 91.75467 -32.887593) (xy 91.762502 -32.783093) (xy 91.778122 -32.679471) (xy 91.801441 -32.577305)
			(xy 91.83233 -32.477168) (xy 91.870616 -32.379619) (xy 91.916085 -32.285204) (xy 91.968482 -32.19445)
			(xy 92.027515 -32.107866) (xy 92.092853 -32.025936) (xy 92.164131 -31.949118) (xy 92.24095 -31.877841)
			(xy 92.322881 -31.812504) (xy 92.409466 -31.753472) (xy 92.500219 -31.701076) (xy 92.594635 -31.655609)
			(xy 92.692185 -31.617324) (xy 92.792322 -31.586436) (xy 92.894488 -31.563118) (xy 92.998111 -31.5475)
			(xy 93.102611 -31.53967) (xy 93.155008 -31.53918) (xy 93.209545 -31.539695) (xy 93.318287 -31.548183)
			(xy 93.426041 -31.565099) (xy 93.532154 -31.590341) (xy 93.635983 -31.623756) (xy 93.7369 -31.665141)
			(xy 93.834294 -31.714246) (xy 93.927577 -31.770775) (xy 94.016182 -31.834384) (xy 94.099574 -31.904689)
			(xy 94.177248 -31.981264) (xy 94.248734 -32.063646) (xy 94.313599 -32.151336) (xy 94.342966 -32.197294)
			(xy 94.347777 -32.20439) (xy 94.361169 -32.215083) (xy 94.377326 -32.220796) (xy 94.385892 -32.22117)
			(xy 94.464124 -32.22117) (xy 94.472697 -32.220829) (xy 94.48887 -32.215134) (xy 94.502239 -32.204398)
			(xy 94.50705 -32.197294) (xy 94.536418 -32.151337) (xy 94.601278 -32.063642) (xy 94.67276 -31.981255)
			(xy 94.750432 -31.904676) (xy 94.833823 -31.834368) (xy 94.922428 -31.770757) (xy 95.015711 -31.714228)
			(xy 95.113106 -31.665123) (xy 95.214025 -31.623739) (xy 95.317856 -31.590328) (xy 95.423971 -31.565091)
			(xy 95.531727 -31.548181) (xy 95.640471 -31.539701) (xy 95.695008 -31.53918) (xy 95.747404 -31.539672)
			(xy 95.851903 -31.547504) (xy 95.955525 -31.563123) (xy 96.05769 -31.586442) (xy 96.157827 -31.61733)
			(xy 96.255375 -31.655615) (xy 96.349789 -31.701083) (xy 96.440542 -31.753479) (xy 96.527126 -31.812511)
			(xy 96.609055 -31.877848) (xy 96.685874 -31.949125) (xy 96.757151 -32.025943) (xy 96.822488 -32.107873)
			(xy 96.881519 -32.194456) (xy 96.933916 -32.285209) (xy 96.979384 -32.379623) (xy 97.017669 -32.477172)
			(xy 97.048558 -32.577308) (xy 97.071877 -32.679473) (xy 97.087496 -32.783095) (xy 97.095328 -32.887594)
			(xy 97.095818 -32.93999) (xy 130.289563 -32.93999) (xy 130.293559 -32.758124) (xy 130.305539 -32.576609)
			(xy 130.325481 -32.395796) (xy 130.353346 -32.216033) (xy 130.38908 -32.037668) (xy 130.432613 -31.861044)
			(xy 130.483863 -31.686503) (xy 130.54273 -31.514381) (xy 130.609101 -31.345011) (xy 130.682847 -31.17872)
			(xy 130.763826 -31.015829) (xy 130.851881 -30.856652) (xy 130.946844 -30.701496) (xy 131.048529 -30.550661)
			(xy 131.156742 -30.404439) (xy 131.271274 -30.26311) (xy 131.391902 -30.126949) (xy 131.518395 -29.996217)
			(xy 131.650508 -29.871168) (xy 131.787986 -29.752042) (xy 131.930564 -29.63907) (xy 132.077967 -29.53247)
			(xy 132.22991 -29.432447) (xy 132.386099 -29.339195) (xy 132.546234 -29.252893) (xy 132.710005 -29.173708)
			(xy 132.877096 -29.101793) (xy 133.047184 -29.037287) (xy 133.219942 -28.980315) (xy 133.395036 -28.930985)
			(xy 133.572127 -28.889394) (xy 133.750874 -28.855621) (xy 133.930932 -28.829733) (xy 134.111954 -28.811778)
			(xy 134.293589 -28.801792) (xy 134.475488 -28.799794) (xy 134.657299 -28.805788) (xy 134.838671 -28.819761)
			(xy 135.019255 -28.841688) (xy 135.198701 -28.871526) (xy 135.376663 -28.909217) (xy 135.552798 -28.954688)
			(xy 135.726766 -29.007852) (xy 135.89823 -29.068606) (xy 136.066861 -29.136833) (xy 136.232332 -29.212401)
			(xy 136.394324 -29.295164) (xy 136.552524 -29.384963) (xy 136.706627 -29.481624) (xy 136.856336 -29.584961)
			(xy 137.001361 -29.694773) (xy 137.141423 -29.81085) (xy 137.276251 -29.932967) (xy 137.405585 -30.060888)
			(xy 137.529176 -30.194367) (xy 137.646784 -30.333145) (xy 137.758183 -30.476956) (xy 137.863158 -30.62552)
			(xy 137.961506 -30.778552) (xy 138.053037 -30.935757) (xy 138.137575 -31.09683) (xy 138.214956 -31.261461)
			(xy 138.285031 -31.429332) (xy 138.347665 -31.600119) (xy 138.402736 -31.773492) (xy 138.45014 -31.949117)
			(xy 138.489783 -32.126654) (xy 138.52159 -32.305761) (xy 138.545499 -32.486093) (xy 138.561464 -32.667301)
			(xy 138.569454 -32.849035) (xy 138.569954 -32.93999) (xy 138.569454 -33.030945) (xy 138.561464 -33.212679)
			(xy 138.545499 -33.393887) (xy 138.52159 -33.574219) (xy 138.489783 -33.753326) (xy 138.45014 -33.930863)
			(xy 138.402736 -34.106488) (xy 138.347665 -34.279861) (xy 138.285031 -34.450648) (xy 138.214956 -34.618519)
			(xy 138.137575 -34.78315) (xy 138.053037 -34.944223) (xy 137.961506 -35.101428) (xy 137.863158 -35.25446)
			(xy 137.758183 -35.403024) (xy 137.646784 -35.546835) (xy 137.529176 -35.685613) (xy 137.405585 -35.819092)
			(xy 137.276251 -35.947013) (xy 137.141423 -36.06913) (xy 137.001361 -36.185207) (xy 136.856336 -36.295019)
			(xy 136.706627 -36.398356) (xy 136.552524 -36.495017) (xy 136.394324 -36.584816) (xy 136.232332 -36.667579)
			(xy 136.066861 -36.743147) (xy 135.89823 -36.811374) (xy 135.726766 -36.872128) (xy 135.552798 -36.925292)
			(xy 135.376663 -36.970763) (xy 135.198701 -37.008454) (xy 135.019255 -37.038292) (xy 134.838671 -37.060219)
			(xy 134.657299 -37.074192) (xy 134.475488 -37.080186) (xy 134.293589 -37.078188) (xy 134.111954 -37.068202)
			(xy 133.930932 -37.050247) (xy 133.750874 -37.024359) (xy 133.572127 -36.990586) (xy 133.395036 -36.948995)
			(xy 133.219942 -36.899665) (xy 133.047184 -36.842693) (xy 132.877096 -36.778187) (xy 132.710005 -36.706272)
			(xy 132.546234 -36.627087) (xy 132.386099 -36.540785) (xy 132.22991 -36.447533) (xy 132.077967 -36.34751)
			(xy 131.930564 -36.24091) (xy 131.787986 -36.127938) (xy 131.650508 -36.008812) (xy 131.518395 -35.883763)
			(xy 131.391902 -35.753031) (xy 131.271274 -35.61687) (xy 131.156742 -35.475541) (xy 131.048529 -35.329319)
			(xy 130.946844 -35.178484) (xy 130.851881 -35.023328) (xy 130.763826 -34.864151) (xy 130.682847 -34.70126)
			(xy 130.609101 -34.534969) (xy 130.54273 -34.365599) (xy 130.483863 -34.193477) (xy 130.432613 -34.018936)
			(xy 130.38908 -33.842312) (xy 130.353346 -33.663947) (xy 130.325481 -33.484184) (xy 130.305539 -33.303371)
			(xy 130.293559 -33.121856) (xy 130.289563 -32.93999) (xy 97.095818 -32.93999) (xy 97.095289 -32.994526)
			(xy 97.086803 -33.103269) (xy 97.069888 -33.211022) (xy 97.044647 -33.317135) (xy 97.011234 -33.420964)
			(xy 96.96985 -33.521881) (xy 96.920746 -33.619275) (xy 96.864218 -33.712557) (xy 96.80061 -33.801163)
			(xy 96.730306 -33.884555) (xy 96.653732 -33.962229) (xy 96.57135 -34.033715) (xy 96.483661 -34.098581)
			(xy 96.437704 -34.127948) (xy 96.430616 -34.132769) (xy 96.419922 -34.146157) (xy 96.414205 -34.162309)
			(xy 96.413828 -34.170874) (xy 96.413828 -34.249106) (xy 96.414182 -34.257678) (xy 96.419871 -34.27385)
			(xy 96.430602 -34.28722) (xy 96.437704 -34.292032) (xy 96.481968 -34.320302) (xy 96.566605 -34.382508)
			(xy 96.646346 -34.450878) (xy 96.720743 -34.525027) (xy 96.789379 -34.604539) (xy 96.851867 -34.688969)
			(xy 96.907856 -34.77784) (xy 96.957033 -34.870656) (xy 96.999122 -34.966893) (xy 97.033885 -35.066012)
			(xy 97.061127 -35.167456) (xy 97.080696 -35.270655) (xy 97.092482 -35.37503) (xy 97.096418 -35.479995)
			(xy 97.092483 -35.584959) (xy 97.080698 -35.689334) (xy 97.06113 -35.792534) (xy 97.033888 -35.893978)
			(xy 96.999126 -35.993097) (xy 96.957038 -36.089335) (xy 96.907862 -36.18215) (xy 96.851873 -36.271023)
			(xy 96.789385 -36.355452) (xy 96.720751 -36.434965) (xy 96.646354 -36.509115) (xy 96.566614 -36.577486)
			(xy 96.481977 -36.639692) (xy 96.437704 -36.667948) (xy 96.430616 -36.672769) (xy 96.419922 -36.686157)
			(xy 96.414205 -36.702309) (xy 96.413828 -36.710874) (xy 96.413828 -36.789106) (xy 96.414182 -36.797678)
			(xy 96.419871 -36.81385) (xy 96.430602 -36.82722) (xy 96.437704 -36.832032) (xy 96.481968 -36.860302)
			(xy 96.566605 -36.922508) (xy 96.646346 -36.990878) (xy 96.720743 -37.065027) (xy 96.789379 -37.144539)
			(xy 96.851867 -37.228969) (xy 96.907856 -37.31784) (xy 96.957033 -37.410656) (xy 96.999122 -37.506893)
			(xy 97.033885 -37.606012) (xy 97.061127 -37.707456) (xy 97.080696 -37.810655) (xy 97.092482 -37.91503)
			(xy 97.09378 -37.949632) (xy 164.784541 -37.949632) (xy 164.788537 -37.767766) (xy 164.800517 -37.586251)
			(xy 164.820459 -37.405438) (xy 164.848324 -37.225675) (xy 164.884058 -37.04731) (xy 164.927591 -36.870686)
			(xy 164.978841 -36.696145) (xy 165.037708 -36.524023) (xy 165.104079 -36.354653) (xy 165.177825 -36.188362)
			(xy 165.258804 -36.025471) (xy 165.346859 -35.866294) (xy 165.441822 -35.711138) (xy 165.543507 -35.560303)
			(xy 165.65172 -35.414081) (xy 165.766252 -35.272752) (xy 165.88688 -35.136591) (xy 166.013373 -35.005859)
			(xy 166.145486 -34.88081) (xy 166.282964 -34.761684) (xy 166.425542 -34.648712) (xy 166.572945 -34.542112)
			(xy 166.724888 -34.442089) (xy 166.881077 -34.348837) (xy 167.041212 -34.262535) (xy 167.204983 -34.18335)
			(xy 167.372074 -34.111435) (xy 167.542162 -34.046929) (xy 167.71492 -33.989957) (xy 167.890014 -33.940627)
			(xy 168.067105 -33.899036) (xy 168.245852 -33.865263) (xy 168.42591 -33.839375) (xy 168.606932 -33.82142)
			(xy 168.788567 -33.811434) (xy 168.970466 -33.809436) (xy 169.152277 -33.81543) (xy 169.333649 -33.829403)
			(xy 169.514233 -33.85133) (xy 169.693679 -33.881168) (xy 169.871641 -33.918859) (xy 170.047776 -33.96433)
			(xy 170.221744 -34.017494) (xy 170.393208 -34.078248) (xy 170.561839 -34.146475) (xy 170.72731 -34.222043)
			(xy 170.889302 -34.304806) (xy 171.047502 -34.394605) (xy 171.201605 -34.491266) (xy 171.351314 -34.594603)
			(xy 171.496339 -34.704415) (xy 171.636401 -34.820492) (xy 171.771229 -34.942609) (xy 171.900563 -35.07053)
			(xy 172.024154 -35.204009) (xy 172.141762 -35.342787) (xy 172.253161 -35.486598) (xy 172.358136 -35.635162)
			(xy 172.456484 -35.788194) (xy 172.548015 -35.945399) (xy 172.632553 -36.106472) (xy 172.709934 -36.271103)
			(xy 172.780009 -36.438974) (xy 172.842643 -36.609761) (xy 172.897714 -36.783134) (xy 172.945118 -36.958759)
			(xy 172.984761 -37.136296) (xy 173.016568 -37.315403) (xy 173.040477 -37.495735) (xy 173.056442 -37.676943)
			(xy 173.064432 -37.858677) (xy 173.064932 -37.949632) (xy 173.064432 -38.040587) (xy 173.056442 -38.222321)
			(xy 173.040477 -38.403529) (xy 173.016568 -38.583861) (xy 172.984761 -38.762968) (xy 172.945118 -38.940505)
			(xy 172.897714 -39.11613) (xy 172.842643 -39.289503) (xy 172.780009 -39.46029) (xy 172.709934 -39.628161)
			(xy 172.632553 -39.792792) (xy 172.548015 -39.953865) (xy 172.456484 -40.11107) (xy 172.358136 -40.264102)
			(xy 172.253161 -40.412666) (xy 172.141762 -40.556477) (xy 172.024154 -40.695255) (xy 171.900563 -40.828734)
			(xy 171.771229 -40.956655) (xy 171.636401 -41.078772) (xy 171.496339 -41.194849) (xy 171.351314 -41.304661)
			(xy 171.201605 -41.407998) (xy 171.047502 -41.504659) (xy 170.889302 -41.594458) (xy 170.72731 -41.677221)
			(xy 170.561839 -41.752789) (xy 170.393208 -41.821016) (xy 170.221744 -41.88177) (xy 170.047776 -41.934934)
			(xy 169.871641 -41.980405) (xy 169.693679 -42.018096) (xy 169.514233 -42.047934) (xy 169.333649 -42.069861)
			(xy 169.152277 -42.083834) (xy 168.970466 -42.089828) (xy 168.788567 -42.08783) (xy 168.606932 -42.077844)
			(xy 168.42591 -42.059889) (xy 168.245852 -42.034001) (xy 168.067105 -42.000228) (xy 167.890014 -41.958637)
			(xy 167.71492 -41.909307) (xy 167.542162 -41.852335) (xy 167.372074 -41.787829) (xy 167.204983 -41.715914)
			(xy 167.041212 -41.636729) (xy 166.881077 -41.550427) (xy 166.724888 -41.457175) (xy 166.572945 -41.357152)
			(xy 166.425542 -41.250552) (xy 166.282964 -41.13758) (xy 166.145486 -41.018454) (xy 166.013373 -40.893405)
			(xy 165.88688 -40.762673) (xy 165.766252 -40.626512) (xy 165.65172 -40.485183) (xy 165.543507 -40.338961)
			(xy 165.441822 -40.188126) (xy 165.346859 -40.03297) (xy 165.258804 -39.873793) (xy 165.177825 -39.710902)
			(xy 165.104079 -39.544611) (xy 165.037708 -39.375241) (xy 164.978841 -39.203119) (xy 164.927591 -39.028578)
			(xy 164.884058 -38.851954) (xy 164.848324 -38.673589) (xy 164.820459 -38.493826) (xy 164.800517 -38.313013)
			(xy 164.788537 -38.131498) (xy 164.784541 -37.949632) (xy 97.09378 -37.949632) (xy 97.096418 -38.019995)
			(xy 97.092483 -38.124959) (xy 97.080698 -38.229334) (xy 97.06113 -38.332534) (xy 97.033888 -38.433978)
			(xy 96.999126 -38.533097) (xy 96.957038 -38.629335) (xy 96.907862 -38.72215) (xy 96.851873 -38.811023)
			(xy 96.789385 -38.895452) (xy 96.720751 -38.974965) (xy 96.646354 -39.049115) (xy 96.566614 -39.117486)
			(xy 96.481977 -39.179692) (xy 96.437704 -39.207948) (xy 96.430616 -39.212769) (xy 96.419922 -39.226157)
			(xy 96.414205 -39.242309) (xy 96.413828 -39.250874) (xy 96.413828 -39.329106) (xy 96.414182 -39.337678)
			(xy 96.419871 -39.35385) (xy 96.430602 -39.36722) (xy 96.437704 -39.372032) (xy 96.483653 -39.401414)
			(xy 96.571348 -39.466272) (xy 96.653734 -39.537753) (xy 96.730314 -39.615424) (xy 96.800622 -39.698813)
			(xy 96.864234 -39.787417) (xy 96.920763 -39.880699) (xy 96.969869 -39.978093) (xy 97.011254 -40.079011)
			(xy 97.044666 -40.182841) (xy 97.069904 -40.288955) (xy 97.086815 -40.39671) (xy 97.095297 -40.505453)
			(xy 97.095818 -40.55999) (xy 97.095322 -40.612386) (xy 97.087492 -40.716886) (xy 97.071874 -40.820509)
			(xy 97.048556 -40.922674) (xy 97.017669 -41.022812) (xy 96.979384 -41.120361) (xy 96.933917 -41.214776)
			(xy 96.881521 -41.30553) (xy 96.82249 -41.392114) (xy 96.757153 -41.474045) (xy 96.685877 -41.550864)
			(xy 96.609058 -41.622141) (xy 96.527129 -41.687479) (xy 96.440545 -41.746512) (xy 96.349792 -41.798909)
			(xy 96.255377 -41.844377) (xy 96.157829 -41.882663) (xy 96.057692 -41.913552) (xy 95.955526 -41.936871)
			(xy 95.851904 -41.95249) (xy 95.747404 -41.960322) (xy 95.695008 -41.9608) (xy 95.640471 -41.960281)
			(xy 95.531728 -41.951794) (xy 95.423975 -41.934879) (xy 95.317862 -41.909638) (xy 95.214033 -41.876224)
			(xy 95.113115 -41.834839) (xy 95.015721 -41.785734) (xy 94.922438 -41.729206) (xy 94.833833 -41.665597)
			(xy 94.750441 -41.595292) (xy 94.672767 -41.518716) (xy 94.601282 -41.436334) (xy 94.536417 -41.348644)
			(xy 94.50705 -41.302686) (xy 94.502235 -41.295593) (xy 94.488844 -41.284901) (xy 94.47269 -41.279186)
			(xy 94.464124 -41.27881) (xy 94.385892 -41.27881) (xy 94.377321 -41.279171) (xy 94.36115 -41.284858)
			(xy 94.347779 -41.295586) (xy 94.342966 -41.302686) (xy 94.313579 -41.348631) (xy 94.248721 -41.436327)
			(xy 94.177241 -41.518714) (xy 94.099571 -41.595294) (xy 94.016182 -41.665602) (xy 93.927579 -41.729214)
			(xy 93.834298 -41.785745) (xy 93.736904 -41.834851) (xy 93.635986 -41.876235) (xy 93.532156 -41.909648)
			(xy 93.426043 -41.934886) (xy 93.318288 -41.951797) (xy 93.209545 -41.960279) (xy 93.155008 -41.9608)
			(xy 93.102611 -41.960324) (xy 92.99811 -41.952494) (xy 92.894487 -41.936875) (xy 92.792321 -41.913557)
			(xy 92.692183 -41.882669) (xy 92.594633 -41.844384) (xy 92.500217 -41.798916) (xy 92.409463 -41.746519)
			(xy 92.322878 -41.687487) (xy 92.240947 -41.622149) (xy 92.164128 -41.550871) (xy 92.09285 -41.474052)
			(xy 92.027512 -41.39212) (xy 91.96848 -41.305536) (xy 91.916083 -41.214781) (xy 91.870616 -41.120365)
			(xy 91.83233 -41.022816) (xy 91.801442 -40.922677) (xy 91.778124 -40.820511) (xy 91.762506 -40.716888)
			(xy 91.754676 -40.612387) (xy 91.754198 -40.55999) (xy 91.754703 -40.505453) (xy 91.763191 -40.39671)
			(xy 91.780108 -40.288956) (xy 91.80535 -40.182843) (xy 91.838765 -40.079013) (xy 91.880151 -39.978096)
			(xy 91.929258 -39.880701) (xy 91.985787 -39.787419) (xy 92.049397 -39.698814) (xy 92.119703 -39.615422)
			(xy 92.19628 -39.537749) (xy 92.278663 -39.466263) (xy 92.366354 -39.401399) (xy 92.412312 -39.372032)
			(xy 92.419413 -39.367227) (xy 92.430103 -39.353832) (xy 92.435815 -39.337673) (xy 92.436188 -39.329106)
			(xy 92.436188 -39.250874) (xy 92.43584 -39.242302) (xy 92.430147 -39.22613) (xy 92.419414 -39.21276)
			(xy 92.412312 -39.207948) (xy 92.368032 -39.179705) (xy 92.283398 -39.117494) (xy 92.203661 -39.049121)
			(xy 92.129268 -38.974969) (xy 92.060637 -38.895454) (xy 91.998153 -38.811022) (xy 91.942167 -38.722149)
			(xy 91.892993 -38.629333) (xy 91.850908 -38.533095) (xy 91.816147 -38.433976) (xy 91.788907 -38.332532)
			(xy 91.76934 -38.229333) (xy 91.757555 -38.124959) (xy 91.75362 -38.019995) (xy 88.206418 -38.019995)
			(xy 88.202483 -38.124959) (xy 88.190698 -38.229334) (xy 88.17113 -38.332534) (xy 88.143888 -38.433978)
			(xy 88.109126 -38.533097) (xy 88.067038 -38.629335) (xy 88.017862 -38.72215) (xy 87.961873 -38.811023)
			(xy 87.899385 -38.895452) (xy 87.830751 -38.974965) (xy 87.756354 -39.049115) (xy 87.676614 -39.117486)
			(xy 87.591977 -39.179692) (xy 87.547704 -39.207948) (xy 87.540616 -39.212769) (xy 87.529922 -39.226157)
			(xy 87.524205 -39.242309) (xy 87.523828 -39.250874) (xy 87.523828 -39.329106) (xy 87.524182 -39.337678)
			(xy 87.529871 -39.35385) (xy 87.540602 -39.36722) (xy 87.547704 -39.372032) (xy 87.593653 -39.401414)
			(xy 87.681348 -39.466272) (xy 87.763734 -39.537753) (xy 87.840314 -39.615424) (xy 87.910622 -39.698813)
			(xy 87.974234 -39.787417) (xy 88.030763 -39.880699) (xy 88.079869 -39.978093) (xy 88.121254 -40.079011)
			(xy 88.154666 -40.182841) (xy 88.179904 -40.288955) (xy 88.196815 -40.39671) (xy 88.205297 -40.505453)
			(xy 88.205818 -40.55999) (xy 88.205322 -40.612386) (xy 88.197492 -40.716886) (xy 88.181874 -40.820509)
			(xy 88.158556 -40.922674) (xy 88.127669 -41.022812) (xy 88.089384 -41.120361) (xy 88.043917 -41.214776)
			(xy 87.991521 -41.30553) (xy 87.93249 -41.392114) (xy 87.867153 -41.474045) (xy 87.795877 -41.550864)
			(xy 87.719058 -41.622141) (xy 87.637129 -41.687479) (xy 87.550545 -41.746512) (xy 87.459792 -41.798909)
			(xy 87.365377 -41.844377) (xy 87.267829 -41.882663) (xy 87.167692 -41.913552) (xy 87.065526 -41.936871)
			(xy 86.961904 -41.95249) (xy 86.857404 -41.960322) (xy 86.805008 -41.9608) (xy 86.750471 -41.960281)
			(xy 86.641728 -41.951794) (xy 86.533975 -41.934879) (xy 86.427862 -41.909638) (xy 86.324033 -41.876224)
			(xy 86.223115 -41.834839) (xy 86.125721 -41.785734) (xy 86.032438 -41.729206) (xy 85.943833 -41.665597)
			(xy 85.860441 -41.595292) (xy 85.782767 -41.518716) (xy 85.711282 -41.436334) (xy 85.646417 -41.348644)
			(xy 85.61705 -41.302686) (xy 85.612235 -41.295593) (xy 85.598844 -41.284901) (xy 85.58269 -41.279186)
			(xy 85.574124 -41.27881) (xy 85.495892 -41.27881) (xy 85.487321 -41.279171) (xy 85.47115 -41.284858)
			(xy 85.457779 -41.295586) (xy 85.452966 -41.302686) (xy 85.423579 -41.348631) (xy 85.358721 -41.436327)
			(xy 85.287241 -41.518714) (xy 85.209571 -41.595294) (xy 85.126182 -41.665602) (xy 85.037579 -41.729214)
			(xy 84.944298 -41.785745) (xy 84.846904 -41.834851) (xy 84.745986 -41.876235) (xy 84.642156 -41.909648)
			(xy 84.536043 -41.934886) (xy 84.428288 -41.951797) (xy 84.319545 -41.960279) (xy 84.265008 -41.9608)
			(xy 84.212611 -41.960324) (xy 84.10811 -41.952494) (xy 84.004487 -41.936875) (xy 83.902321 -41.913557)
			(xy 83.802183 -41.882669) (xy 83.704633 -41.844384) (xy 83.610217 -41.798916) (xy 83.519463 -41.746519)
			(xy 83.432878 -41.687487) (xy 83.350947 -41.622149) (xy 83.274128 -41.550871) (xy 83.20285 -41.474052)
			(xy 83.137512 -41.39212) (xy 83.07848 -41.305536) (xy 83.026083 -41.214781) (xy 82.980616 -41.120365)
			(xy 82.94233 -41.022816) (xy 82.911442 -40.922677) (xy 82.888124 -40.820511) (xy 82.872506 -40.716888)
			(xy 82.864676 -40.612387) (xy 82.864198 -40.55999) (xy 82.864703 -40.505453) (xy 82.873191 -40.39671)
			(xy 82.890108 -40.288956) (xy 82.91535 -40.182843) (xy 82.948765 -40.079013) (xy 82.990151 -39.978096)
			(xy 83.039258 -39.880701) (xy 83.095787 -39.787419) (xy 83.159397 -39.698814) (xy 83.229703 -39.615422)
			(xy 83.30628 -39.537749) (xy 83.388663 -39.466263) (xy 83.476354 -39.401399) (xy 83.522312 -39.372032)
			(xy 83.529413 -39.367227) (xy 83.540103 -39.353832) (xy 83.545815 -39.337673) (xy 83.546188 -39.329106)
			(xy 83.546188 -39.250874) (xy 83.54584 -39.242302) (xy 83.540147 -39.22613) (xy 83.529414 -39.21276)
			(xy 83.522312 -39.207948) (xy 83.478032 -39.179705) (xy 83.393398 -39.117494) (xy 83.313661 -39.049121)
			(xy 83.239268 -38.974969) (xy 83.170637 -38.895454) (xy 83.108153 -38.811022) (xy 83.052167 -38.722149)
			(xy 83.002993 -38.629333) (xy 82.960908 -38.533095) (xy 82.926147 -38.433976) (xy 82.898907 -38.332532)
			(xy 82.87934 -38.229333) (xy 82.867555 -38.124959) (xy 82.86362 -38.019995) (xy 79.316418 -38.019995)
			(xy 79.312483 -38.124959) (xy 79.300698 -38.229334) (xy 79.28113 -38.332534) (xy 79.253888 -38.433978)
			(xy 79.219126 -38.533097) (xy 79.177038 -38.629335) (xy 79.127862 -38.72215) (xy 79.071873 -38.811023)
			(xy 79.009385 -38.895452) (xy 78.940751 -38.974965) (xy 78.866354 -39.049115) (xy 78.786614 -39.117486)
			(xy 78.701977 -39.179692) (xy 78.657704 -39.207948) (xy 78.650616 -39.212769) (xy 78.639922 -39.226157)
			(xy 78.634205 -39.242309) (xy 78.633828 -39.250874) (xy 78.633828 -39.329106) (xy 78.634182 -39.337678)
			(xy 78.639871 -39.35385) (xy 78.650602 -39.36722) (xy 78.657704 -39.372032) (xy 78.703653 -39.401414)
			(xy 78.791348 -39.466272) (xy 78.873734 -39.537753) (xy 78.950314 -39.615424) (xy 79.020622 -39.698813)
			(xy 79.084234 -39.787417) (xy 79.140763 -39.880699) (xy 79.189869 -39.978093) (xy 79.231254 -40.079011)
			(xy 79.264666 -40.182841) (xy 79.289904 -40.288955) (xy 79.306815 -40.39671) (xy 79.315297 -40.505453)
			(xy 79.315818 -40.55999) (xy 79.315322 -40.612386) (xy 79.307492 -40.716886) (xy 79.291874 -40.820509)
			(xy 79.268556 -40.922674) (xy 79.237669 -41.022812) (xy 79.199384 -41.120361) (xy 79.153917 -41.214776)
			(xy 79.101521 -41.30553) (xy 79.04249 -41.392114) (xy 78.977153 -41.474045) (xy 78.905877 -41.550864)
			(xy 78.829058 -41.622141) (xy 78.747129 -41.687479) (xy 78.660545 -41.746512) (xy 78.569792 -41.798909)
			(xy 78.475377 -41.844377) (xy 78.377829 -41.882663) (xy 78.277692 -41.913552) (xy 78.175526 -41.936871)
			(xy 78.071904 -41.95249) (xy 77.967404 -41.960322) (xy 77.915008 -41.9608) (xy 77.860471 -41.960281)
			(xy 77.751728 -41.951794) (xy 77.643975 -41.934879) (xy 77.537862 -41.909638) (xy 77.434033 -41.876224)
			(xy 77.333115 -41.834839) (xy 77.235721 -41.785734) (xy 77.142438 -41.729206) (xy 77.053833 -41.665597)
			(xy 76.970441 -41.595292) (xy 76.892767 -41.518716) (xy 76.821282 -41.436334) (xy 76.756417 -41.348644)
			(xy 76.72705 -41.302686) (xy 76.722235 -41.295593) (xy 76.708844 -41.284901) (xy 76.69269 -41.279186)
			(xy 76.684124 -41.27881) (xy 76.605892 -41.27881) (xy 76.597321 -41.279171) (xy 76.58115 -41.284858)
			(xy 76.567779 -41.295586) (xy 76.562966 -41.302686) (xy 76.533579 -41.348631) (xy 76.468721 -41.436327)
			(xy 76.397241 -41.518714) (xy 76.319571 -41.595294) (xy 76.236182 -41.665602) (xy 76.147579 -41.729214)
			(xy 76.054298 -41.785745) (xy 75.956904 -41.834851) (xy 75.855986 -41.876235) (xy 75.752156 -41.909648)
			(xy 75.646043 -41.934886) (xy 75.538288 -41.951797) (xy 75.429545 -41.960279) (xy 75.375008 -41.9608)
			(xy 75.322611 -41.960324) (xy 75.21811 -41.952494) (xy 75.114487 -41.936875) (xy 75.012321 -41.913557)
			(xy 74.912183 -41.882669) (xy 74.814633 -41.844384) (xy 74.720217 -41.798916) (xy 74.629463 -41.746519)
			(xy 74.542878 -41.687487) (xy 74.460947 -41.622149) (xy 74.384128 -41.550871) (xy 74.31285 -41.474052)
			(xy 74.247512 -41.39212) (xy 74.18848 -41.305536) (xy 74.136083 -41.214781) (xy 74.090616 -41.120365)
			(xy 74.05233 -41.022816) (xy 74.021442 -40.922677) (xy 73.998124 -40.820511) (xy 73.982506 -40.716888)
			(xy 73.974676 -40.612387) (xy 73.974198 -40.55999) (xy 73.974703 -40.505453) (xy 73.983191 -40.39671)
			(xy 74.000108 -40.288956) (xy 74.02535 -40.182843) (xy 74.058765 -40.079013) (xy 74.100151 -39.978096)
			(xy 74.149258 -39.880701) (xy 74.205787 -39.787419) (xy 74.269397 -39.698814) (xy 74.339703 -39.615422)
			(xy 74.41628 -39.537749) (xy 74.498663 -39.466263) (xy 74.586354 -39.401399) (xy 74.632312 -39.372032)
			(xy 74.639413 -39.367227) (xy 74.650103 -39.353832) (xy 74.655815 -39.337673) (xy 74.656188 -39.329106)
			(xy 74.656188 -39.250874) (xy 74.65584 -39.242302) (xy 74.650147 -39.22613) (xy 74.639414 -39.21276)
			(xy 74.632312 -39.207948) (xy 74.588032 -39.179705) (xy 74.503398 -39.117494) (xy 74.423661 -39.049121)
			(xy 74.349268 -38.974969) (xy 74.280637 -38.895454) (xy 74.218153 -38.811022) (xy 74.162167 -38.722149)
			(xy 74.112993 -38.629333) (xy 74.070908 -38.533095) (xy 74.036147 -38.433976) (xy 74.008907 -38.332532)
			(xy 73.98934 -38.229333) (xy 73.977555 -38.124959) (xy 73.97362 -38.019995) (xy 44.057311 -38.019995)
			(xy 35.447986 -46.62932) (xy 35.441133 -46.636715) (xy 35.433393 -46.655314) (xy 35.433 -46.665388)
			(xy 35.433 -52.324) (xy 74.548492 -52.324) (xy 74.548492 -52.323238) (xy 74.5489 -52.285018) (xy 74.555465 -52.208859)
			(xy 74.568549 -52.133547) (xy 74.588056 -52.059637) (xy 74.600562 -52.023518) (xy 74.603148 -52.015202)
			(xy 74.603148 -51.997798) (xy 74.600562 -51.989482) (xy 74.588071 -51.953359) (xy 74.568581 -51.879447)
			(xy 74.555497 -51.804136) (xy 74.548915 -51.727981) (xy 74.548492 -51.689762) (xy 74.548492 -51.689)
			(xy 74.548907 -51.648953) (xy 74.556102 -51.569184) (xy 74.570436 -51.490384) (xy 74.59179 -51.41319)
			(xy 74.619994 -51.338227) (xy 74.654818 -51.2661) (xy 74.695982 -51.197395) (xy 74.743151 -51.132665)
			(xy 74.769218 -51.10226) (xy 74.774983 -51.095171) (xy 74.781495 -51.078114) (xy 74.781918 -51.068986)
			(xy 74.781918 -51.039014) (xy 74.781484 -51.029891) (xy 74.774964 -51.012841) (xy 74.769218 -51.00574)
			(xy 74.74316 -50.975326) (xy 74.695974 -50.910608) (xy 74.654798 -50.841908) (xy 74.619967 -50.769784)
			(xy 74.591763 -50.69482) (xy 74.570414 -50.617623) (xy 74.556094 -50.538819) (xy 74.548919 -50.459047)
			(xy 74.548492 -50.419) (xy 74.548492 -50.418238) (xy 74.5489 -50.380018) (xy 74.555465 -50.303859)
			(xy 74.568549 -50.228547) (xy 74.588056 -50.154637) (xy 74.600562 -50.118518) (xy 74.603148 -50.110202)
			(xy 74.603148 -50.092798) (xy 74.600562 -50.084482) (xy 74.588071 -50.048359) (xy 74.568581 -49.974447)
			(xy 74.555497 -49.899136) (xy 74.548915 -49.822981) (xy 74.548492 -49.784762) (xy 74.548492 -49.784)
			(xy 74.548996 -49.741652) (xy 74.557047 -49.657338) (xy 74.573076 -49.574172) (xy 74.596937 -49.492905)
			(xy 74.628416 -49.414275) (xy 74.667227 -49.338994) (xy 74.713017 -49.267742) (xy 74.765373 -49.201166)
			(xy 74.823821 -49.139868) (xy 74.887831 -49.084403) (xy 74.956823 -49.035274) (xy 75.030173 -48.992925)
			(xy 75.107216 -48.957741) (xy 75.187255 -48.930039) (xy 75.269564 -48.910071) (xy 75.353399 -48.898018)
			(xy 75.438 -48.893988) (xy 75.522601 -48.898018) (xy 75.606436 -48.910071) (xy 75.688745 -48.930039)
			(xy 75.768784 -48.957741) (xy 75.845827 -48.992925) (xy 75.919177 -49.035274) (xy 75.988169 -49.084403)
			(xy 76.052179 -49.139868) (xy 76.110627 -49.201166) (xy 76.162983 -49.267742) (xy 76.208773 -49.338994)
			(xy 76.247584 -49.414275) (xy 76.279063 -49.492905) (xy 76.302924 -49.574172) (xy 76.318953 -49.657338)
			(xy 76.327004 -49.741652) (xy 76.327508 -49.784) (xy 76.327508 -49.784762) (xy 76.3271 -49.822982)
			(xy 76.320535 -49.899141) (xy 76.307451 -49.974453) (xy 76.287944 -50.048363) (xy 76.275438 -50.084482)
			(xy 76.272852 -50.092798) (xy 76.272852 -50.110202) (xy 76.275438 -50.118518) (xy 76.287929 -50.154641)
			(xy 76.307419 -50.228553) (xy 76.320503 -50.303864) (xy 76.327085 -50.380019) (xy 76.327508 -50.418238)
			(xy 76.327508 -50.419) (xy 76.327093 -50.459047) (xy 76.319898 -50.538816) (xy 76.305564 -50.617616)
			(xy 76.28421 -50.69481) (xy 76.256006 -50.769773) (xy 76.221182 -50.8419) (xy 76.180018 -50.910605)
			(xy 76.132849 -50.975335) (xy 76.106782 -51.00574) (xy 76.101017 -51.012829) (xy 76.094505 -51.029886)
			(xy 76.094082 -51.039014) (xy 76.094082 -51.068986) (xy 76.094516 -51.078109) (xy 76.101036 -51.095159)
			(xy 76.106782 -51.10226) (xy 76.13284 -51.132674) (xy 76.180026 -51.197392) (xy 76.221202 -51.266092)
			(xy 76.256033 -51.338216) (xy 76.284237 -51.41318) (xy 76.305586 -51.490377) (xy 76.319906 -51.569181)
			(xy 76.327081 -51.648953) (xy 76.327508 -51.689) (xy 76.327508 -51.689762) (xy 76.3271 -51.727982)
			(xy 76.320535 -51.804141) (xy 76.307451 -51.879453) (xy 76.287944 -51.953363) (xy 76.275438 -51.989482)
			(xy 76.272852 -51.997798) (xy 76.272852 -52.015202) (xy 76.275438 -52.023518) (xy 76.287929 -52.059641)
			(xy 76.307419 -52.133553) (xy 76.320503 -52.208864) (xy 76.327085 -52.285019) (xy 76.327508 -52.323238)
			(xy 76.327508 -52.324) (xy 80.009492 -52.324) (xy 80.009492 -52.323238) (xy 80.0099 -52.285018) (xy 80.016465 -52.208859)
			(xy 80.029549 -52.133547) (xy 80.049056 -52.059637) (xy 80.061562 -52.023518) (xy 80.064148 -52.015202)
			(xy 80.064148 -51.997798) (xy 80.061562 -51.989482) (xy 80.049071 -51.953359) (xy 80.029581 -51.879447)
			(xy 80.016497 -51.804136) (xy 80.009915 -51.727981) (xy 80.009492 -51.689762) (xy 80.009492 -51.689)
			(xy 80.009907 -51.648953) (xy 80.017102 -51.569184) (xy 80.031436 -51.490384) (xy 80.05279 -51.41319)
			(xy 80.080994 -51.338227) (xy 80.115818 -51.2661) (xy 80.156982 -51.197395) (xy 80.204151 -51.132665)
			(xy 80.230218 -51.10226) (xy 80.235983 -51.095171) (xy 80.242495 -51.078114) (xy 80.242918 -51.068986)
			(xy 80.242918 -51.039014) (xy 80.242484 -51.029891) (xy 80.235964 -51.012841) (xy 80.230218 -51.00574)
			(xy 80.20416 -50.975326) (xy 80.156974 -50.910608) (xy 80.115798 -50.841908) (xy 80.080967 -50.769784)
			(xy 80.052763 -50.69482) (xy 80.031414 -50.617623) (xy 80.017094 -50.538819) (xy 80.009919 -50.459047)
			(xy 80.009492 -50.419) (xy 80.009492 -50.418238) (xy 80.0099 -50.380018) (xy 80.016465 -50.303859)
			(xy 80.029549 -50.228547) (xy 80.049056 -50.154637) (xy 80.061562 -50.118518) (xy 80.064148 -50.110202)
			(xy 80.064148 -50.092798) (xy 80.061562 -50.084482) (xy 80.049071 -50.048359) (xy 80.029581 -49.974447)
			(xy 80.016497 -49.899136) (xy 80.009915 -49.822981) (xy 80.009492 -49.784762) (xy 80.009492 -49.784)
			(xy 80.009996 -49.741652) (xy 80.018047 -49.657338) (xy 80.034076 -49.574172) (xy 80.057937 -49.492905)
			(xy 80.089416 -49.414275) (xy 80.128227 -49.338994) (xy 80.174017 -49.267742) (xy 80.226373 -49.201166)
			(xy 80.284821 -49.139868) (xy 80.348831 -49.084403) (xy 80.417823 -49.035274) (xy 80.491173 -48.992925)
			(xy 80.568216 -48.957741) (xy 80.648255 -48.930039) (xy 80.730564 -48.910071) (xy 80.814399 -48.898018)
			(xy 80.899 -48.893988) (xy 80.983601 -48.898018) (xy 81.067436 -48.910071) (xy 81.149745 -48.930039)
			(xy 81.229784 -48.957741) (xy 81.306827 -48.992925) (xy 81.380177 -49.035274) (xy 81.449169 -49.084403)
			(xy 81.513179 -49.139868) (xy 81.571627 -49.201166) (xy 81.623983 -49.267742) (xy 81.669773 -49.338994)
			(xy 81.708584 -49.414275) (xy 81.740063 -49.492905) (xy 81.763924 -49.574172) (xy 81.779953 -49.657338)
			(xy 81.788004 -49.741652) (xy 81.788508 -49.784) (xy 81.788508 -49.784762) (xy 81.7881 -49.822982)
			(xy 81.781535 -49.899141) (xy 81.768451 -49.974453) (xy 81.748944 -50.048363) (xy 81.736438 -50.084482)
			(xy 81.733852 -50.092798) (xy 81.733852 -50.110202) (xy 81.736438 -50.118518) (xy 81.748929 -50.154641)
			(xy 81.768419 -50.228553) (xy 81.781503 -50.303864) (xy 81.788085 -50.380019) (xy 81.788508 -50.418238)
			(xy 81.788508 -50.419) (xy 81.788093 -50.459047) (xy 81.780898 -50.538816) (xy 81.766564 -50.617616)
			(xy 81.74521 -50.69481) (xy 81.717006 -50.769773) (xy 81.682182 -50.8419) (xy 81.641018 -50.910605)
			(xy 81.593849 -50.975335) (xy 81.567782 -51.00574) (xy 81.562017 -51.012829) (xy 81.555505 -51.029886)
			(xy 81.555082 -51.039014) (xy 81.555082 -51.068986) (xy 81.555516 -51.078109) (xy 81.562036 -51.095159)
			(xy 81.567782 -51.10226) (xy 81.59384 -51.132674) (xy 81.641026 -51.197392) (xy 81.682202 -51.266092)
			(xy 81.717033 -51.338216) (xy 81.745237 -51.41318) (xy 81.766586 -51.490377) (xy 81.780906 -51.569181)
			(xy 81.788081 -51.648953) (xy 81.788508 -51.689) (xy 81.788508 -51.689762) (xy 81.7881 -51.727982)
			(xy 81.781535 -51.804141) (xy 81.768451 -51.879453) (xy 81.748944 -51.953363) (xy 81.736438 -51.989482)
			(xy 81.733852 -51.997798) (xy 81.733852 -52.015202) (xy 81.736438 -52.023518) (xy 81.748929 -52.059641)
			(xy 81.768419 -52.133553) (xy 81.781503 -52.208864) (xy 81.788085 -52.285019) (xy 81.788508 -52.323238)
			(xy 81.788508 -52.324) (xy 85.470492 -52.324) (xy 85.470492 -52.323238) (xy 85.4709 -52.285018) (xy 85.477465 -52.208859)
			(xy 85.490549 -52.133547) (xy 85.510056 -52.059637) (xy 85.522562 -52.023518) (xy 85.525148 -52.015202)
			(xy 85.525148 -51.997798) (xy 85.522562 -51.989482) (xy 85.510071 -51.953359) (xy 85.490581 -51.879447)
			(xy 85.477497 -51.804136) (xy 85.470915 -51.727981) (xy 85.470492 -51.689762) (xy 85.470492 -51.689)
			(xy 85.470907 -51.648953) (xy 85.478102 -51.569184) (xy 85.492436 -51.490384) (xy 85.51379 -51.41319)
			(xy 85.541994 -51.338227) (xy 85.576818 -51.2661) (xy 85.617982 -51.197395) (xy 85.665151 -51.132665)
			(xy 85.691218 -51.10226) (xy 85.696983 -51.095171) (xy 85.703495 -51.078114) (xy 85.703918 -51.068986)
			(xy 85.703918 -51.039014) (xy 85.703484 -51.029891) (xy 85.696964 -51.012841) (xy 85.691218 -51.00574)
			(xy 85.66516 -50.975326) (xy 85.617974 -50.910608) (xy 85.576798 -50.841908) (xy 85.541967 -50.769784)
			(xy 85.513763 -50.69482) (xy 85.492414 -50.617623) (xy 85.478094 -50.538819) (xy 85.470919 -50.459047)
			(xy 85.470492 -50.419) (xy 85.470492 -50.418238) (xy 85.4709 -50.380018) (xy 85.477465 -50.303859)
			(xy 85.490549 -50.228547) (xy 85.510056 -50.154637) (xy 85.522562 -50.118518) (xy 85.525148 -50.110202)
			(xy 85.525148 -50.092798) (xy 85.522562 -50.084482) (xy 85.510071 -50.048359) (xy 85.490581 -49.974447)
			(xy 85.477497 -49.899136) (xy 85.470915 -49.822981) (xy 85.470492 -49.784762) (xy 85.470492 -49.784)
			(xy 85.470996 -49.741652) (xy 85.479047 -49.657338) (xy 85.495076 -49.574172) (xy 85.518937 -49.492905)
			(xy 85.550416 -49.414275) (xy 85.589227 -49.338994) (xy 85.635017 -49.267742) (xy 85.687373 -49.201166)
			(xy 85.745821 -49.139868) (xy 85.809831 -49.084403) (xy 85.878823 -49.035274) (xy 85.952173 -48.992925)
			(xy 86.029216 -48.957741) (xy 86.109255 -48.930039) (xy 86.191564 -48.910071) (xy 86.275399 -48.898018)
			(xy 86.36 -48.893988) (xy 86.444601 -48.898018) (xy 86.528436 -48.910071) (xy 86.610745 -48.930039)
			(xy 86.690784 -48.957741) (xy 86.767827 -48.992925) (xy 86.841177 -49.035274) (xy 86.910169 -49.084403)
			(xy 86.974179 -49.139868) (xy 87.032627 -49.201166) (xy 87.084983 -49.267742) (xy 87.130773 -49.338994)
			(xy 87.169584 -49.414275) (xy 87.201063 -49.492905) (xy 87.224924 -49.574172) (xy 87.240953 -49.657338)
			(xy 87.249004 -49.741652) (xy 87.249508 -49.784) (xy 87.249508 -49.784762) (xy 87.2491 -49.822982)
			(xy 87.242535 -49.899141) (xy 87.229451 -49.974453) (xy 87.209944 -50.048363) (xy 87.197438 -50.084482)
			(xy 87.194852 -50.092798) (xy 87.194852 -50.110202) (xy 87.197438 -50.118518) (xy 87.209929 -50.154641)
			(xy 87.229419 -50.228553) (xy 87.242503 -50.303864) (xy 87.249085 -50.380019) (xy 87.249508 -50.418238)
			(xy 87.249508 -50.419) (xy 87.249093 -50.459047) (xy 87.241898 -50.538816) (xy 87.227564 -50.617616)
			(xy 87.20621 -50.69481) (xy 87.178006 -50.769773) (xy 87.143182 -50.8419) (xy 87.102018 -50.910605)
			(xy 87.054849 -50.975335) (xy 87.028782 -51.00574) (xy 87.023017 -51.012829) (xy 87.016505 -51.029886)
			(xy 87.016082 -51.039014) (xy 87.016082 -51.068986) (xy 87.016516 -51.078109) (xy 87.023036 -51.095159)
			(xy 87.028782 -51.10226) (xy 87.05484 -51.132674) (xy 87.102026 -51.197392) (xy 87.143202 -51.266092)
			(xy 87.178033 -51.338216) (xy 87.206237 -51.41318) (xy 87.227586 -51.490377) (xy 87.241906 -51.569181)
			(xy 87.249081 -51.648953) (xy 87.249508 -51.689) (xy 87.249508 -51.689762) (xy 87.2491 -51.727982)
			(xy 87.242535 -51.804141) (xy 87.229451 -51.879453) (xy 87.209944 -51.953363) (xy 87.197438 -51.989482)
			(xy 87.194852 -51.997798) (xy 87.194852 -52.015202) (xy 87.197438 -52.023518) (xy 87.209929 -52.059641)
			(xy 87.229419 -52.133553) (xy 87.242503 -52.208864) (xy 87.249085 -52.285019) (xy 87.249508 -52.323238)
			(xy 87.249508 -52.324) (xy 90.931492 -52.324) (xy 90.931492 -52.323238) (xy 90.9319 -52.285018) (xy 90.938465 -52.208859)
			(xy 90.951549 -52.133547) (xy 90.971056 -52.059637) (xy 90.983562 -52.023518) (xy 90.986148 -52.015202)
			(xy 90.986148 -51.997798) (xy 90.983562 -51.989482) (xy 90.971071 -51.953359) (xy 90.951581 -51.879447)
			(xy 90.938497 -51.804136) (xy 90.931915 -51.727981) (xy 90.931492 -51.689762) (xy 90.931492 -51.689)
			(xy 90.931907 -51.648953) (xy 90.939102 -51.569184) (xy 90.953436 -51.490384) (xy 90.97479 -51.41319)
			(xy 91.002994 -51.338227) (xy 91.037818 -51.2661) (xy 91.078982 -51.197395) (xy 91.126151 -51.132665)
			(xy 91.152218 -51.10226) (xy 91.157983 -51.095171) (xy 91.164495 -51.078114) (xy 91.164918 -51.068986)
			(xy 91.164918 -51.039014) (xy 91.164484 -51.029891) (xy 91.157964 -51.012841) (xy 91.152218 -51.00574)
			(xy 91.12616 -50.975326) (xy 91.078974 -50.910608) (xy 91.037798 -50.841908) (xy 91.002967 -50.769784)
			(xy 90.974763 -50.69482) (xy 90.953414 -50.617623) (xy 90.939094 -50.538819) (xy 90.931919 -50.459047)
			(xy 90.931492 -50.419) (xy 90.931492 -50.418238) (xy 90.9319 -50.380018) (xy 90.938465 -50.303859)
			(xy 90.951549 -50.228547) (xy 90.971056 -50.154637) (xy 90.983562 -50.118518) (xy 90.986148 -50.110202)
			(xy 90.986148 -50.092798) (xy 90.983562 -50.084482) (xy 90.971071 -50.048359) (xy 90.951581 -49.974447)
			(xy 90.938497 -49.899136) (xy 90.931915 -49.822981) (xy 90.931492 -49.784762) (xy 90.931492 -49.784)
			(xy 90.931996 -49.741652) (xy 90.940047 -49.657338) (xy 90.956076 -49.574172) (xy 90.979937 -49.492905)
			(xy 91.011416 -49.414275) (xy 91.050227 -49.338994) (xy 91.096017 -49.267742) (xy 91.148373 -49.201166)
			(xy 91.206821 -49.139868) (xy 91.270831 -49.084403) (xy 91.339823 -49.035274) (xy 91.413173 -48.992925)
			(xy 91.490216 -48.957741) (xy 91.570255 -48.930039) (xy 91.652564 -48.910071) (xy 91.736399 -48.898018)
			(xy 91.821 -48.893988) (xy 91.905601 -48.898018) (xy 91.989436 -48.910071) (xy 92.071745 -48.930039)
			(xy 92.151784 -48.957741) (xy 92.228827 -48.992925) (xy 92.302177 -49.035274) (xy 92.371169 -49.084403)
			(xy 92.435179 -49.139868) (xy 92.493627 -49.201166) (xy 92.545983 -49.267742) (xy 92.591773 -49.338994)
			(xy 92.630584 -49.414275) (xy 92.662063 -49.492905) (xy 92.685924 -49.574172) (xy 92.701953 -49.657338)
			(xy 92.710004 -49.741652) (xy 92.710508 -49.784) (xy 92.710508 -49.784762) (xy 92.7101 -49.822982)
			(xy 92.703535 -49.899141) (xy 92.690451 -49.974453) (xy 92.670944 -50.048363) (xy 92.658438 -50.084482)
			(xy 92.655852 -50.092798) (xy 92.655852 -50.110202) (xy 92.658438 -50.118518) (xy 92.670929 -50.154641)
			(xy 92.690419 -50.228553) (xy 92.703503 -50.303864) (xy 92.710085 -50.380019) (xy 92.710508 -50.418238)
			(xy 92.710508 -50.419) (xy 92.710093 -50.459047) (xy 92.702898 -50.538816) (xy 92.688564 -50.617616)
			(xy 92.66721 -50.69481) (xy 92.639006 -50.769773) (xy 92.604182 -50.8419) (xy 92.563018 -50.910605)
			(xy 92.515849 -50.975335) (xy 92.489782 -51.00574) (xy 92.484017 -51.012829) (xy 92.477505 -51.029886)
			(xy 92.477082 -51.039014) (xy 92.477082 -51.068986) (xy 92.477516 -51.078109) (xy 92.484036 -51.095159)
			(xy 92.489782 -51.10226) (xy 92.51584 -51.132674) (xy 92.563026 -51.197392) (xy 92.604202 -51.266092)
			(xy 92.639033 -51.338216) (xy 92.667237 -51.41318) (xy 92.688586 -51.490377) (xy 92.702906 -51.569181)
			(xy 92.710081 -51.648953) (xy 92.710508 -51.689) (xy 92.710508 -51.689762) (xy 92.7101 -51.727982)
			(xy 92.703535 -51.804141) (xy 92.690451 -51.879453) (xy 92.670944 -51.953363) (xy 92.658438 -51.989482)
			(xy 92.655852 -51.997798) (xy 92.655852 -52.015202) (xy 92.658438 -52.023518) (xy 92.670929 -52.059641)
			(xy 92.690419 -52.133553) (xy 92.703503 -52.208864) (xy 92.710085 -52.285019) (xy 92.710508 -52.323238)
			(xy 92.710508 -52.324) (xy 96.392492 -52.324) (xy 96.392492 -52.323238) (xy 96.3929 -52.285018) (xy 96.399465 -52.208859)
			(xy 96.412549 -52.133547) (xy 96.432056 -52.059637) (xy 96.444562 -52.023518) (xy 96.447148 -52.015202)
			(xy 96.447148 -51.997798) (xy 96.444562 -51.989482) (xy 96.432071 -51.953359) (xy 96.412581 -51.879447)
			(xy 96.399497 -51.804136) (xy 96.392915 -51.727981) (xy 96.392492 -51.689762) (xy 96.392492 -51.689)
			(xy 96.392907 -51.648953) (xy 96.400102 -51.569184) (xy 96.414436 -51.490384) (xy 96.43579 -51.41319)
			(xy 96.463994 -51.338227) (xy 96.498818 -51.2661) (xy 96.539982 -51.197395) (xy 96.587151 -51.132665)
			(xy 96.613218 -51.10226) (xy 96.618983 -51.095171) (xy 96.625495 -51.078114) (xy 96.625918 -51.068986)
			(xy 96.625918 -51.039014) (xy 96.625484 -51.029891) (xy 96.618964 -51.012841) (xy 96.613218 -51.00574)
			(xy 96.58716 -50.975326) (xy 96.539974 -50.910608) (xy 96.498798 -50.841908) (xy 96.463967 -50.769784)
			(xy 96.435763 -50.69482) (xy 96.414414 -50.617623) (xy 96.400094 -50.538819) (xy 96.392919 -50.459047)
			(xy 96.392492 -50.419) (xy 96.392492 -50.418238) (xy 96.3929 -50.380018) (xy 96.399465 -50.303859)
			(xy 96.412549 -50.228547) (xy 96.432056 -50.154637) (xy 96.444562 -50.118518) (xy 96.447148 -50.110202)
			(xy 96.447148 -50.092798) (xy 96.444562 -50.084482) (xy 96.432071 -50.048359) (xy 96.412581 -49.974447)
			(xy 96.399497 -49.899136) (xy 96.392915 -49.822981) (xy 96.392492 -49.784762) (xy 96.392492 -49.784)
			(xy 96.392996 -49.741652) (xy 96.401047 -49.657338) (xy 96.417076 -49.574172) (xy 96.440937 -49.492905)
			(xy 96.472416 -49.414275) (xy 96.511227 -49.338994) (xy 96.557017 -49.267742) (xy 96.609373 -49.201166)
			(xy 96.667821 -49.139868) (xy 96.731831 -49.084403) (xy 96.800823 -49.035274) (xy 96.874173 -48.992925)
			(xy 96.951216 -48.957741) (xy 97.031255 -48.930039) (xy 97.113564 -48.910071) (xy 97.197399 -48.898018)
			(xy 97.282 -48.893988) (xy 97.366601 -48.898018) (xy 97.450436 -48.910071) (xy 97.532745 -48.930039)
			(xy 97.612784 -48.957741) (xy 97.689827 -48.992925) (xy 97.763177 -49.035274) (xy 97.832169 -49.084403)
			(xy 97.896179 -49.139868) (xy 97.954627 -49.201166) (xy 98.006983 -49.267742) (xy 98.052773 -49.338994)
			(xy 98.091584 -49.414275) (xy 98.123063 -49.492905) (xy 98.146924 -49.574172) (xy 98.162953 -49.657338)
			(xy 98.171004 -49.741652) (xy 98.171508 -49.784) (xy 98.171508 -49.784762) (xy 98.1711 -49.822982)
			(xy 98.164535 -49.899141) (xy 98.151451 -49.974453) (xy 98.131944 -50.048363) (xy 98.119438 -50.084482)
			(xy 98.116852 -50.092798) (xy 98.116852 -50.110202) (xy 98.119438 -50.118518) (xy 98.131929 -50.154641)
			(xy 98.151419 -50.228553) (xy 98.164503 -50.303864) (xy 98.171085 -50.380019) (xy 98.171508 -50.418238)
			(xy 98.171508 -50.419) (xy 98.171093 -50.459047) (xy 98.163898 -50.538816) (xy 98.149564 -50.617616)
			(xy 98.12821 -50.69481) (xy 98.100006 -50.769773) (xy 98.065182 -50.8419) (xy 98.024018 -50.910605)
			(xy 97.976849 -50.975335) (xy 97.950782 -51.00574) (xy 97.945017 -51.012829) (xy 97.938505 -51.029886)
			(xy 97.938082 -51.039014) (xy 97.938082 -51.068986) (xy 97.938516 -51.078109) (xy 97.945036 -51.095159)
			(xy 97.950782 -51.10226) (xy 97.97684 -51.132674) (xy 98.024026 -51.197392) (xy 98.065202 -51.266092)
			(xy 98.100033 -51.338216) (xy 98.128237 -51.41318) (xy 98.149586 -51.490377) (xy 98.163906 -51.569181)
			(xy 98.171081 -51.648953) (xy 98.171508 -51.689) (xy 98.171508 -51.689762) (xy 98.1711 -51.727982)
			(xy 98.164535 -51.804141) (xy 98.151451 -51.879453) (xy 98.131944 -51.953363) (xy 98.119438 -51.989482)
			(xy 98.116852 -51.997798) (xy 98.116852 -52.015202) (xy 98.119438 -52.023518) (xy 98.131929 -52.059641)
			(xy 98.151419 -52.133553) (xy 98.164503 -52.208864) (xy 98.171085 -52.285019) (xy 98.171508 -52.323238)
			(xy 98.171508 -52.324) (xy 101.853492 -52.324) (xy 101.853492 -52.323238) (xy 101.8539 -52.285018)
			(xy 101.860465 -52.208859) (xy 101.873549 -52.133547) (xy 101.893056 -52.059637) (xy 101.905562 -52.023518)
			(xy 101.908148 -52.015202) (xy 101.908148 -51.997798) (xy 101.905562 -51.989482) (xy 101.893071 -51.953359)
			(xy 101.873581 -51.879447) (xy 101.860497 -51.804136) (xy 101.853915 -51.727981) (xy 101.853492 -51.689762)
			(xy 101.853492 -51.689) (xy 101.853907 -51.648953) (xy 101.861102 -51.569184) (xy 101.875436 -51.490384)
			(xy 101.89679 -51.41319) (xy 101.924994 -51.338227) (xy 101.959818 -51.2661) (xy 102.000982 -51.197395)
			(xy 102.048151 -51.132665) (xy 102.074218 -51.10226) (xy 102.079983 -51.095171) (xy 102.086495 -51.078114)
			(xy 102.086918 -51.068986) (xy 102.086918 -51.039014) (xy 102.086484 -51.029891) (xy 102.079964 -51.012841)
			(xy 102.074218 -51.00574) (xy 102.04816 -50.975326) (xy 102.000974 -50.910608) (xy 101.959798 -50.841908)
			(xy 101.924967 -50.769784) (xy 101.896763 -50.69482) (xy 101.875414 -50.617623) (xy 101.861094 -50.538819)
			(xy 101.853919 -50.459047) (xy 101.853492 -50.419) (xy 101.853492 -50.418238) (xy 101.8539 -50.380018)
			(xy 101.860465 -50.303859) (xy 101.873549 -50.228547) (xy 101.893056 -50.154637) (xy 101.905562 -50.118518)
			(xy 101.908148 -50.110202) (xy 101.908148 -50.092798) (xy 101.905562 -50.084482) (xy 101.893071 -50.048359)
			(xy 101.873581 -49.974447) (xy 101.860497 -49.899136) (xy 101.853915 -49.822981) (xy 101.853492 -49.784762)
			(xy 101.853492 -49.784) (xy 101.853996 -49.741652) (xy 101.862047 -49.657338) (xy 101.878076 -49.574172)
			(xy 101.901937 -49.492905) (xy 101.933416 -49.414275) (xy 101.972227 -49.338994) (xy 102.018017 -49.267742)
			(xy 102.070373 -49.201166) (xy 102.128821 -49.139868) (xy 102.192831 -49.084403) (xy 102.261823 -49.035274)
			(xy 102.335173 -48.992925) (xy 102.412216 -48.957741) (xy 102.492255 -48.930039) (xy 102.574564 -48.910071)
			(xy 102.658399 -48.898018) (xy 102.743 -48.893988) (xy 102.827601 -48.898018) (xy 102.911436 -48.910071)
			(xy 102.993745 -48.930039) (xy 103.073784 -48.957741) (xy 103.150827 -48.992925) (xy 103.224177 -49.035274)
			(xy 103.293169 -49.084403) (xy 103.357179 -49.139868) (xy 103.415627 -49.201166) (xy 103.467983 -49.267742)
			(xy 103.513773 -49.338994) (xy 103.552584 -49.414275) (xy 103.584063 -49.492905) (xy 103.607924 -49.574172)
			(xy 103.623953 -49.657338) (xy 103.632004 -49.741652) (xy 103.632508 -49.784) (xy 103.632508 -49.784762)
			(xy 103.6321 -49.822982) (xy 103.625535 -49.899141) (xy 103.612451 -49.974453) (xy 103.592944 -50.048363)
			(xy 103.580438 -50.084482) (xy 103.577852 -50.092798) (xy 103.577852 -50.110202) (xy 103.580438 -50.118518)
			(xy 103.592929 -50.154641) (xy 103.612419 -50.228553) (xy 103.625503 -50.303864) (xy 103.632085 -50.380019)
			(xy 103.632508 -50.418238) (xy 103.632508 -50.419) (xy 103.632093 -50.459047) (xy 103.624898 -50.538816)
			(xy 103.610564 -50.617616) (xy 103.58921 -50.69481) (xy 103.561006 -50.769773) (xy 103.526182 -50.8419)
			(xy 103.485018 -50.910605) (xy 103.437849 -50.975335) (xy 103.411782 -51.00574) (xy 103.406017 -51.012829)
			(xy 103.399505 -51.029886) (xy 103.399082 -51.039014) (xy 103.399082 -51.068986) (xy 103.399516 -51.078109)
			(xy 103.406036 -51.095159) (xy 103.411782 -51.10226) (xy 103.43784 -51.132674) (xy 103.485026 -51.197392)
			(xy 103.526202 -51.266092) (xy 103.561033 -51.338216) (xy 103.589237 -51.41318) (xy 103.610586 -51.490377)
			(xy 103.624906 -51.569181) (xy 103.632081 -51.648953) (xy 103.632508 -51.689) (xy 103.632508 -51.689762)
			(xy 103.6321 -51.727982) (xy 103.625535 -51.804141) (xy 103.612451 -51.879453) (xy 103.592944 -51.953363)
			(xy 103.580438 -51.989482) (xy 103.577852 -51.997798) (xy 103.577852 -52.015202) (xy 103.580438 -52.023518)
			(xy 103.592929 -52.059641) (xy 103.612419 -52.133553) (xy 103.625503 -52.208864) (xy 103.632085 -52.285019)
			(xy 103.632508 -52.323238) (xy 103.632508 -52.324) (xy 107.314492 -52.324) (xy 107.314492 -52.323238)
			(xy 107.3149 -52.285018) (xy 107.321465 -52.208859) (xy 107.334549 -52.133547) (xy 107.354056 -52.059637)
			(xy 107.366562 -52.023518) (xy 107.369148 -52.015202) (xy 107.369148 -51.997798) (xy 107.366562 -51.989482)
			(xy 107.354071 -51.953359) (xy 107.334581 -51.879447) (xy 107.321497 -51.804136) (xy 107.314915 -51.727981)
			(xy 107.314492 -51.689762) (xy 107.314492 -51.689) (xy 107.314907 -51.648953) (xy 107.322102 -51.569184)
			(xy 107.336436 -51.490384) (xy 107.35779 -51.41319) (xy 107.385994 -51.338227) (xy 107.420818 -51.2661)
			(xy 107.461982 -51.197395) (xy 107.509151 -51.132665) (xy 107.535218 -51.10226) (xy 107.540983 -51.095171)
			(xy 107.547495 -51.078114) (xy 107.547918 -51.068986) (xy 107.547918 -51.039014) (xy 107.547484 -51.029891)
			(xy 107.540964 -51.012841) (xy 107.535218 -51.00574) (xy 107.50916 -50.975326) (xy 107.461974 -50.910608)
			(xy 107.420798 -50.841908) (xy 107.385967 -50.769784) (xy 107.357763 -50.69482) (xy 107.336414 -50.617623)
			(xy 107.322094 -50.538819) (xy 107.314919 -50.459047) (xy 107.314492 -50.419) (xy 107.314492 -50.418238)
			(xy 107.3149 -50.380018) (xy 107.321465 -50.303859) (xy 107.334549 -50.228547) (xy 107.354056 -50.154637)
			(xy 107.366562 -50.118518) (xy 107.369148 -50.110202) (xy 107.369148 -50.092798) (xy 107.366562 -50.084482)
			(xy 107.354071 -50.048359) (xy 107.334581 -49.974447) (xy 107.321497 -49.899136) (xy 107.314915 -49.822981)
			(xy 107.314492 -49.784762) (xy 107.314492 -49.784) (xy 107.314996 -49.741652) (xy 107.323047 -49.657338)
			(xy 107.339076 -49.574172) (xy 107.362937 -49.492905) (xy 107.394416 -49.414275) (xy 107.433227 -49.338994)
			(xy 107.479017 -49.267742) (xy 107.531373 -49.201166) (xy 107.589821 -49.139868) (xy 107.653831 -49.084403)
			(xy 107.722823 -49.035274) (xy 107.796173 -48.992925) (xy 107.873216 -48.957741) (xy 107.953255 -48.930039)
			(xy 108.035564 -48.910071) (xy 108.119399 -48.898018) (xy 108.204 -48.893988) (xy 108.288601 -48.898018)
			(xy 108.372436 -48.910071) (xy 108.454745 -48.930039) (xy 108.534784 -48.957741) (xy 108.611827 -48.992925)
			(xy 108.685177 -49.035274) (xy 108.754169 -49.084403) (xy 108.818179 -49.139868) (xy 108.876627 -49.201166)
			(xy 108.928983 -49.267742) (xy 108.974773 -49.338994) (xy 109.013584 -49.414275) (xy 109.045063 -49.492905)
			(xy 109.068924 -49.574172) (xy 109.084953 -49.657338) (xy 109.093004 -49.741652) (xy 109.093508 -49.784)
			(xy 109.093508 -49.784762) (xy 109.0931 -49.822982) (xy 109.086535 -49.899141) (xy 109.073451 -49.974453)
			(xy 109.053944 -50.048363) (xy 109.041438 -50.084482) (xy 109.038852 -50.092798) (xy 109.038852 -50.110202)
			(xy 109.041438 -50.118518) (xy 109.053929 -50.154641) (xy 109.073419 -50.228553) (xy 109.086503 -50.303864)
			(xy 109.093085 -50.380019) (xy 109.093508 -50.418238) (xy 109.093508 -50.419) (xy 109.093093 -50.459047)
			(xy 109.085898 -50.538816) (xy 109.071564 -50.617616) (xy 109.05021 -50.69481) (xy 109.022006 -50.769773)
			(xy 108.987182 -50.8419) (xy 108.946018 -50.910605) (xy 108.898849 -50.975335) (xy 108.872782 -51.00574)
			(xy 108.867017 -51.012829) (xy 108.860505 -51.029886) (xy 108.860082 -51.039014) (xy 108.860082 -51.068986)
			(xy 108.860516 -51.078109) (xy 108.867036 -51.095159) (xy 108.872782 -51.10226) (xy 108.89884 -51.132674)
			(xy 108.946026 -51.197392) (xy 108.987202 -51.266092) (xy 109.022033 -51.338216) (xy 109.050237 -51.41318)
			(xy 109.071586 -51.490377) (xy 109.085906 -51.569181) (xy 109.093081 -51.648953) (xy 109.093508 -51.689)
			(xy 109.093508 -51.689762) (xy 109.0931 -51.727982) (xy 109.086535 -51.804141) (xy 109.073451 -51.879453)
			(xy 109.053944 -51.953363) (xy 109.041438 -51.989482) (xy 109.038852 -51.997798) (xy 109.038852 -52.015202)
			(xy 109.041438 -52.023518) (xy 109.053929 -52.059641) (xy 109.073419 -52.133553) (xy 109.084442 -52.197)
			(xy 152.653492 -52.197) (xy 152.653492 -52.196238) (xy 152.6539 -52.158018) (xy 152.660465 -52.081859)
			(xy 152.673549 -52.006547) (xy 152.693056 -51.932637) (xy 152.705562 -51.896518) (xy 152.708148 -51.888202)
			(xy 152.708148 -51.870798) (xy 152.705562 -51.862482) (xy 152.693071 -51.826359) (xy 152.673581 -51.752447)
			(xy 152.660497 -51.677136) (xy 152.653915 -51.600981) (xy 152.653492 -51.562762) (xy 152.653492 -51.562)
			(xy 152.653907 -51.521953) (xy 152.661102 -51.442184) (xy 152.675436 -51.363384) (xy 152.69679 -51.28619)
			(xy 152.724994 -51.211227) (xy 152.759818 -51.1391) (xy 152.800982 -51.070395) (xy 152.848151 -51.005665)
			(xy 152.874218 -50.97526) (xy 152.879983 -50.968171) (xy 152.886495 -50.951114) (xy 152.886918 -50.941986)
			(xy 152.886918 -50.912014) (xy 152.886484 -50.902891) (xy 152.879964 -50.885841) (xy 152.874218 -50.87874)
			(xy 152.84816 -50.848326) (xy 152.800974 -50.783608) (xy 152.759798 -50.714908) (xy 152.724967 -50.642784)
			(xy 152.696763 -50.56782) (xy 152.675414 -50.490623) (xy 152.661094 -50.411819) (xy 152.653919 -50.332047)
			(xy 152.653492 -50.292) (xy 152.653492 -50.291238) (xy 152.6539 -50.253018) (xy 152.660465 -50.176859)
			(xy 152.673549 -50.101547) (xy 152.693056 -50.027637) (xy 152.705562 -49.991518) (xy 152.708148 -49.983202)
			(xy 152.708148 -49.965798) (xy 152.705562 -49.957482) (xy 152.693071 -49.921359) (xy 152.673581 -49.847447)
			(xy 152.660497 -49.772136) (xy 152.653915 -49.695981) (xy 152.653492 -49.657762) (xy 152.653492 -49.657)
			(xy 152.653996 -49.614652) (xy 152.662047 -49.530338) (xy 152.678076 -49.447172) (xy 152.701937 -49.365905)
			(xy 152.733416 -49.287275) (xy 152.772227 -49.211994) (xy 152.818017 -49.140742) (xy 152.870373 -49.074166)
			(xy 152.928821 -49.012868) (xy 152.992831 -48.957403) (xy 153.061823 -48.908274) (xy 153.135173 -48.865925)
			(xy 153.212216 -48.830741) (xy 153.292255 -48.803039) (xy 153.374564 -48.783071) (xy 153.458399 -48.771018)
			(xy 153.543 -48.766988) (xy 153.627601 -48.771018) (xy 153.711436 -48.783071) (xy 153.793745 -48.803039)
			(xy 153.873784 -48.830741) (xy 153.950827 -48.865925) (xy 154.024177 -48.908274) (xy 154.093169 -48.957403)
			(xy 154.157179 -49.012868) (xy 154.215627 -49.074166) (xy 154.267983 -49.140742) (xy 154.313773 -49.211994)
			(xy 154.352584 -49.287275) (xy 154.384063 -49.365905) (xy 154.407924 -49.447172) (xy 154.423953 -49.530338)
			(xy 154.432004 -49.614652) (xy 154.432508 -49.657) (xy 154.432508 -49.657762) (xy 154.4321 -49.695982)
			(xy 154.425535 -49.772141) (xy 154.412451 -49.847453) (xy 154.392944 -49.921363) (xy 154.380438 -49.957482)
			(xy 154.377852 -49.965798) (xy 154.377852 -49.983202) (xy 154.380438 -49.991518) (xy 154.392929 -50.027641)
			(xy 154.412419 -50.101553) (xy 154.425503 -50.176864) (xy 154.432085 -50.253019) (xy 154.432508 -50.291238)
			(xy 154.432508 -50.292) (xy 154.432093 -50.332047) (xy 154.424898 -50.411816) (xy 154.410564 -50.490616)
			(xy 154.38921 -50.56781) (xy 154.361006 -50.642773) (xy 154.326182 -50.7149) (xy 154.285018 -50.783605)
			(xy 154.237849 -50.848335) (xy 154.211782 -50.87874) (xy 154.206017 -50.885829) (xy 154.199505 -50.902886)
			(xy 154.199082 -50.912014) (xy 154.199082 -50.941986) (xy 154.199516 -50.951109) (xy 154.206036 -50.968159)
			(xy 154.211782 -50.97526) (xy 154.23784 -51.005674) (xy 154.285026 -51.070392) (xy 154.326202 -51.139092)
			(xy 154.361033 -51.211216) (xy 154.389237 -51.28618) (xy 154.410586 -51.363377) (xy 154.424906 -51.442181)
			(xy 154.432081 -51.521953) (xy 154.432508 -51.562) (xy 154.432508 -51.562762) (xy 154.4321 -51.600982)
			(xy 154.425535 -51.677141) (xy 154.412451 -51.752453) (xy 154.392944 -51.826363) (xy 154.380438 -51.862482)
			(xy 154.377852 -51.870798) (xy 154.377852 -51.888202) (xy 154.380438 -51.896518) (xy 154.392929 -51.932641)
			(xy 154.412419 -52.006553) (xy 154.425503 -52.081864) (xy 154.432085 -52.158019) (xy 154.432508 -52.196238)
			(xy 154.432508 -52.197) (xy 158.114492 -52.197) (xy 158.114492 -52.196238) (xy 158.1149 -52.158018)
			(xy 158.121465 -52.081859) (xy 158.134549 -52.006547) (xy 158.154056 -51.932637) (xy 158.166562 -51.896518)
			(xy 158.169148 -51.888202) (xy 158.169148 -51.870798) (xy 158.166562 -51.862482) (xy 158.154071 -51.826359)
			(xy 158.134581 -51.752447) (xy 158.121497 -51.677136) (xy 158.114915 -51.600981) (xy 158.114492 -51.562762)
			(xy 158.114492 -51.562) (xy 158.114907 -51.521953) (xy 158.122102 -51.442184) (xy 158.136436 -51.363384)
			(xy 158.15779 -51.28619) (xy 158.185994 -51.211227) (xy 158.220818 -51.1391) (xy 158.261982 -51.070395)
			(xy 158.309151 -51.005665) (xy 158.335218 -50.97526) (xy 158.340983 -50.968171) (xy 158.347495 -50.951114)
			(xy 158.347918 -50.941986) (xy 158.347918 -50.912014) (xy 158.347484 -50.902891) (xy 158.340964 -50.885841)
			(xy 158.335218 -50.87874) (xy 158.30916 -50.848326) (xy 158.261974 -50.783608) (xy 158.220798 -50.714908)
			(xy 158.185967 -50.642784) (xy 158.157763 -50.56782) (xy 158.136414 -50.490623) (xy 158.122094 -50.411819)
			(xy 158.114919 -50.332047) (xy 158.114492 -50.292) (xy 158.114492 -50.291238) (xy 158.1149 -50.253018)
			(xy 158.121465 -50.176859) (xy 158.134549 -50.101547) (xy 158.154056 -50.027637) (xy 158.166562 -49.991518)
			(xy 158.169148 -49.983202) (xy 158.169148 -49.965798) (xy 158.166562 -49.957482) (xy 158.154071 -49.921359)
			(xy 158.134581 -49.847447) (xy 158.121497 -49.772136) (xy 158.114915 -49.695981) (xy 158.114492 -49.657762)
			(xy 158.114492 -49.657) (xy 158.114996 -49.614652) (xy 158.123047 -49.530338) (xy 158.139076 -49.447172)
			(xy 158.162937 -49.365905) (xy 158.194416 -49.287275) (xy 158.233227 -49.211994) (xy 158.279017 -49.140742)
			(xy 158.331373 -49.074166) (xy 158.389821 -49.012868) (xy 158.453831 -48.957403) (xy 158.522823 -48.908274)
			(xy 158.596173 -48.865925) (xy 158.673216 -48.830741) (xy 158.753255 -48.803039) (xy 158.835564 -48.783071)
			(xy 158.919399 -48.771018) (xy 159.004 -48.766988) (xy 159.088601 -48.771018) (xy 159.172436 -48.783071)
			(xy 159.254745 -48.803039) (xy 159.334784 -48.830741) (xy 159.411827 -48.865925) (xy 159.485177 -48.908274)
			(xy 159.554169 -48.957403) (xy 159.618179 -49.012868) (xy 159.676627 -49.074166) (xy 159.728983 -49.140742)
			(xy 159.774773 -49.211994) (xy 159.813584 -49.287275) (xy 159.845063 -49.365905) (xy 159.868924 -49.447172)
			(xy 159.884953 -49.530338) (xy 159.893004 -49.614652) (xy 159.893508 -49.657) (xy 159.893508 -49.657762)
			(xy 159.8931 -49.695982) (xy 159.886535 -49.772141) (xy 159.873451 -49.847453) (xy 159.853944 -49.921363)
			(xy 159.841438 -49.957482) (xy 159.838852 -49.965798) (xy 159.838852 -49.983202) (xy 159.841438 -49.991518)
			(xy 159.853929 -50.027641) (xy 159.873419 -50.101553) (xy 159.886503 -50.176864) (xy 159.893085 -50.253019)
			(xy 159.893508 -50.291238) (xy 159.893508 -50.292) (xy 159.893093 -50.332047) (xy 159.885898 -50.411816)
			(xy 159.871564 -50.490616) (xy 159.85021 -50.56781) (xy 159.822006 -50.642773) (xy 159.787182 -50.7149)
			(xy 159.746018 -50.783605) (xy 159.698849 -50.848335) (xy 159.672782 -50.87874) (xy 159.667017 -50.885829)
			(xy 159.660505 -50.902886) (xy 159.660082 -50.912014) (xy 159.660082 -50.941986) (xy 159.660516 -50.951109)
			(xy 159.667036 -50.968159) (xy 159.672782 -50.97526) (xy 159.69884 -51.005674) (xy 159.746026 -51.070392)
			(xy 159.787202 -51.139092) (xy 159.822033 -51.211216) (xy 159.850237 -51.28618) (xy 159.871586 -51.363377)
			(xy 159.885906 -51.442181) (xy 159.893081 -51.521953) (xy 159.893508 -51.562) (xy 159.893508 -51.562762)
			(xy 159.8931 -51.600982) (xy 159.886535 -51.677141) (xy 159.873451 -51.752453) (xy 159.853944 -51.826363)
			(xy 159.841438 -51.862482) (xy 159.838852 -51.870798) (xy 159.838852 -51.888202) (xy 159.841438 -51.896518)
			(xy 159.853929 -51.932641) (xy 159.873419 -52.006553) (xy 159.886503 -52.081864) (xy 159.893085 -52.158019)
			(xy 159.893508 -52.196238) (xy 159.893508 -52.197) (xy 163.575492 -52.197) (xy 163.575492 -52.196238)
			(xy 163.5759 -52.158018) (xy 163.582465 -52.081859) (xy 163.595549 -52.006547) (xy 163.615056 -51.932637)
			(xy 163.627562 -51.896518) (xy 163.630148 -51.888202) (xy 163.630148 -51.870798) (xy 163.627562 -51.862482)
			(xy 163.615071 -51.826359) (xy 163.595581 -51.752447) (xy 163.582497 -51.677136) (xy 163.575915 -51.600981)
			(xy 163.575492 -51.562762) (xy 163.575492 -51.562) (xy 163.575907 -51.521953) (xy 163.583102 -51.442184)
			(xy 163.597436 -51.363384) (xy 163.61879 -51.28619) (xy 163.646994 -51.211227) (xy 163.681818 -51.1391)
			(xy 163.722982 -51.070395) (xy 163.770151 -51.005665) (xy 163.796218 -50.97526) (xy 163.801983 -50.968171)
			(xy 163.808495 -50.951114) (xy 163.808918 -50.941986) (xy 163.808918 -50.912014) (xy 163.808484 -50.902891)
			(xy 163.801964 -50.885841) (xy 163.796218 -50.87874) (xy 163.77016 -50.848326) (xy 163.722974 -50.783608)
			(xy 163.681798 -50.714908) (xy 163.646967 -50.642784) (xy 163.618763 -50.56782) (xy 163.597414 -50.490623)
			(xy 163.583094 -50.411819) (xy 163.575919 -50.332047) (xy 163.575492 -50.292) (xy 163.575492 -50.291238)
			(xy 163.5759 -50.253018) (xy 163.582465 -50.176859) (xy 163.595549 -50.101547) (xy 163.615056 -50.027637)
			(xy 163.627562 -49.991518) (xy 163.630148 -49.983202) (xy 163.630148 -49.965798) (xy 163.627562 -49.957482)
			(xy 163.615071 -49.921359) (xy 163.595581 -49.847447) (xy 163.582497 -49.772136) (xy 163.575915 -49.695981)
			(xy 163.575492 -49.657762) (xy 163.575492 -49.657) (xy 163.575996 -49.614652) (xy 163.584047 -49.530338)
			(xy 163.600076 -49.447172) (xy 163.623937 -49.365905) (xy 163.655416 -49.287275) (xy 163.694227 -49.211994)
			(xy 163.740017 -49.140742) (xy 163.792373 -49.074166) (xy 163.850821 -49.012868) (xy 163.914831 -48.957403)
			(xy 163.983823 -48.908274) (xy 164.057173 -48.865925) (xy 164.134216 -48.830741) (xy 164.214255 -48.803039)
			(xy 164.296564 -48.783071) (xy 164.380399 -48.771018) (xy 164.465 -48.766988) (xy 164.549601 -48.771018)
			(xy 164.633436 -48.783071) (xy 164.715745 -48.803039) (xy 164.795784 -48.830741) (xy 164.872827 -48.865925)
			(xy 164.946177 -48.908274) (xy 165.015169 -48.957403) (xy 165.079179 -49.012868) (xy 165.137627 -49.074166)
			(xy 165.189983 -49.140742) (xy 165.235773 -49.211994) (xy 165.274584 -49.287275) (xy 165.306063 -49.365905)
			(xy 165.329924 -49.447172) (xy 165.345953 -49.530338) (xy 165.354004 -49.614652) (xy 165.354508 -49.657)
			(xy 165.354508 -49.657762) (xy 165.3541 -49.695982) (xy 165.347535 -49.772141) (xy 165.334451 -49.847453)
			(xy 165.314944 -49.921363) (xy 165.302438 -49.957482) (xy 165.299852 -49.965798) (xy 165.299852 -49.983202)
			(xy 165.302438 -49.991518) (xy 165.314929 -50.027641) (xy 165.334419 -50.101553) (xy 165.347503 -50.176864)
			(xy 165.354085 -50.253019) (xy 165.354508 -50.291238) (xy 165.354508 -50.292) (xy 165.354093 -50.332047)
			(xy 165.346898 -50.411816) (xy 165.332564 -50.490616) (xy 165.31121 -50.56781) (xy 165.283006 -50.642773)
			(xy 165.248182 -50.7149) (xy 165.207018 -50.783605) (xy 165.159849 -50.848335) (xy 165.133782 -50.87874)
			(xy 165.128017 -50.885829) (xy 165.121505 -50.902886) (xy 165.121082 -50.912014) (xy 165.121082 -50.941986)
			(xy 165.121516 -50.951109) (xy 165.128036 -50.968159) (xy 165.133782 -50.97526) (xy 165.15984 -51.005674)
			(xy 165.207026 -51.070392) (xy 165.248202 -51.139092) (xy 165.283033 -51.211216) (xy 165.311237 -51.28618)
			(xy 165.332586 -51.363377) (xy 165.346906 -51.442181) (xy 165.354081 -51.521953) (xy 165.354508 -51.562)
			(xy 165.354508 -51.562762) (xy 165.3541 -51.600982) (xy 165.347535 -51.677141) (xy 165.334451 -51.752453)
			(xy 165.314944 -51.826363) (xy 165.302438 -51.862482) (xy 165.299852 -51.870798) (xy 165.299852 -51.888202)
			(xy 165.302438 -51.896518) (xy 165.314929 -51.932641) (xy 165.334419 -52.006553) (xy 165.347503 -52.081864)
			(xy 165.354085 -52.158019) (xy 165.354508 -52.196238) (xy 165.354508 -52.197) (xy 169.036492 -52.197)
			(xy 169.036492 -52.196238) (xy 169.0369 -52.158018) (xy 169.043465 -52.081859) (xy 169.056549 -52.006547)
			(xy 169.076056 -51.932637) (xy 169.088562 -51.896518) (xy 169.091148 -51.888202) (xy 169.091148 -51.870798)
			(xy 169.088562 -51.862482) (xy 169.076071 -51.826359) (xy 169.056581 -51.752447) (xy 169.043497 -51.677136)
			(xy 169.036915 -51.600981) (xy 169.036492 -51.562762) (xy 169.036492 -51.562) (xy 169.036907 -51.521953)
			(xy 169.044102 -51.442184) (xy 169.058436 -51.363384) (xy 169.07979 -51.28619) (xy 169.107994 -51.211227)
			(xy 169.142818 -51.1391) (xy 169.183982 -51.070395) (xy 169.231151 -51.005665) (xy 169.257218 -50.97526)
			(xy 169.262983 -50.968171) (xy 169.269495 -50.951114) (xy 169.269918 -50.941986) (xy 169.269918 -50.912014)
			(xy 169.269484 -50.902891) (xy 169.262964 -50.885841) (xy 169.257218 -50.87874) (xy 169.23116 -50.848326)
			(xy 169.183974 -50.783608) (xy 169.142798 -50.714908) (xy 169.107967 -50.642784) (xy 169.079763 -50.56782)
			(xy 169.058414 -50.490623) (xy 169.044094 -50.411819) (xy 169.036919 -50.332047) (xy 169.036492 -50.292)
			(xy 169.036492 -50.291238) (xy 169.0369 -50.253018) (xy 169.043465 -50.176859) (xy 169.056549 -50.101547)
			(xy 169.076056 -50.027637) (xy 169.088562 -49.991518) (xy 169.091148 -49.983202) (xy 169.091148 -49.965798)
			(xy 169.088562 -49.957482) (xy 169.076071 -49.921359) (xy 169.056581 -49.847447) (xy 169.043497 -49.772136)
			(xy 169.036915 -49.695981) (xy 169.036492 -49.657762) (xy 169.036492 -49.657) (xy 169.036996 -49.614652)
			(xy 169.045047 -49.530338) (xy 169.061076 -49.447172) (xy 169.084937 -49.365905) (xy 169.116416 -49.287275)
			(xy 169.155227 -49.211994) (xy 169.201017 -49.140742) (xy 169.253373 -49.074166) (xy 169.311821 -49.012868)
			(xy 169.375831 -48.957403) (xy 169.444823 -48.908274) (xy 169.518173 -48.865925) (xy 169.595216 -48.830741)
			(xy 169.675255 -48.803039) (xy 169.757564 -48.783071) (xy 169.841399 -48.771018) (xy 169.926 -48.766988)
			(xy 170.010601 -48.771018) (xy 170.094436 -48.783071) (xy 170.176745 -48.803039) (xy 170.256784 -48.830741)
			(xy 170.333827 -48.865925) (xy 170.407177 -48.908274) (xy 170.476169 -48.957403) (xy 170.540179 -49.012868)
			(xy 170.598627 -49.074166) (xy 170.650983 -49.140742) (xy 170.696773 -49.211994) (xy 170.735584 -49.287275)
			(xy 170.767063 -49.365905) (xy 170.790924 -49.447172) (xy 170.806953 -49.530338) (xy 170.815004 -49.614652)
			(xy 170.815508 -49.657) (xy 170.815508 -49.657762) (xy 170.8151 -49.695982) (xy 170.808535 -49.772141)
			(xy 170.795451 -49.847453) (xy 170.775944 -49.921363) (xy 170.763438 -49.957482) (xy 170.760852 -49.965798)
			(xy 170.760852 -49.983202) (xy 170.763438 -49.991518) (xy 170.775929 -50.027641) (xy 170.795419 -50.101553)
			(xy 170.808503 -50.176864) (xy 170.815085 -50.253019) (xy 170.815508 -50.291238) (xy 170.815508 -50.292)
			(xy 170.815093 -50.332047) (xy 170.807898 -50.411816) (xy 170.793564 -50.490616) (xy 170.77221 -50.56781)
			(xy 170.744006 -50.642773) (xy 170.709182 -50.7149) (xy 170.668018 -50.783605) (xy 170.620849 -50.848335)
			(xy 170.594782 -50.87874) (xy 170.589017 -50.885829) (xy 170.582505 -50.902886) (xy 170.582082 -50.912014)
			(xy 170.582082 -50.941986) (xy 170.582516 -50.951109) (xy 170.589036 -50.968159) (xy 170.594782 -50.97526)
			(xy 170.62084 -51.005674) (xy 170.668026 -51.070392) (xy 170.709202 -51.139092) (xy 170.744033 -51.211216)
			(xy 170.772237 -51.28618) (xy 170.793586 -51.363377) (xy 170.807906 -51.442181) (xy 170.815081 -51.521953)
			(xy 170.815508 -51.562) (xy 170.815508 -51.562762) (xy 170.8151 -51.600982) (xy 170.808535 -51.677141)
			(xy 170.795451 -51.752453) (xy 170.775944 -51.826363) (xy 170.763438 -51.862482) (xy 170.760852 -51.870798)
			(xy 170.760852 -51.888202) (xy 170.763438 -51.896518) (xy 170.775929 -51.932641) (xy 170.795419 -52.006553)
			(xy 170.808503 -52.081864) (xy 170.815085 -52.158019) (xy 170.815508 -52.196238) (xy 170.815508 -52.197)
			(xy 174.497492 -52.197) (xy 174.497492 -52.196238) (xy 174.4979 -52.158018) (xy 174.504465 -52.081859)
			(xy 174.517549 -52.006547) (xy 174.537056 -51.932637) (xy 174.549562 -51.896518) (xy 174.552148 -51.888202)
			(xy 174.552148 -51.870798) (xy 174.549562 -51.862482) (xy 174.537071 -51.826359) (xy 174.517581 -51.752447)
			(xy 174.504497 -51.677136) (xy 174.497915 -51.600981) (xy 174.497492 -51.562762) (xy 174.497492 -51.562)
			(xy 174.497907 -51.521953) (xy 174.505102 -51.442184) (xy 174.519436 -51.363384) (xy 174.54079 -51.28619)
			(xy 174.568994 -51.211227) (xy 174.603818 -51.1391) (xy 174.644982 -51.070395) (xy 174.692151 -51.005665)
			(xy 174.718218 -50.97526) (xy 174.723983 -50.968171) (xy 174.730495 -50.951114) (xy 174.730918 -50.941986)
			(xy 174.730918 -50.912014) (xy 174.730484 -50.902891) (xy 174.723964 -50.885841) (xy 174.718218 -50.87874)
			(xy 174.69216 -50.848326) (xy 174.644974 -50.783608) (xy 174.603798 -50.714908) (xy 174.568967 -50.642784)
			(xy 174.540763 -50.56782) (xy 174.519414 -50.490623) (xy 174.505094 -50.411819) (xy 174.497919 -50.332047)
			(xy 174.497492 -50.292) (xy 174.497492 -50.291238) (xy 174.4979 -50.253018) (xy 174.504465 -50.176859)
			(xy 174.517549 -50.101547) (xy 174.537056 -50.027637) (xy 174.549562 -49.991518) (xy 174.552148 -49.983202)
			(xy 174.552148 -49.965798) (xy 174.549562 -49.957482) (xy 174.537071 -49.921359) (xy 174.517581 -49.847447)
			(xy 174.504497 -49.772136) (xy 174.497915 -49.695981) (xy 174.497492 -49.657762) (xy 174.497492 -49.657)
			(xy 174.497996 -49.614652) (xy 174.506047 -49.530338) (xy 174.522076 -49.447172) (xy 174.545937 -49.365905)
			(xy 174.577416 -49.287275) (xy 174.616227 -49.211994) (xy 174.662017 -49.140742) (xy 174.714373 -49.074166)
			(xy 174.772821 -49.012868) (xy 174.836831 -48.957403) (xy 174.905823 -48.908274) (xy 174.979173 -48.865925)
			(xy 175.056216 -48.830741) (xy 175.136255 -48.803039) (xy 175.218564 -48.783071) (xy 175.302399 -48.771018)
			(xy 175.387 -48.766988) (xy 175.471601 -48.771018) (xy 175.555436 -48.783071) (xy 175.637745 -48.803039)
			(xy 175.717784 -48.830741) (xy 175.794827 -48.865925) (xy 175.868177 -48.908274) (xy 175.937169 -48.957403)
			(xy 176.001179 -49.012868) (xy 176.059627 -49.074166) (xy 176.111983 -49.140742) (xy 176.157773 -49.211994)
			(xy 176.196584 -49.287275) (xy 176.228063 -49.365905) (xy 176.251924 -49.447172) (xy 176.267953 -49.530338)
			(xy 176.276004 -49.614652) (xy 176.276508 -49.657) (xy 176.276508 -49.657762) (xy 176.2761 -49.695982)
			(xy 176.269535 -49.772141) (xy 176.256451 -49.847453) (xy 176.236944 -49.921363) (xy 176.224438 -49.957482)
			(xy 176.221852 -49.965798) (xy 176.221852 -49.983202) (xy 176.224438 -49.991518) (xy 176.236929 -50.027641)
			(xy 176.256419 -50.101553) (xy 176.269503 -50.176864) (xy 176.276085 -50.253019) (xy 176.276508 -50.291238)
			(xy 176.276508 -50.292) (xy 176.276093 -50.332047) (xy 176.268898 -50.411816) (xy 176.254564 -50.490616)
			(xy 176.23321 -50.56781) (xy 176.205006 -50.642773) (xy 176.170182 -50.7149) (xy 176.129018 -50.783605)
			(xy 176.081849 -50.848335) (xy 176.055782 -50.87874) (xy 176.050017 -50.885829) (xy 176.043505 -50.902886)
			(xy 176.043082 -50.912014) (xy 176.043082 -50.941986) (xy 176.043516 -50.951109) (xy 176.050036 -50.968159)
			(xy 176.055782 -50.97526) (xy 176.08184 -51.005674) (xy 176.129026 -51.070392) (xy 176.170202 -51.139092)
			(xy 176.205033 -51.211216) (xy 176.233237 -51.28618) (xy 176.254586 -51.363377) (xy 176.268906 -51.442181)
			(xy 176.276081 -51.521953) (xy 176.276508 -51.562) (xy 176.276508 -51.562762) (xy 176.2761 -51.600982)
			(xy 176.269535 -51.677141) (xy 176.256451 -51.752453) (xy 176.236944 -51.826363) (xy 176.224438 -51.862482)
			(xy 176.221852 -51.870798) (xy 176.221852 -51.888202) (xy 176.224438 -51.896518) (xy 176.236929 -51.932641)
			(xy 176.256419 -52.006553) (xy 176.269503 -52.081864) (xy 176.276085 -52.158019) (xy 176.276508 -52.196238)
			(xy 176.276508 -52.197) (xy 179.955952 -52.197) (xy 179.955952 -52.196238) (xy 179.956357 -52.158018)
			(xy 179.962922 -52.081859) (xy 179.976007 -52.006546) (xy 179.995515 -51.932637) (xy 180.008022 -51.896518)
			(xy 180.01061 -51.888202) (xy 180.01061 -51.870798) (xy 180.008022 -51.862482) (xy 179.995533 -51.826358)
			(xy 179.976042 -51.752446) (xy 179.962957 -51.677136) (xy 179.956375 -51.600981) (xy 179.955952 -51.562762)
			(xy 179.955952 -51.562) (xy 179.956377 -51.521954) (xy 179.963572 -51.442185) (xy 179.977904 -51.363385)
			(xy 179.999258 -51.286192) (xy 180.02746 -51.211228) (xy 180.062283 -51.139102) (xy 180.103445 -51.070396)
			(xy 180.150612 -51.005665) (xy 180.176678 -50.97526) (xy 180.182439 -50.968167) (xy 180.188954 -50.951113)
			(xy 180.189378 -50.941986) (xy 180.189378 -50.912014) (xy 180.188931 -50.902892) (xy 180.182419 -50.885843)
			(xy 180.176678 -50.87874) (xy 180.150614 -50.848332) (xy 180.103428 -50.783612) (xy 180.062254 -50.714911)
			(xy 180.027424 -50.642786) (xy 179.999221 -50.567821) (xy 179.977874 -50.490624) (xy 179.963554 -50.41182)
			(xy 179.956379 -50.332047) (xy 179.955952 -50.292) (xy 179.955952 -50.291238) (xy 179.956357 -50.253018)
			(xy 179.962922 -50.176859) (xy 179.976007 -50.101546) (xy 179.995515 -50.027637) (xy 180.008022 -49.991518)
			(xy 180.01061 -49.983202) (xy 180.01061 -49.965798) (xy 180.008022 -49.957482) (xy 179.995533 -49.921358)
			(xy 179.976042 -49.847446) (xy 179.962957 -49.772136) (xy 179.956375 -49.695981) (xy 179.955952 -49.657762)
			(xy 179.955952 -49.657) (xy 179.956456 -49.614652) (xy 179.964507 -49.530338) (xy 179.980536 -49.447172)
			(xy 180.004397 -49.365905) (xy 180.035876 -49.287275) (xy 180.074687 -49.211994) (xy 180.120477 -49.140742)
			(xy 180.172833 -49.074166) (xy 180.231281 -49.012868) (xy 180.295291 -48.957403) (xy 180.364283 -48.908274)
			(xy 180.437633 -48.865925) (xy 180.514676 -48.830741) (xy 180.594715 -48.803039) (xy 180.677024 -48.783071)
			(xy 180.760859 -48.771018) (xy 180.84546 -48.766988) (xy 180.930061 -48.771018) (xy 181.013896 -48.783071)
			(xy 181.096205 -48.803039) (xy 181.176244 -48.830741) (xy 181.253287 -48.865925) (xy 181.326637 -48.908274)
			(xy 181.395629 -48.957403) (xy 181.459639 -49.012868) (xy 181.518087 -49.074166) (xy 181.570443 -49.140742)
			(xy 181.616233 -49.211994) (xy 181.655044 -49.287275) (xy 181.686523 -49.365905) (xy 181.710384 -49.447172)
			(xy 181.726413 -49.530338) (xy 181.734464 -49.614652) (xy 181.734968 -49.657) (xy 181.734968 -49.657762)
			(xy 181.734562 -49.695982) (xy 181.727997 -49.772141) (xy 181.714912 -49.847454) (xy 181.695405 -49.921363)
			(xy 181.682898 -49.957482) (xy 181.68031 -49.965798) (xy 181.68031 -49.983202) (xy 181.682898 -49.991518)
			(xy 181.695388 -50.027641) (xy 181.714878 -50.101553) (xy 181.727963 -50.176864) (xy 181.734545 -50.253019)
			(xy 181.734968 -50.291238) (xy 181.734968 -50.292) (xy 181.734538 -50.332046) (xy 181.727343 -50.411815)
			(xy 181.713011 -50.490614) (xy 181.691658 -50.567808) (xy 181.663456 -50.642771) (xy 181.628634 -50.714897)
			(xy 181.587474 -50.783604) (xy 181.540307 -50.848334) (xy 181.514242 -50.87874) (xy 181.508472 -50.885825)
			(xy 181.501964 -50.902886) (xy 181.501542 -50.912014) (xy 181.501542 -50.941986) (xy 181.501985 -50.951108)
			(xy 181.5085 -50.968158) (xy 181.514242 -50.97526) (xy 181.54031 -51.005665) (xy 181.587494 -51.070386)
			(xy 181.628668 -51.139087) (xy 181.663497 -51.211213) (xy 181.691699 -51.286178) (xy 181.713047 -51.363376)
			(xy 181.727366 -51.44218) (xy 181.734541 -51.521953) (xy 181.734968 -51.562) (xy 181.734968 -51.562762)
			(xy 181.734562 -51.600982) (xy 181.727997 -51.677141) (xy 181.714912 -51.752454) (xy 181.695405 -51.826363)
			(xy 181.682898 -51.862482) (xy 181.68031 -51.870798) (xy 181.68031 -51.888202) (xy 181.682898 -51.896518)
			(xy 181.695388 -51.932641) (xy 181.714878 -52.006553) (xy 181.727963 -52.081864) (xy 181.734545 -52.158019)
			(xy 181.734968 -52.196238) (xy 181.734968 -52.197) (xy 185.416952 -52.197) (xy 185.416952 -52.196238)
			(xy 185.417357 -52.158018) (xy 185.423922 -52.081859) (xy 185.437007 -52.006546) (xy 185.456515 -51.932637)
			(xy 185.469022 -51.896518) (xy 185.47161 -51.888202) (xy 185.47161 -51.870798) (xy 185.469022 -51.862482)
			(xy 185.456533 -51.826358) (xy 185.437042 -51.752446) (xy 185.423957 -51.677136) (xy 185.417375 -51.600981)
			(xy 185.416952 -51.562762) (xy 185.416952 -51.562) (xy 185.417377 -51.521954) (xy 185.424572 -51.442185)
			(xy 185.438904 -51.363385) (xy 185.460258 -51.286192) (xy 185.48846 -51.211228) (xy 185.523283 -51.139102)
			(xy 185.564445 -51.070396) (xy 185.611612 -51.005665) (xy 185.637678 -50.97526) (xy 185.643439 -50.968167)
			(xy 185.649954 -50.951113) (xy 185.650378 -50.941986) (xy 185.650378 -50.912014) (xy 185.649931 -50.902892)
			(xy 185.643419 -50.885843) (xy 185.637678 -50.87874) (xy 185.611614 -50.848332) (xy 185.564428 -50.783612)
			(xy 185.523254 -50.714911) (xy 185.488424 -50.642786) (xy 185.460221 -50.567821) (xy 185.438874 -50.490624)
			(xy 185.424554 -50.41182) (xy 185.417379 -50.332047) (xy 185.416952 -50.292) (xy 185.416952 -50.291238)
			(xy 185.417357 -50.253018) (xy 185.423922 -50.176859) (xy 185.437007 -50.101546) (xy 185.456515 -50.027637)
			(xy 185.469022 -49.991518) (xy 185.47161 -49.983202) (xy 185.47161 -49.965798) (xy 185.469022 -49.957482)
			(xy 185.456533 -49.921358) (xy 185.437042 -49.847446) (xy 185.423957 -49.772136) (xy 185.417375 -49.695981)
			(xy 185.416952 -49.657762) (xy 185.416952 -49.657) (xy 185.417456 -49.614652) (xy 185.425507 -49.530338)
			(xy 185.441536 -49.447172) (xy 185.465397 -49.365905) (xy 185.496876 -49.287275) (xy 185.535687 -49.211994)
			(xy 185.581477 -49.140742) (xy 185.633833 -49.074166) (xy 185.692281 -49.012868) (xy 185.756291 -48.957403)
			(xy 185.825283 -48.908274) (xy 185.898633 -48.865925) (xy 185.975676 -48.830741) (xy 186.055715 -48.803039)
			(xy 186.138024 -48.783071) (xy 186.221859 -48.771018) (xy 186.30646 -48.766988) (xy 186.391061 -48.771018)
			(xy 186.474896 -48.783071) (xy 186.557205 -48.803039) (xy 186.637244 -48.830741) (xy 186.714287 -48.865925)
			(xy 186.787637 -48.908274) (xy 186.856629 -48.957403) (xy 186.920639 -49.012868) (xy 186.979087 -49.074166)
			(xy 187.031443 -49.140742) (xy 187.077233 -49.211994) (xy 187.116044 -49.287275) (xy 187.147523 -49.365905)
			(xy 187.171384 -49.447172) (xy 187.187413 -49.530338) (xy 187.195464 -49.614652) (xy 187.195968 -49.657)
			(xy 187.195968 -49.657762) (xy 187.195562 -49.695982) (xy 187.188997 -49.772141) (xy 187.175912 -49.847454)
			(xy 187.156405 -49.921363) (xy 187.143898 -49.957482) (xy 187.14131 -49.965798) (xy 187.14131 -49.983202)
			(xy 187.143898 -49.991518) (xy 187.156388 -50.027641) (xy 187.175878 -50.101553) (xy 187.188963 -50.176864)
			(xy 187.195545 -50.253019) (xy 187.195968 -50.291238) (xy 187.195968 -50.292) (xy 187.195538 -50.332046)
			(xy 187.188343 -50.411815) (xy 187.174011 -50.490614) (xy 187.152658 -50.567808) (xy 187.124456 -50.642771)
			(xy 187.089634 -50.714897) (xy 187.048474 -50.783604) (xy 187.001307 -50.848334) (xy 186.975242 -50.87874)
			(xy 186.969472 -50.885825) (xy 186.962964 -50.902886) (xy 186.962542 -50.912014) (xy 186.962542 -50.941986)
			(xy 186.962985 -50.951108) (xy 186.9695 -50.968158) (xy 186.975242 -50.97526) (xy 187.00131 -51.005665)
			(xy 187.048494 -51.070386) (xy 187.089668 -51.139087) (xy 187.124497 -51.211213) (xy 187.152699 -51.286178)
			(xy 187.174047 -51.363376) (xy 187.188366 -51.44218) (xy 187.195541 -51.521953) (xy 187.195968 -51.562)
			(xy 187.195968 -51.562762) (xy 187.195562 -51.600982) (xy 187.188997 -51.677141) (xy 187.175912 -51.752454)
			(xy 187.156405 -51.826363) (xy 187.143898 -51.862482) (xy 187.14131 -51.870798) (xy 187.14131 -51.888202)
			(xy 187.143898 -51.896518) (xy 187.156388 -51.932641) (xy 187.175878 -52.006553) (xy 187.188963 -52.081864)
			(xy 187.195545 -52.158019) (xy 187.195968 -52.196238) (xy 187.195968 -52.197) (xy 187.195464 -52.239348)
			(xy 187.187413 -52.323662) (xy 187.171384 -52.406828) (xy 187.147523 -52.488095) (xy 187.116044 -52.566725)
			(xy 187.077233 -52.642006) (xy 187.031443 -52.713258) (xy 186.979087 -52.779834) (xy 186.920639 -52.841132)
			(xy 186.856629 -52.896597) (xy 186.787637 -52.945726) (xy 186.714287 -52.988075) (xy 186.637244 -53.023259)
			(xy 186.557205 -53.050961) (xy 186.474896 -53.070929) (xy 186.391061 -53.082982) (xy 186.30646 -53.087013)
			(xy 186.221859 -53.082982) (xy 186.138024 -53.070929) (xy 186.055715 -53.050961) (xy 185.975676 -53.023259)
			(xy 185.898633 -52.988075) (xy 185.825283 -52.945726) (xy 185.756291 -52.896597) (xy 185.692281 -52.841132)
			(xy 185.633833 -52.779834) (xy 185.581477 -52.713258) (xy 185.535687 -52.642006) (xy 185.496876 -52.566725)
			(xy 185.465397 -52.488095) (xy 185.441536 -52.406828) (xy 185.425507 -52.323662) (xy 185.417456 -52.239348)
			(xy 185.416952 -52.197) (xy 181.734968 -52.197) (xy 181.734464 -52.239348) (xy 181.726413 -52.323662)
			(xy 181.710384 -52.406828) (xy 181.686523 -52.488095) (xy 181.655044 -52.566725) (xy 181.616233 -52.642006)
			(xy 181.570443 -52.713258) (xy 181.518087 -52.779834) (xy 181.459639 -52.841132) (xy 181.395629 -52.896597)
			(xy 181.326637 -52.945726) (xy 181.253287 -52.988075) (xy 181.176244 -53.023259) (xy 181.096205 -53.050961)
			(xy 181.013896 -53.070929) (xy 180.930061 -53.082982) (xy 180.84546 -53.087013) (xy 180.760859 -53.082982)
			(xy 180.677024 -53.070929) (xy 180.594715 -53.050961) (xy 180.514676 -53.023259) (xy 180.437633 -52.988075)
			(xy 180.364283 -52.945726) (xy 180.295291 -52.896597) (xy 180.231281 -52.841132) (xy 180.172833 -52.779834)
			(xy 180.120477 -52.713258) (xy 180.074687 -52.642006) (xy 180.035876 -52.566725) (xy 180.004397 -52.488095)
			(xy 179.980536 -52.406828) (xy 179.964507 -52.323662) (xy 179.956456 -52.239348) (xy 179.955952 -52.197)
			(xy 176.276508 -52.197) (xy 176.276004 -52.239348) (xy 176.267953 -52.323662) (xy 176.251924 -52.406828)
			(xy 176.228063 -52.488095) (xy 176.196584 -52.566725) (xy 176.157773 -52.642006) (xy 176.111983 -52.713258)
			(xy 176.059627 -52.779834) (xy 176.001179 -52.841132) (xy 175.937169 -52.896597) (xy 175.868177 -52.945726)
			(xy 175.794827 -52.988075) (xy 175.717784 -53.023259) (xy 175.637745 -53.050961) (xy 175.555436 -53.070929)
			(xy 175.471601 -53.082982) (xy 175.387 -53.087013) (xy 175.302399 -53.082982) (xy 175.218564 -53.070929)
			(xy 175.136255 -53.050961) (xy 175.056216 -53.023259) (xy 174.979173 -52.988075) (xy 174.905823 -52.945726)
			(xy 174.836831 -52.896597) (xy 174.772821 -52.841132) (xy 174.714373 -52.779834) (xy 174.662017 -52.713258)
			(xy 174.616227 -52.642006) (xy 174.577416 -52.566725) (xy 174.545937 -52.488095) (xy 174.522076 -52.406828)
			(xy 174.506047 -52.323662) (xy 174.497996 -52.239348) (xy 174.497492 -52.197) (xy 170.815508 -52.197)
			(xy 170.815004 -52.239348) (xy 170.806953 -52.323662) (xy 170.790924 -52.406828) (xy 170.767063 -52.488095)
			(xy 170.735584 -52.566725) (xy 170.696773 -52.642006) (xy 170.650983 -52.713258) (xy 170.598627 -52.779834)
			(xy 170.540179 -52.841132) (xy 170.476169 -52.896597) (xy 170.407177 -52.945726) (xy 170.333827 -52.988075)
			(xy 170.256784 -53.023259) (xy 170.176745 -53.050961) (xy 170.094436 -53.070929) (xy 170.010601 -53.082982)
			(xy 169.926 -53.087013) (xy 169.841399 -53.082982) (xy 169.757564 -53.070929) (xy 169.675255 -53.050961)
			(xy 169.595216 -53.023259) (xy 169.518173 -52.988075) (xy 169.444823 -52.945726) (xy 169.375831 -52.896597)
			(xy 169.311821 -52.841132) (xy 169.253373 -52.779834) (xy 169.201017 -52.713258) (xy 169.155227 -52.642006)
			(xy 169.116416 -52.566725) (xy 169.084937 -52.488095) (xy 169.061076 -52.406828) (xy 169.045047 -52.323662)
			(xy 169.036996 -52.239348) (xy 169.036492 -52.197) (xy 165.354508 -52.197) (xy 165.354004 -52.239348)
			(xy 165.345953 -52.323662) (xy 165.329924 -52.406828) (xy 165.306063 -52.488095) (xy 165.274584 -52.566725)
			(xy 165.235773 -52.642006) (xy 165.189983 -52.713258) (xy 165.137627 -52.779834) (xy 165.079179 -52.841132)
			(xy 165.015169 -52.896597) (xy 164.946177 -52.945726) (xy 164.872827 -52.988075) (xy 164.795784 -53.023259)
			(xy 164.715745 -53.050961) (xy 164.633436 -53.070929) (xy 164.549601 -53.082982) (xy 164.465 -53.087013)
			(xy 164.380399 -53.082982) (xy 164.296564 -53.070929) (xy 164.214255 -53.050961) (xy 164.134216 -53.023259)
			(xy 164.057173 -52.988075) (xy 163.983823 -52.945726) (xy 163.914831 -52.896597) (xy 163.850821 -52.841132)
			(xy 163.792373 -52.779834) (xy 163.740017 -52.713258) (xy 163.694227 -52.642006) (xy 163.655416 -52.566725)
			(xy 163.623937 -52.488095) (xy 163.600076 -52.406828) (xy 163.584047 -52.323662) (xy 163.575996 -52.239348)
			(xy 163.575492 -52.197) (xy 159.893508 -52.197) (xy 159.893004 -52.239348) (xy 159.884953 -52.323662)
			(xy 159.868924 -52.406828) (xy 159.845063 -52.488095) (xy 159.813584 -52.566725) (xy 159.774773 -52.642006)
			(xy 159.728983 -52.713258) (xy 159.676627 -52.779834) (xy 159.618179 -52.841132) (xy 159.554169 -52.896597)
			(xy 159.485177 -52.945726) (xy 159.411827 -52.988075) (xy 159.334784 -53.023259) (xy 159.254745 -53.050961)
			(xy 159.172436 -53.070929) (xy 159.088601 -53.082982) (xy 159.004 -53.087013) (xy 158.919399 -53.082982)
			(xy 158.835564 -53.070929) (xy 158.753255 -53.050961) (xy 158.673216 -53.023259) (xy 158.596173 -52.988075)
			(xy 158.522823 -52.945726) (xy 158.453831 -52.896597) (xy 158.389821 -52.841132) (xy 158.331373 -52.779834)
			(xy 158.279017 -52.713258) (xy 158.233227 -52.642006) (xy 158.194416 -52.566725) (xy 158.162937 -52.488095)
			(xy 158.139076 -52.406828) (xy 158.123047 -52.323662) (xy 158.114996 -52.239348) (xy 158.114492 -52.197)
			(xy 154.432508 -52.197) (xy 154.432004 -52.239348) (xy 154.423953 -52.323662) (xy 154.407924 -52.406828)
			(xy 154.384063 -52.488095) (xy 154.352584 -52.566725) (xy 154.313773 -52.642006) (xy 154.267983 -52.713258)
			(xy 154.215627 -52.779834) (xy 154.157179 -52.841132) (xy 154.093169 -52.896597) (xy 154.024177 -52.945726)
			(xy 153.950827 -52.988075) (xy 153.873784 -53.023259) (xy 153.793745 -53.050961) (xy 153.711436 -53.070929)
			(xy 153.627601 -53.082982) (xy 153.543 -53.087013) (xy 153.458399 -53.082982) (xy 153.374564 -53.070929)
			(xy 153.292255 -53.050961) (xy 153.212216 -53.023259) (xy 153.135173 -52.988075) (xy 153.061823 -52.945726)
			(xy 152.992831 -52.896597) (xy 152.928821 -52.841132) (xy 152.870373 -52.779834) (xy 152.818017 -52.713258)
			(xy 152.772227 -52.642006) (xy 152.733416 -52.566725) (xy 152.701937 -52.488095) (xy 152.678076 -52.406828)
			(xy 152.662047 -52.323662) (xy 152.653996 -52.239348) (xy 152.653492 -52.197) (xy 109.084442 -52.197)
			(xy 109.086503 -52.208864) (xy 109.093085 -52.285019) (xy 109.093508 -52.323238) (xy 109.093508 -52.324)
			(xy 109.093004 -52.366348) (xy 109.084953 -52.450662) (xy 109.068924 -52.533828) (xy 109.045063 -52.615095)
			(xy 109.013584 -52.693725) (xy 108.974773 -52.769006) (xy 108.928983 -52.840258) (xy 108.876627 -52.906834)
			(xy 108.818179 -52.968132) (xy 108.754169 -53.023597) (xy 108.685177 -53.072726) (xy 108.611827 -53.115075)
			(xy 108.534784 -53.150259) (xy 108.454745 -53.177961) (xy 108.372436 -53.197929) (xy 108.288601 -53.209982)
			(xy 108.204 -53.214013) (xy 108.119399 -53.209982) (xy 108.035564 -53.197929) (xy 107.953255 -53.177961)
			(xy 107.873216 -53.150259) (xy 107.796173 -53.115075) (xy 107.722823 -53.072726) (xy 107.653831 -53.023597)
			(xy 107.589821 -52.968132) (xy 107.531373 -52.906834) (xy 107.479017 -52.840258) (xy 107.433227 -52.769006)
			(xy 107.394416 -52.693725) (xy 107.362937 -52.615095) (xy 107.339076 -52.533828) (xy 107.323047 -52.450662)
			(xy 107.314996 -52.366348) (xy 107.314492 -52.324) (xy 103.632508 -52.324) (xy 103.632004 -52.366348)
			(xy 103.623953 -52.450662) (xy 103.607924 -52.533828) (xy 103.584063 -52.615095) (xy 103.552584 -52.693725)
			(xy 103.513773 -52.769006) (xy 103.467983 -52.840258) (xy 103.415627 -52.906834) (xy 103.357179 -52.968132)
			(xy 103.293169 -53.023597) (xy 103.224177 -53.072726) (xy 103.150827 -53.115075) (xy 103.073784 -53.150259)
			(xy 102.993745 -53.177961) (xy 102.911436 -53.197929) (xy 102.827601 -53.209982) (xy 102.743 -53.214013)
			(xy 102.658399 -53.209982) (xy 102.574564 -53.197929) (xy 102.492255 -53.177961) (xy 102.412216 -53.150259)
			(xy 102.335173 -53.115075) (xy 102.261823 -53.072726) (xy 102.192831 -53.023597) (xy 102.128821 -52.968132)
			(xy 102.070373 -52.906834) (xy 102.018017 -52.840258) (xy 101.972227 -52.769006) (xy 101.933416 -52.693725)
			(xy 101.901937 -52.615095) (xy 101.878076 -52.533828) (xy 101.862047 -52.450662) (xy 101.853996 -52.366348)
			(xy 101.853492 -52.324) (xy 98.171508 -52.324) (xy 98.171004 -52.366348) (xy 98.162953 -52.450662)
			(xy 98.146924 -52.533828) (xy 98.123063 -52.615095) (xy 98.091584 -52.693725) (xy 98.052773 -52.769006)
			(xy 98.006983 -52.840258) (xy 97.954627 -52.906834) (xy 97.896179 -52.968132) (xy 97.832169 -53.023597)
			(xy 97.763177 -53.072726) (xy 97.689827 -53.115075) (xy 97.612784 -53.150259) (xy 97.532745 -53.177961)
			(xy 97.450436 -53.197929) (xy 97.366601 -53.209982) (xy 97.282 -53.214013) (xy 97.197399 -53.209982)
			(xy 97.113564 -53.197929) (xy 97.031255 -53.177961) (xy 96.951216 -53.150259) (xy 96.874173 -53.115075)
			(xy 96.800823 -53.072726) (xy 96.731831 -53.023597) (xy 96.667821 -52.968132) (xy 96.609373 -52.906834)
			(xy 96.557017 -52.840258) (xy 96.511227 -52.769006) (xy 96.472416 -52.693725) (xy 96.440937 -52.615095)
			(xy 96.417076 -52.533828) (xy 96.401047 -52.450662) (xy 96.392996 -52.366348) (xy 96.392492 -52.324)
			(xy 92.710508 -52.324) (xy 92.710004 -52.366348) (xy 92.701953 -52.450662) (xy 92.685924 -52.533828)
			(xy 92.662063 -52.615095) (xy 92.630584 -52.693725) (xy 92.591773 -52.769006) (xy 92.545983 -52.840258)
			(xy 92.493627 -52.906834) (xy 92.435179 -52.968132) (xy 92.371169 -53.023597) (xy 92.302177 -53.072726)
			(xy 92.228827 -53.115075) (xy 92.151784 -53.150259) (xy 92.071745 -53.177961) (xy 91.989436 -53.197929)
			(xy 91.905601 -53.209982) (xy 91.821 -53.214013) (xy 91.736399 -53.209982) (xy 91.652564 -53.197929)
			(xy 91.570255 -53.177961) (xy 91.490216 -53.150259) (xy 91.413173 -53.115075) (xy 91.339823 -53.072726)
			(xy 91.270831 -53.023597) (xy 91.206821 -52.968132) (xy 91.148373 -52.906834) (xy 91.096017 -52.840258)
			(xy 91.050227 -52.769006) (xy 91.011416 -52.693725) (xy 90.979937 -52.615095) (xy 90.956076 -52.533828)
			(xy 90.940047 -52.450662) (xy 90.931996 -52.366348) (xy 90.931492 -52.324) (xy 87.249508 -52.324)
			(xy 87.249004 -52.366348) (xy 87.240953 -52.450662) (xy 87.224924 -52.533828) (xy 87.201063 -52.615095)
			(xy 87.169584 -52.693725) (xy 87.130773 -52.769006) (xy 87.084983 -52.840258) (xy 87.032627 -52.906834)
			(xy 86.974179 -52.968132) (xy 86.910169 -53.023597) (xy 86.841177 -53.072726) (xy 86.767827 -53.115075)
			(xy 86.690784 -53.150259) (xy 86.610745 -53.177961) (xy 86.528436 -53.197929) (xy 86.444601 -53.209982)
			(xy 86.36 -53.214013) (xy 86.275399 -53.209982) (xy 86.191564 -53.197929) (xy 86.109255 -53.177961)
			(xy 86.029216 -53.150259) (xy 85.952173 -53.115075) (xy 85.878823 -53.072726) (xy 85.809831 -53.023597)
			(xy 85.745821 -52.968132) (xy 85.687373 -52.906834) (xy 85.635017 -52.840258) (xy 85.589227 -52.769006)
			(xy 85.550416 -52.693725) (xy 85.518937 -52.615095) (xy 85.495076 -52.533828) (xy 85.479047 -52.450662)
			(xy 85.470996 -52.366348) (xy 85.470492 -52.324) (xy 81.788508 -52.324) (xy 81.788004 -52.366348)
			(xy 81.779953 -52.450662) (xy 81.763924 -52.533828) (xy 81.740063 -52.615095) (xy 81.708584 -52.693725)
			(xy 81.669773 -52.769006) (xy 81.623983 -52.840258) (xy 81.571627 -52.906834) (xy 81.513179 -52.968132)
			(xy 81.449169 -53.023597) (xy 81.380177 -53.072726) (xy 81.306827 -53.115075) (xy 81.229784 -53.150259)
			(xy 81.149745 -53.177961) (xy 81.067436 -53.197929) (xy 80.983601 -53.209982) (xy 80.899 -53.214013)
			(xy 80.814399 -53.209982) (xy 80.730564 -53.197929) (xy 80.648255 -53.177961) (xy 80.568216 -53.150259)
			(xy 80.491173 -53.115075) (xy 80.417823 -53.072726) (xy 80.348831 -53.023597) (xy 80.284821 -52.968132)
			(xy 80.226373 -52.906834) (xy 80.174017 -52.840258) (xy 80.128227 -52.769006) (xy 80.089416 -52.693725)
			(xy 80.057937 -52.615095) (xy 80.034076 -52.533828) (xy 80.018047 -52.450662) (xy 80.009996 -52.366348)
			(xy 80.009492 -52.324) (xy 76.327508 -52.324) (xy 76.327004 -52.366348) (xy 76.318953 -52.450662)
			(xy 76.302924 -52.533828) (xy 76.279063 -52.615095) (xy 76.247584 -52.693725) (xy 76.208773 -52.769006)
			(xy 76.162983 -52.840258) (xy 76.110627 -52.906834) (xy 76.052179 -52.968132) (xy 75.988169 -53.023597)
			(xy 75.919177 -53.072726) (xy 75.845827 -53.115075) (xy 75.768784 -53.150259) (xy 75.688745 -53.177961)
			(xy 75.606436 -53.197929) (xy 75.522601 -53.209982) (xy 75.438 -53.214013) (xy 75.353399 -53.209982)
			(xy 75.269564 -53.197929) (xy 75.187255 -53.177961) (xy 75.107216 -53.150259) (xy 75.030173 -53.115075)
			(xy 74.956823 -53.072726) (xy 74.887831 -53.023597) (xy 74.823821 -52.968132) (xy 74.765373 -52.906834)
			(xy 74.713017 -52.840258) (xy 74.667227 -52.769006) (xy 74.628416 -52.693725) (xy 74.596937 -52.615095)
			(xy 74.573076 -52.533828) (xy 74.557047 -52.450662) (xy 74.548996 -52.366348) (xy 74.548492 -52.324)
			(xy 35.433 -52.324) (xy 35.433 -55.642002) (xy 37.371528 -55.642002) (xy 37.372025 -55.599894) (xy 37.379983 -55.516053)
			(xy 37.395827 -55.43334) (xy 37.419416 -55.352494) (xy 37.450538 -55.274239) (xy 37.488916 -55.199275)
			(xy 37.534205 -55.128272) (xy 37.586001 -55.061867) (xy 37.64384 -55.000653) (xy 37.707204 -54.945178)
			(xy 37.775527 -54.895939) (xy 37.848196 -54.853376) (xy 37.924563 -54.81787) (xy 38.003942 -54.789738)
			(xy 38.085625 -54.769234) (xy 38.127178 -54.7624) (xy 38.13937 -54.760622) (xy 38.159436 -54.746144)
			(xy 38.207442 -54.64937) (xy 38.207188 -54.624732) (xy 38.201092 -54.61381) (xy 38.180677 -54.57486)
			(xy 38.146762 -54.493717) (xy 38.121019 -54.409623) (xy 38.103699 -54.3234) (xy 38.094971 -54.235888)
			(xy 38.094412 -54.191916) (xy 38.094412 -54.1909) (xy 38.094916 -54.148552) (xy 38.102967 -54.064238)
			(xy 38.118996 -53.981072) (xy 38.142857 -53.899805) (xy 38.174336 -53.821175) (xy 38.213147 -53.745894)
			(xy 38.258937 -53.674642) (xy 38.311293 -53.608066) (xy 38.369741 -53.546768) (xy 38.433751 -53.491303)
			(xy 38.502743 -53.442174) (xy 38.576093 -53.399825) (xy 38.653136 -53.364641) (xy 38.733175 -53.336939)
			(xy 38.815484 -53.316971) (xy 38.899319 -53.304918) (xy 38.98392 -53.300888) (xy 39.068521 -53.304918)
			(xy 39.152356 -53.316971) (xy 39.234665 -53.336939) (xy 39.314704 -53.364641) (xy 39.391747 -53.399825)
			(xy 39.465097 -53.442174) (xy 39.534089 -53.491303) (xy 39.598099 -53.546768) (xy 39.656547 -53.608066)
			(xy 39.708903 -53.674642) (xy 39.754693 -53.745894) (xy 39.793504 -53.821175) (xy 39.824983 -53.899805)
			(xy 39.848844 -53.981072) (xy 39.86323 -54.055715) (xy 45.935388 -54.055715) (xy 45.935388 -53.970993)
			(xy 45.943441 -53.886656) (xy 45.959475 -53.803466) (xy 45.983343 -53.722176) (xy 46.014831 -53.643524)
			(xy 46.053653 -53.568221) (xy 46.099456 -53.496949) (xy 46.151827 -53.430353) (xy 46.210292 -53.369038)
			(xy 46.27432 -53.313557) (xy 46.343332 -53.264414) (xy 46.416702 -53.222054) (xy 46.493767 -53.186859)
			(xy 46.573829 -53.15915) (xy 46.656162 -53.139176) (xy 46.740021 -53.127119) (xy 46.824646 -53.123088)
			(xy 46.909271 -53.127119) (xy 46.99313 -53.139176) (xy 47.075463 -53.15915) (xy 47.155525 -53.186859)
			(xy 47.23259 -53.222054) (xy 47.30596 -53.264414) (xy 47.374972 -53.313557) (xy 47.439 -53.369038)
			(xy 47.497465 -53.430353) (xy 47.549836 -53.496949) (xy 47.595639 -53.568221) (xy 47.634461 -53.643524)
			(xy 47.665949 -53.722176) (xy 47.689817 -53.803466) (xy 47.705851 -53.886656) (xy 47.713904 -53.970993)
			(xy 47.714408 -54.013354) (xy 47.713904 -54.055715) (xy 47.705851 -54.140052) (xy 47.689817 -54.223242)
			(xy 47.665949 -54.304532) (xy 47.634461 -54.383184) (xy 47.595639 -54.458487) (xy 47.549836 -54.529759)
			(xy 47.497465 -54.596355) (xy 47.439 -54.65767) (xy 47.374972 -54.713151) (xy 47.30596 -54.762294)
			(xy 47.23259 -54.804654) (xy 47.155525 -54.839849) (xy 47.075463 -54.867558) (xy 46.99313 -54.887532)
			(xy 46.909271 -54.899589) (xy 46.824646 -54.903621) (xy 46.740021 -54.899589) (xy 46.656162 -54.887532)
			(xy 46.573829 -54.867558) (xy 46.493767 -54.839849) (xy 46.416702 -54.804654) (xy 46.343332 -54.762294)
			(xy 46.27432 -54.713151) (xy 46.210292 -54.65767) (xy 46.151827 -54.596355) (xy 46.099456 -54.529759)
			(xy 46.053653 -54.458487) (xy 46.014831 -54.383184) (xy 45.983343 -54.304532) (xy 45.959475 -54.223242)
			(xy 45.943441 -54.140052) (xy 45.935388 -54.055715) (xy 39.86323 -54.055715) (xy 39.864873 -54.064238)
			(xy 39.872924 -54.148552) (xy 39.873428 -54.1909) (xy 39.87297 -54.23301) (xy 39.865012 -54.316852)
			(xy 39.849167 -54.399567) (xy 39.825576 -54.480415) (xy 39.794452 -54.558672) (xy 39.756072 -54.633638)
			(xy 39.710779 -54.704641) (xy 39.65898 -54.771047) (xy 39.601138 -54.832261) (xy 39.537771 -54.887736)
			(xy 39.469444 -54.936974) (xy 39.396771 -54.979536) (xy 39.320401 -55.01504) (xy 39.241018 -55.043169)
			(xy 39.159333 -55.06367) (xy 39.117778 -55.070502) (xy 39.105586 -55.07228) (xy 39.08552 -55.086758)
			(xy 39.037514 -55.183532) (xy 39.037768 -55.20817) (xy 39.043864 -55.219092) (xy 39.06432 -55.258135)
			(xy 39.098296 -55.339473) (xy 39.124061 -55.423772) (xy 39.141362 -55.510206) (xy 39.150031 -55.597927)
			(xy 39.150544 -55.642002) (xy 39.149888 -55.692156) (xy 39.13869 -55.791837) (xy 39.128192 -55.840884)
			(xy 39.126403 -55.851401) (xy 39.130519 -55.872305) (xy 39.142729 -55.889765) (xy 39.15156 -55.895748)
			(xy 39.188993 -55.918893) (xy 39.259542 -55.971521) (xy 39.324556 -56.030851) (xy 39.383399 -56.096306)
			(xy 39.409878 -56.13146) (xy 39.416788 -56.140033) (xy 39.436031 -56.150694) (xy 39.446962 -56.152034)
			(xy 39.488331 -56.155768) (xy 39.570195 -56.169853) (xy 39.65039 -56.191507) (xy 39.728218 -56.220543)
			(xy 39.802999 -56.256707) (xy 39.874084 -56.299685) (xy 39.940853 -56.349102) (xy 40.002725 -56.404528)
			(xy 40.049273 -56.454802) (xy 42.97934 -56.454802) (xy 42.97934 -56.454294) (xy 42.979916 -56.408849)
			(xy 42.989185 -56.318433) (xy 43.007626 -56.229433) (xy 43.035046 -56.142777) (xy 43.07116 -56.05937)
			(xy 43.092878 -56.019446) (xy 43.097838 -56.009355) (xy 43.09942 -55.986953) (xy 43.095926 -55.976266)
			(xy 43.081477 -55.937748) (xy 43.058925 -55.858627) (xy 43.043785 -55.777759) (xy 43.036187 -55.695838)
			(xy 43.035728 -55.654702) (xy 43.035728 -55.65394) (xy 43.03619 -55.612836) (xy 43.043772 -55.53098)
			(xy 43.058875 -55.450172) (xy 43.08137 -55.371102) (xy 43.111064 -55.294446) (xy 43.147706 -55.220856)
			(xy 43.190981 -55.150962) (xy 43.240521 -55.085358) (xy 43.295904 -55.024606) (xy 43.356655 -54.969224)
			(xy 43.422258 -54.919683) (xy 43.492153 -54.876408) (xy 43.565742 -54.839766) (xy 43.642398 -54.810071)
			(xy 43.721468 -54.787576) (xy 43.802276 -54.772473) (xy 43.884132 -54.764891) (xy 43.925236 -54.764432)
			(xy 43.925744 -54.764432) (xy 43.972721 -54.765036) (xy 44.066153 -54.774917) (xy 44.158025 -54.794587)
			(xy 44.202858 -54.808628) (xy 44.213338 -54.811501) (xy 44.234917 -54.80915) (xy 44.244514 -54.804056)
			(xy 44.278856 -54.784226) (xy 44.350406 -54.750021) (xy 44.42472 -54.722329) (xy 44.501207 -54.701372)
			(xy 44.579258 -54.687316) (xy 44.658251 -54.680274) (xy 44.697904 -54.67985) (xy 44.738985 -54.680256)
			(xy 44.820797 -54.687838) (xy 44.90156 -54.702936) (xy 44.980586 -54.725422) (xy 45.0572 -54.755104)
			(xy 45.130748 -54.791728) (xy 45.200603 -54.834983) (xy 45.266168 -54.884498) (xy 45.326886 -54.939853)
			(xy 45.382236 -55.000573) (xy 45.431748 -55.066142) (xy 45.474998 -55.135999) (xy 45.511618 -55.20955)
			(xy 45.541295 -55.286165) (xy 45.563776 -55.365192) (xy 45.578869 -55.445956) (xy 45.586446 -55.527769)
			(xy 45.586904 -55.56885) (xy 45.58637 -55.611928) (xy 45.57804 -55.69768) (xy 45.561453 -55.782224)
			(xy 45.536764 -55.864767) (xy 45.504206 -55.944534) (xy 45.464083 -56.020778) (xy 45.416773 -56.092782)
			(xy 45.369284 -56.151723) (xy 45.799752 -56.151723) (xy 45.799752 -56.067001) (xy 45.807805 -55.982664)
			(xy 45.823839 -55.899474) (xy 45.847707 -55.818184) (xy 45.879195 -55.739532) (xy 45.918017 -55.664229)
			(xy 45.96382 -55.592957) (xy 46.016191 -55.526361) (xy 46.074656 -55.465046) (xy 46.138684 -55.409565)
			(xy 46.207696 -55.360422) (xy 46.281066 -55.318062) (xy 46.358131 -55.282867) (xy 46.438193 -55.255158)
			(xy 46.520526 -55.235184) (xy 46.604385 -55.223127) (xy 46.68901 -55.219096) (xy 46.773635 -55.223127)
			(xy 46.857494 -55.235184) (xy 46.939827 -55.255158) (xy 47.019889 -55.282867) (xy 47.096954 -55.318062)
			(xy 47.170324 -55.360422) (xy 47.239336 -55.409565) (xy 47.303364 -55.465046) (xy 47.361829 -55.526361)
			(xy 47.4142 -55.592957) (xy 47.460003 -55.664229) (xy 47.498825 -55.739532) (xy 47.530313 -55.818184)
			(xy 47.554181 -55.899474) (xy 47.565849 -55.96001) (xy 66.673737 -55.96001) (xy 66.677742 -55.854261)
			(xy 66.689732 -55.749118) (xy 66.709641 -55.645183) (xy 66.737352 -55.543051) (xy 66.772709 -55.443307)
			(xy 66.815507 -55.346523) (xy 66.865503 -55.253253) (xy 66.92241 -55.164032) (xy 66.985901 -55.079369)
			(xy 67.055613 -54.999751) (xy 67.131147 -54.925633) (xy 67.21207 -54.85744) (xy 67.297919 -54.795562)
			(xy 67.388202 -54.740355) (xy 67.482401 -54.692133) (xy 67.579978 -54.651173) (xy 67.680373 -54.617711)
			(xy 67.783011 -54.591937) (xy 67.887304 -54.573999) (xy 67.992655 -54.564) (xy 68.098461 -54.561997)
			(xy 68.204115 -54.568002) (xy 68.309012 -54.581981) (xy 68.412552 -54.603852) (xy 68.514141 -54.633492)
			(xy 68.613198 -54.67073) (xy 68.709155 -54.715352) (xy 68.801462 -54.767104) (xy 68.889591 -54.825689)
			(xy 68.973037 -54.890771) (xy 69.051321 -54.961977) (xy 69.123996 -55.0389) (xy 69.190646 -55.1211)
			(xy 69.250888 -55.208104) (xy 69.304377 -55.299415) (xy 69.350808 -55.39451) (xy 69.389913 -55.492844)
			(xy 69.42147 -55.593855) (xy 69.445297 -55.696962) (xy 69.461258 -55.801576) (xy 69.469262 -55.907098)
			(xy 69.469762 -55.96001) (xy 77.976737 -55.96001) (xy 77.980742 -55.854261) (xy 77.992732 -55.749118)
			(xy 78.012641 -55.645183) (xy 78.040352 -55.543051) (xy 78.075709 -55.443307) (xy 78.118507 -55.346523)
			(xy 78.168503 -55.253253) (xy 78.22541 -55.164032) (xy 78.288901 -55.079369) (xy 78.358613 -54.999751)
			(xy 78.434147 -54.925633) (xy 78.51507 -54.85744) (xy 78.600919 -54.795562) (xy 78.691202 -54.740355)
			(xy 78.785401 -54.692133) (xy 78.882978 -54.651173) (xy 78.983373 -54.617711) (xy 79.086011 -54.591937)
			(xy 79.190304 -54.573999) (xy 79.295655 -54.564) (xy 79.401461 -54.561997) (xy 79.507115 -54.568002)
			(xy 79.612012 -54.581981) (xy 79.715552 -54.603852) (xy 79.817141 -54.633492) (xy 79.916198 -54.67073)
			(xy 80.012155 -54.715352) (xy 80.104462 -54.767104) (xy 80.192591 -54.825689) (xy 80.276037 -54.890771)
			(xy 80.354321 -54.961977) (xy 80.426996 -55.0389) (xy 80.493646 -55.1211) (xy 80.553888 -55.208104)
			(xy 80.607377 -55.299415) (xy 80.653808 -55.39451) (xy 80.692913 -55.492844) (xy 80.72447 -55.593855)
			(xy 80.748297 -55.696962) (xy 80.764258 -55.801576) (xy 80.772262 -55.907098) (xy 80.772762 -55.96001)
			(xy 89.279737 -55.96001) (xy 89.283742 -55.854261) (xy 89.295732 -55.749118) (xy 89.315641 -55.645183)
			(xy 89.343352 -55.543051) (xy 89.378709 -55.443307) (xy 89.421507 -55.346523) (xy 89.471503 -55.253253)
			(xy 89.52841 -55.164032) (xy 89.591901 -55.079369) (xy 89.661613 -54.999751) (xy 89.737147 -54.925633)
			(xy 89.81807 -54.85744) (xy 89.903919 -54.795562) (xy 89.994202 -54.740355) (xy 90.088401 -54.692133)
			(xy 90.185978 -54.651173) (xy 90.286373 -54.617711) (xy 90.389011 -54.591937) (xy 90.493304 -54.573999)
			(xy 90.598655 -54.564) (xy 90.704461 -54.561997) (xy 90.810115 -54.568002) (xy 90.915012 -54.581981)
			(xy 91.018552 -54.603852) (xy 91.120141 -54.633492) (xy 91.219198 -54.67073) (xy 91.315155 -54.715352)
			(xy 91.407462 -54.767104) (xy 91.495591 -54.825689) (xy 91.579037 -54.890771) (xy 91.657321 -54.961977)
			(xy 91.729996 -55.0389) (xy 91.796646 -55.1211) (xy 91.856888 -55.208104) (xy 91.910377 -55.299415)
			(xy 91.956808 -55.39451) (xy 91.995913 -55.492844) (xy 92.02747 -55.593855) (xy 92.051297 -55.696962)
			(xy 92.067258 -55.801576) (xy 92.075262 -55.907098) (xy 92.075762 -55.96001) (xy 107.440737 -55.96001)
			(xy 107.444742 -55.854261) (xy 107.456732 -55.749118) (xy 107.476641 -55.645183) (xy 107.504352 -55.543051)
			(xy 107.539709 -55.443307) (xy 107.582507 -55.346523) (xy 107.632503 -55.253253) (xy 107.68941 -55.164032)
			(xy 107.752901 -55.079369) (xy 107.822613 -54.999751) (xy 107.898147 -54.925633) (xy 107.97907 -54.85744)
			(xy 108.064919 -54.795562) (xy 108.155202 -54.740355) (xy 108.249401 -54.692133) (xy 108.346978 -54.651173)
			(xy 108.447373 -54.617711) (xy 108.550011 -54.591937) (xy 108.654304 -54.573999) (xy 108.759655 -54.564)
			(xy 108.865461 -54.561997) (xy 108.971115 -54.568002) (xy 109.076012 -54.581981) (xy 109.179552 -54.603852)
			(xy 109.281141 -54.633492) (xy 109.380198 -54.67073) (xy 109.476155 -54.715352) (xy 109.568462 -54.767104)
			(xy 109.656591 -54.825689) (xy 109.740037 -54.890771) (xy 109.818321 -54.961977) (xy 109.890996 -55.0389)
			(xy 109.957646 -55.1211) (xy 110.017888 -55.208104) (xy 110.071377 -55.299415) (xy 110.117808 -55.39451)
			(xy 110.156913 -55.492844) (xy 110.18847 -55.593855) (xy 110.212297 -55.696962) (xy 110.228258 -55.801576)
			(xy 110.236262 -55.907098) (xy 110.236762 -55.96001) (xy 118.616737 -55.96001) (xy 118.620742 -55.854261)
			(xy 118.632732 -55.749118) (xy 118.652641 -55.645183) (xy 118.680352 -55.543051) (xy 118.715709 -55.443307)
			(xy 118.758507 -55.346523) (xy 118.808503 -55.253253) (xy 118.86541 -55.164032) (xy 118.928901 -55.079369)
			(xy 118.998613 -54.999751) (xy 119.074147 -54.925633) (xy 119.15507 -54.85744) (xy 119.240919 -54.795562)
			(xy 119.331202 -54.740355) (xy 119.425401 -54.692133) (xy 119.522978 -54.651173) (xy 119.623373 -54.617711)
			(xy 119.726011 -54.591937) (xy 119.830304 -54.573999) (xy 119.935655 -54.564) (xy 120.041461 -54.561997)
			(xy 120.147115 -54.568002) (xy 120.252012 -54.581981) (xy 120.355552 -54.603852) (xy 120.457141 -54.633492)
			(xy 120.556198 -54.67073) (xy 120.652155 -54.715352) (xy 120.744462 -54.767104) (xy 120.832591 -54.825689)
			(xy 120.916037 -54.890771) (xy 120.994321 -54.961977) (xy 121.066996 -55.0389) (xy 121.133646 -55.1211)
			(xy 121.193888 -55.208104) (xy 121.247377 -55.299415) (xy 121.293808 -55.39451) (xy 121.332913 -55.492844)
			(xy 121.36447 -55.593855) (xy 121.388297 -55.696962) (xy 121.404258 -55.801576) (xy 121.412262 -55.907098)
			(xy 121.412762 -55.96001) (xy 129.792737 -55.96001) (xy 129.796742 -55.854261) (xy 129.808732 -55.749118)
			(xy 129.828641 -55.645183) (xy 129.856352 -55.543051) (xy 129.891709 -55.443307) (xy 129.934507 -55.346523)
			(xy 129.984503 -55.253253) (xy 130.04141 -55.164032) (xy 130.104901 -55.079369) (xy 130.174613 -54.999751)
			(xy 130.250147 -54.925633) (xy 130.33107 -54.85744) (xy 130.416919 -54.795562) (xy 130.507202 -54.740355)
			(xy 130.601401 -54.692133) (xy 130.698978 -54.651173) (xy 130.799373 -54.617711) (xy 130.902011 -54.591937)
			(xy 131.006304 -54.573999) (xy 131.111655 -54.564) (xy 131.217461 -54.561997) (xy 131.323115 -54.568002)
			(xy 131.428012 -54.581981) (xy 131.531552 -54.603852) (xy 131.633141 -54.633492) (xy 131.732198 -54.67073)
			(xy 131.828155 -54.715352) (xy 131.920462 -54.767104) (xy 132.008591 -54.825689) (xy 132.092037 -54.890771)
			(xy 132.170321 -54.961977) (xy 132.242996 -55.0389) (xy 132.309646 -55.1211) (xy 132.369888 -55.208104)
			(xy 132.423377 -55.299415) (xy 132.469808 -55.39451) (xy 132.508913 -55.492844) (xy 132.54047 -55.593855)
			(xy 132.564297 -55.696962) (xy 132.580258 -55.801576) (xy 132.588262 -55.907098) (xy 132.588762 -55.96001)
			(xy 145.540737 -55.96001) (xy 145.544742 -55.854261) (xy 145.556732 -55.749118) (xy 145.576641 -55.645183)
			(xy 145.604352 -55.543051) (xy 145.639709 -55.443307) (xy 145.682507 -55.346523) (xy 145.732503 -55.253253)
			(xy 145.78941 -55.164032) (xy 145.852901 -55.079369) (xy 145.922613 -54.999751) (xy 145.998147 -54.925633)
			(xy 146.07907 -54.85744) (xy 146.164919 -54.795562) (xy 146.255202 -54.740355) (xy 146.349401 -54.692133)
			(xy 146.446978 -54.651173) (xy 146.547373 -54.617711) (xy 146.650011 -54.591937) (xy 146.754304 -54.573999)
			(xy 146.859655 -54.564) (xy 146.965461 -54.561997) (xy 147.071115 -54.568002) (xy 147.176012 -54.581981)
			(xy 147.279552 -54.603852) (xy 147.381141 -54.633492) (xy 147.480198 -54.67073) (xy 147.576155 -54.715352)
			(xy 147.668462 -54.767104) (xy 147.756591 -54.825689) (xy 147.840037 -54.890771) (xy 147.918321 -54.961977)
			(xy 147.990996 -55.0389) (xy 148.057646 -55.1211) (xy 148.117888 -55.208104) (xy 148.171377 -55.299415)
			(xy 148.217808 -55.39451) (xy 148.256913 -55.492844) (xy 148.28847 -55.593855) (xy 148.312297 -55.696962)
			(xy 148.328258 -55.801576) (xy 148.336262 -55.907098) (xy 148.336762 -55.96001) (xy 156.716737 -55.96001)
			(xy 156.720742 -55.854261) (xy 156.732732 -55.749118) (xy 156.752641 -55.645183) (xy 156.780352 -55.543051)
			(xy 156.815709 -55.443307) (xy 156.858507 -55.346523) (xy 156.908503 -55.253253) (xy 156.96541 -55.164032)
			(xy 157.028901 -55.079369) (xy 157.098613 -54.999751) (xy 157.174147 -54.925633) (xy 157.25507 -54.85744)
			(xy 157.340919 -54.795562) (xy 157.431202 -54.740355) (xy 157.525401 -54.692133) (xy 157.622978 -54.651173)
			(xy 157.723373 -54.617711) (xy 157.826011 -54.591937) (xy 157.930304 -54.573999) (xy 158.035655 -54.564)
			(xy 158.141461 -54.561997) (xy 158.247115 -54.568002) (xy 158.352012 -54.581981) (xy 158.455552 -54.603852)
			(xy 158.557141 -54.633492) (xy 158.656198 -54.67073) (xy 158.752155 -54.715352) (xy 158.844462 -54.767104)
			(xy 158.932591 -54.825689) (xy 159.016037 -54.890771) (xy 159.094321 -54.961977) (xy 159.166996 -55.0389)
			(xy 159.233646 -55.1211) (xy 159.293888 -55.208104) (xy 159.347377 -55.299415) (xy 159.393808 -55.39451)
			(xy 159.432913 -55.492844) (xy 159.46447 -55.593855) (xy 159.488297 -55.696962) (xy 159.504258 -55.801576)
			(xy 159.512262 -55.907098) (xy 159.512762 -55.96001) (xy 167.892737 -55.96001) (xy 167.896742 -55.854261)
			(xy 167.908732 -55.749118) (xy 167.928641 -55.645183) (xy 167.956352 -55.543051) (xy 167.991709 -55.443307)
			(xy 168.034507 -55.346523) (xy 168.084503 -55.253253) (xy 168.14141 -55.164032) (xy 168.204901 -55.079369)
			(xy 168.274613 -54.999751) (xy 168.350147 -54.925633) (xy 168.43107 -54.85744) (xy 168.516919 -54.795562)
			(xy 168.607202 -54.740355) (xy 168.701401 -54.692133) (xy 168.798978 -54.651173) (xy 168.899373 -54.617711)
			(xy 169.002011 -54.591937) (xy 169.106304 -54.573999) (xy 169.211655 -54.564) (xy 169.317461 -54.561997)
			(xy 169.423115 -54.568002) (xy 169.528012 -54.581981) (xy 169.631552 -54.603852) (xy 169.733141 -54.633492)
			(xy 169.832198 -54.67073) (xy 169.928155 -54.715352) (xy 170.020462 -54.767104) (xy 170.108591 -54.825689)
			(xy 170.192037 -54.890771) (xy 170.270321 -54.961977) (xy 170.342996 -55.0389) (xy 170.409646 -55.1211)
			(xy 170.469888 -55.208104) (xy 170.523377 -55.299415) (xy 170.569808 -55.39451) (xy 170.608913 -55.492844)
			(xy 170.64047 -55.593855) (xy 170.664297 -55.696962) (xy 170.680258 -55.801576) (xy 170.688262 -55.907098)
			(xy 170.688762 -55.96001) (xy 185.540911 -55.96001) (xy 185.544916 -55.854261) (xy 185.556906 -55.749118)
			(xy 185.576815 -55.645183) (xy 185.604526 -55.543051) (xy 185.639883 -55.443307) (xy 185.682681 -55.346523)
			(xy 185.732677 -55.253253) (xy 185.789584 -55.164032) (xy 185.853075 -55.079369) (xy 185.922787 -54.999751)
			(xy 185.998321 -54.925633) (xy 186.079244 -54.85744) (xy 186.165093 -54.795562) (xy 186.255376 -54.740355)
			(xy 186.349575 -54.692133) (xy 186.447152 -54.651173) (xy 186.547547 -54.617711) (xy 186.650185 -54.591937)
			(xy 186.754478 -54.573999) (xy 186.859829 -54.564) (xy 186.965635 -54.561997) (xy 187.071289 -54.568002)
			(xy 187.176186 -54.581981) (xy 187.279726 -54.603852) (xy 187.381315 -54.633492) (xy 187.480372 -54.67073)
			(xy 187.576329 -54.715352) (xy 187.668636 -54.767104) (xy 187.756765 -54.825689) (xy 187.840211 -54.890771)
			(xy 187.918495 -54.961977) (xy 187.99117 -55.0389) (xy 188.05782 -55.1211) (xy 188.118062 -55.208104)
			(xy 188.171551 -55.299415) (xy 188.217982 -55.39451) (xy 188.257087 -55.492844) (xy 188.288644 -55.593855)
			(xy 188.312471 -55.696962) (xy 188.328432 -55.801576) (xy 188.336436 -55.907098) (xy 188.336936 -55.96001)
			(xy 196.716911 -55.96001) (xy 196.720916 -55.854261) (xy 196.732906 -55.749118) (xy 196.752815 -55.645183)
			(xy 196.780526 -55.543051) (xy 196.815883 -55.443307) (xy 196.858681 -55.346523) (xy 196.908677 -55.253253)
			(xy 196.965584 -55.164032) (xy 197.029075 -55.079369) (xy 197.098787 -54.999751) (xy 197.174321 -54.925633)
			(xy 197.255244 -54.85744) (xy 197.341093 -54.795562) (xy 197.431376 -54.740355) (xy 197.525575 -54.692133)
			(xy 197.623152 -54.651173) (xy 197.723547 -54.617711) (xy 197.826185 -54.591937) (xy 197.930478 -54.573999)
			(xy 198.035829 -54.564) (xy 198.141635 -54.561997) (xy 198.247289 -54.568002) (xy 198.352186 -54.581981)
			(xy 198.455726 -54.603852) (xy 198.557315 -54.633492) (xy 198.656372 -54.67073) (xy 198.752329 -54.715352)
			(xy 198.844636 -54.767104) (xy 198.932765 -54.825689) (xy 199.016211 -54.890771) (xy 199.094495 -54.961977)
			(xy 199.16717 -55.0389) (xy 199.23382 -55.1211) (xy 199.294062 -55.208104) (xy 199.347551 -55.299415)
			(xy 199.393982 -55.39451) (xy 199.433087 -55.492844) (xy 199.464644 -55.593855) (xy 199.488471 -55.696962)
			(xy 199.504432 -55.801576) (xy 199.512436 -55.907098) (xy 199.512936 -55.96001) (xy 207.892911 -55.96001)
			(xy 207.896916 -55.854261) (xy 207.908906 -55.749118) (xy 207.928815 -55.645183) (xy 207.956526 -55.543051)
			(xy 207.991883 -55.443307) (xy 208.034681 -55.346523) (xy 208.084677 -55.253253) (xy 208.141584 -55.164032)
			(xy 208.205075 -55.079369) (xy 208.274787 -54.999751) (xy 208.350321 -54.925633) (xy 208.431244 -54.85744)
			(xy 208.517093 -54.795562) (xy 208.607376 -54.740355) (xy 208.701575 -54.692133) (xy 208.799152 -54.651173)
			(xy 208.899547 -54.617711) (xy 209.002185 -54.591937) (xy 209.106478 -54.573999) (xy 209.211829 -54.564)
			(xy 209.317635 -54.561997) (xy 209.423289 -54.568002) (xy 209.528186 -54.581981) (xy 209.631726 -54.603852)
			(xy 209.733315 -54.633492) (xy 209.832372 -54.67073) (xy 209.928329 -54.715352) (xy 210.020636 -54.767104)
			(xy 210.108765 -54.825689) (xy 210.192211 -54.890771) (xy 210.270495 -54.961977) (xy 210.34317 -55.0389)
			(xy 210.40982 -55.1211) (xy 210.470062 -55.208104) (xy 210.523551 -55.299415) (xy 210.569982 -55.39451)
			(xy 210.609087 -55.492844) (xy 210.640644 -55.593855) (xy 210.664471 -55.696962) (xy 210.680432 -55.801576)
			(xy 210.688436 -55.907098) (xy 210.688936 -55.96001) (xy 210.688436 -56.012922) (xy 210.680432 -56.118444)
			(xy 210.664471 -56.223058) (xy 210.640644 -56.326165) (xy 210.609087 -56.427176) (xy 210.569982 -56.52551)
			(xy 210.523551 -56.620605) (xy 210.470062 -56.711916) (xy 210.40982 -56.79892) (xy 210.34317 -56.88112)
			(xy 210.270495 -56.958043) (xy 210.192211 -57.029249) (xy 210.108765 -57.094331) (xy 210.020636 -57.152916)
			(xy 209.928329 -57.204668) (xy 209.832372 -57.24929) (xy 209.733315 -57.286528) (xy 209.631726 -57.316168)
			(xy 209.528186 -57.338039) (xy 209.423289 -57.352018) (xy 209.317635 -57.358023) (xy 209.211829 -57.35602)
			(xy 209.106478 -57.346021) (xy 209.002185 -57.328083) (xy 208.899547 -57.302309) (xy 208.799152 -57.268847)
			(xy 208.701575 -57.227887) (xy 208.607376 -57.179665) (xy 208.517093 -57.124458) (xy 208.431244 -57.06258)
			(xy 208.350321 -56.994387) (xy 208.274787 -56.920269) (xy 208.205075 -56.840651) (xy 208.141584 -56.755988)
			(xy 208.084677 -56.666767) (xy 208.034681 -56.573497) (xy 207.991883 -56.476713) (xy 207.956526 -56.376969)
			(xy 207.928815 -56.274837) (xy 207.908906 -56.170902) (xy 207.896916 -56.065759) (xy 207.892911 -55.96001)
			(xy 199.512936 -55.96001) (xy 199.512436 -56.012922) (xy 199.504432 -56.118444) (xy 199.488471 -56.223058)
			(xy 199.464644 -56.326165) (xy 199.433087 -56.427176) (xy 199.393982 -56.52551) (xy 199.347551 -56.620605)
			(xy 199.294062 -56.711916) (xy 199.23382 -56.79892) (xy 199.16717 -56.88112) (xy 199.094495 -56.958043)
			(xy 199.016211 -57.029249) (xy 198.932765 -57.094331) (xy 198.844636 -57.152916) (xy 198.752329 -57.204668)
			(xy 198.656372 -57.24929) (xy 198.557315 -57.286528) (xy 198.455726 -57.316168) (xy 198.352186 -57.338039)
			(xy 198.247289 -57.352018) (xy 198.141635 -57.358023) (xy 198.035829 -57.35602) (xy 197.930478 -57.346021)
			(xy 197.826185 -57.328083) (xy 197.723547 -57.302309) (xy 197.623152 -57.268847) (xy 197.525575 -57.227887)
			(xy 197.431376 -57.179665) (xy 197.341093 -57.124458) (xy 197.255244 -57.06258) (xy 197.174321 -56.994387)
			(xy 197.098787 -56.920269) (xy 197.029075 -56.840651) (xy 196.965584 -56.755988) (xy 196.908677 -56.666767)
			(xy 196.858681 -56.573497) (xy 196.815883 -56.476713) (xy 196.780526 -56.376969) (xy 196.752815 -56.274837)
			(xy 196.732906 -56.170902) (xy 196.720916 -56.065759) (xy 196.716911 -55.96001) (xy 188.336936 -55.96001)
			(xy 188.336436 -56.012922) (xy 188.328432 -56.118444) (xy 188.312471 -56.223058) (xy 188.288644 -56.326165)
			(xy 188.257087 -56.427176) (xy 188.217982 -56.52551) (xy 188.171551 -56.620605) (xy 188.118062 -56.711916)
			(xy 188.05782 -56.79892) (xy 187.99117 -56.88112) (xy 187.918495 -56.958043) (xy 187.840211 -57.029249)
			(xy 187.756765 -57.094331) (xy 187.668636 -57.152916) (xy 187.576329 -57.204668) (xy 187.480372 -57.24929)
			(xy 187.381315 -57.286528) (xy 187.279726 -57.316168) (xy 187.176186 -57.338039) (xy 187.071289 -57.352018)
			(xy 186.965635 -57.358023) (xy 186.859829 -57.35602) (xy 186.754478 -57.346021) (xy 186.650185 -57.328083)
			(xy 186.547547 -57.302309) (xy 186.447152 -57.268847) (xy 186.349575 -57.227887) (xy 186.255376 -57.179665)
			(xy 186.165093 -57.124458) (xy 186.079244 -57.06258) (xy 185.998321 -56.994387) (xy 185.922787 -56.920269)
			(xy 185.853075 -56.840651) (xy 185.789584 -56.755988) (xy 185.732677 -56.666767) (xy 185.682681 -56.573497)
			(xy 185.639883 -56.476713) (xy 185.604526 -56.376969) (xy 185.576815 -56.274837) (xy 185.556906 -56.170902)
			(xy 185.544916 -56.065759) (xy 185.540911 -55.96001) (xy 170.688762 -55.96001) (xy 170.688262 -56.012922)
			(xy 170.680258 -56.118444) (xy 170.664297 -56.223058) (xy 170.64047 -56.326165) (xy 170.608913 -56.427176)
			(xy 170.569808 -56.52551) (xy 170.523377 -56.620605) (xy 170.469888 -56.711916) (xy 170.409646 -56.79892)
			(xy 170.342996 -56.88112) (xy 170.270321 -56.958043) (xy 170.192037 -57.029249) (xy 170.108591 -57.094331)
			(xy 170.020462 -57.152916) (xy 169.928155 -57.204668) (xy 169.832198 -57.24929) (xy 169.733141 -57.286528)
			(xy 169.631552 -57.316168) (xy 169.528012 -57.338039) (xy 169.423115 -57.352018) (xy 169.317461 -57.358023)
			(xy 169.211655 -57.35602) (xy 169.106304 -57.346021) (xy 169.002011 -57.328083) (xy 168.899373 -57.302309)
			(xy 168.798978 -57.268847) (xy 168.701401 -57.227887) (xy 168.607202 -57.179665) (xy 168.516919 -57.124458)
			(xy 168.43107 -57.06258) (xy 168.350147 -56.994387) (xy 168.274613 -56.920269) (xy 168.204901 -56.840651)
			(xy 168.14141 -56.755988) (xy 168.084503 -56.666767) (xy 168.034507 -56.573497) (xy 167.991709 -56.476713)
			(xy 167.956352 -56.376969) (xy 167.928641 -56.274837) (xy 167.908732 -56.170902) (xy 167.896742 -56.065759)
			(xy 167.892737 -55.96001) (xy 159.512762 -55.96001) (xy 159.512262 -56.012922) (xy 159.504258 -56.118444)
			(xy 159.488297 -56.223058) (xy 159.46447 -56.326165) (xy 159.432913 -56.427176) (xy 159.393808 -56.52551)
			(xy 159.347377 -56.620605) (xy 159.293888 -56.711916) (xy 159.233646 -56.79892) (xy 159.166996 -56.88112)
			(xy 159.094321 -56.958043) (xy 159.016037 -57.029249) (xy 158.932591 -57.094331) (xy 158.844462 -57.152916)
			(xy 158.752155 -57.204668) (xy 158.656198 -57.24929) (xy 158.557141 -57.286528) (xy 158.455552 -57.316168)
			(xy 158.352012 -57.338039) (xy 158.247115 -57.352018) (xy 158.141461 -57.358023) (xy 158.035655 -57.35602)
			(xy 157.930304 -57.346021) (xy 157.826011 -57.328083) (xy 157.723373 -57.302309) (xy 157.622978 -57.268847)
			(xy 157.525401 -57.227887) (xy 157.431202 -57.179665) (xy 157.340919 -57.124458) (xy 157.25507 -57.06258)
			(xy 157.174147 -56.994387) (xy 157.098613 -56.920269) (xy 157.028901 -56.840651) (xy 156.96541 -56.755988)
			(xy 156.908503 -56.666767) (xy 156.858507 -56.573497) (xy 156.815709 -56.476713) (xy 156.780352 -56.376969)
			(xy 156.752641 -56.274837) (xy 156.732732 -56.170902) (xy 156.720742 -56.065759) (xy 156.716737 -55.96001)
			(xy 148.336762 -55.96001) (xy 148.336262 -56.012922) (xy 148.328258 -56.118444) (xy 148.312297 -56.223058)
			(xy 148.28847 -56.326165) (xy 148.256913 -56.427176) (xy 148.217808 -56.52551) (xy 148.171377 -56.620605)
			(xy 148.117888 -56.711916) (xy 148.057646 -56.79892) (xy 147.990996 -56.88112) (xy 147.918321 -56.958043)
			(xy 147.840037 -57.029249) (xy 147.756591 -57.094331) (xy 147.668462 -57.152916) (xy 147.576155 -57.204668)
			(xy 147.480198 -57.24929) (xy 147.381141 -57.286528) (xy 147.279552 -57.316168) (xy 147.176012 -57.338039)
			(xy 147.071115 -57.352018) (xy 146.965461 -57.358023) (xy 146.859655 -57.35602) (xy 146.754304 -57.346021)
			(xy 146.650011 -57.328083) (xy 146.547373 -57.302309) (xy 146.446978 -57.268847) (xy 146.349401 -57.227887)
			(xy 146.255202 -57.179665) (xy 146.164919 -57.124458) (xy 146.07907 -57.06258) (xy 145.998147 -56.994387)
			(xy 145.922613 -56.920269) (xy 145.852901 -56.840651) (xy 145.78941 -56.755988) (xy 145.732503 -56.666767)
			(xy 145.682507 -56.573497) (xy 145.639709 -56.476713) (xy 145.604352 -56.376969) (xy 145.576641 -56.274837)
			(xy 145.556732 -56.170902) (xy 145.544742 -56.065759) (xy 145.540737 -55.96001) (xy 132.588762 -55.96001)
			(xy 132.588262 -56.012922) (xy 132.580258 -56.118444) (xy 132.564297 -56.223058) (xy 132.54047 -56.326165)
			(xy 132.508913 -56.427176) (xy 132.469808 -56.52551) (xy 132.423377 -56.620605) (xy 132.369888 -56.711916)
			(xy 132.309646 -56.79892) (xy 132.242996 -56.88112) (xy 132.170321 -56.958043) (xy 132.092037 -57.029249)
			(xy 132.008591 -57.094331) (xy 131.920462 -57.152916) (xy 131.828155 -57.204668) (xy 131.732198 -57.24929)
			(xy 131.633141 -57.286528) (xy 131.531552 -57.316168) (xy 131.428012 -57.338039) (xy 131.323115 -57.352018)
			(xy 131.217461 -57.358023) (xy 131.111655 -57.35602) (xy 131.006304 -57.346021) (xy 130.902011 -57.328083)
			(xy 130.799373 -57.302309) (xy 130.698978 -57.268847) (xy 130.601401 -57.227887) (xy 130.507202 -57.179665)
			(xy 130.416919 -57.124458) (xy 130.33107 -57.06258) (xy 130.250147 -56.994387) (xy 130.174613 -56.920269)
			(xy 130.104901 -56.840651) (xy 130.04141 -56.755988) (xy 129.984503 -56.666767) (xy 129.934507 -56.573497)
			(xy 129.891709 -56.476713) (xy 129.856352 -56.376969) (xy 129.828641 -56.274837) (xy 129.808732 -56.170902)
			(xy 129.796742 -56.065759) (xy 129.792737 -55.96001) (xy 121.412762 -55.96001) (xy 121.412262 -56.012922)
			(xy 121.404258 -56.118444) (xy 121.388297 -56.223058) (xy 121.36447 -56.326165) (xy 121.332913 -56.427176)
			(xy 121.293808 -56.52551) (xy 121.247377 -56.620605) (xy 121.193888 -56.711916) (xy 121.133646 -56.79892)
			(xy 121.066996 -56.88112) (xy 120.994321 -56.958043) (xy 120.916037 -57.029249) (xy 120.832591 -57.094331)
			(xy 120.744462 -57.152916) (xy 120.652155 -57.204668) (xy 120.556198 -57.24929) (xy 120.457141 -57.286528)
			(xy 120.355552 -57.316168) (xy 120.252012 -57.338039) (xy 120.147115 -57.352018) (xy 120.041461 -57.358023)
			(xy 119.935655 -57.35602) (xy 119.830304 -57.346021) (xy 119.726011 -57.328083) (xy 119.623373 -57.302309)
			(xy 119.522978 -57.268847) (xy 119.425401 -57.227887) (xy 119.331202 -57.179665) (xy 119.240919 -57.124458)
			(xy 119.15507 -57.06258) (xy 119.074147 -56.994387) (xy 118.998613 -56.920269) (xy 118.928901 -56.840651)
			(xy 118.86541 -56.755988) (xy 118.808503 -56.666767) (xy 118.758507 -56.573497) (xy 118.715709 -56.476713)
			(xy 118.680352 -56.376969) (xy 118.652641 -56.274837) (xy 118.632732 -56.170902) (xy 118.620742 -56.065759)
			(xy 118.616737 -55.96001) (xy 110.236762 -55.96001) (xy 110.236262 -56.012922) (xy 110.228258 -56.118444)
			(xy 110.212297 -56.223058) (xy 110.18847 -56.326165) (xy 110.156913 -56.427176) (xy 110.117808 -56.52551)
			(xy 110.071377 -56.620605) (xy 110.017888 -56.711916) (xy 109.957646 -56.79892) (xy 109.890996 -56.88112)
			(xy 109.818321 -56.958043) (xy 109.740037 -57.029249) (xy 109.656591 -57.094331) (xy 109.568462 -57.152916)
			(xy 109.476155 -57.204668) (xy 109.380198 -57.24929) (xy 109.281141 -57.286528) (xy 109.179552 -57.316168)
			(xy 109.076012 -57.338039) (xy 108.971115 -57.352018) (xy 108.865461 -57.358023) (xy 108.759655 -57.35602)
			(xy 108.654304 -57.346021) (xy 108.550011 -57.328083) (xy 108.447373 -57.302309) (xy 108.346978 -57.268847)
			(xy 108.249401 -57.227887) (xy 108.155202 -57.179665) (xy 108.064919 -57.124458) (xy 107.97907 -57.06258)
			(xy 107.898147 -56.994387) (xy 107.822613 -56.920269) (xy 107.752901 -56.840651) (xy 107.68941 -56.755988)
			(xy 107.632503 -56.666767) (xy 107.582507 -56.573497) (xy 107.539709 -56.476713) (xy 107.504352 -56.376969)
			(xy 107.476641 -56.274837) (xy 107.456732 -56.170902) (xy 107.444742 -56.065759) (xy 107.440737 -55.96001)
			(xy 92.075762 -55.96001) (xy 92.075262 -56.012922) (xy 92.067258 -56.118444) (xy 92.051297 -56.223058)
			(xy 92.02747 -56.326165) (xy 91.995913 -56.427176) (xy 91.956808 -56.52551) (xy 91.910377 -56.620605)
			(xy 91.856888 -56.711916) (xy 91.796646 -56.79892) (xy 91.729996 -56.88112) (xy 91.657321 -56.958043)
			(xy 91.579037 -57.029249) (xy 91.495591 -57.094331) (xy 91.407462 -57.152916) (xy 91.315155 -57.204668)
			(xy 91.219198 -57.24929) (xy 91.120141 -57.286528) (xy 91.018552 -57.316168) (xy 90.915012 -57.338039)
			(xy 90.810115 -57.352018) (xy 90.704461 -57.358023) (xy 90.598655 -57.35602) (xy 90.493304 -57.346021)
			(xy 90.389011 -57.328083) (xy 90.286373 -57.302309) (xy 90.185978 -57.268847) (xy 90.088401 -57.227887)
			(xy 89.994202 -57.179665) (xy 89.903919 -57.124458) (xy 89.81807 -57.06258) (xy 89.737147 -56.994387)
			(xy 89.661613 -56.920269) (xy 89.591901 -56.840651) (xy 89.52841 -56.755988) (xy 89.471503 -56.666767)
			(xy 89.421507 -56.573497) (xy 89.378709 -56.476713) (xy 89.343352 -56.376969) (xy 89.315641 -56.274837)
			(xy 89.295732 -56.170902) (xy 89.283742 -56.065759) (xy 89.279737 -55.96001) (xy 80.772762 -55.96001)
			(xy 80.772262 -56.012922) (xy 80.764258 -56.118444) (xy 80.748297 -56.223058) (xy 80.72447 -56.326165)
			(xy 80.692913 -56.427176) (xy 80.653808 -56.52551) (xy 80.607377 -56.620605) (xy 80.553888 -56.711916)
			(xy 80.493646 -56.79892) (xy 80.426996 -56.88112) (xy 80.354321 -56.958043) (xy 80.276037 -57.029249)
			(xy 80.192591 -57.094331) (xy 80.104462 -57.152916) (xy 80.012155 -57.204668) (xy 79.916198 -57.24929)
			(xy 79.817141 -57.286528) (xy 79.715552 -57.316168) (xy 79.612012 -57.338039) (xy 79.507115 -57.352018)
			(xy 79.401461 -57.358023) (xy 79.295655 -57.35602) (xy 79.190304 -57.346021) (xy 79.086011 -57.328083)
			(xy 78.983373 -57.302309) (xy 78.882978 -57.268847) (xy 78.785401 -57.227887) (xy 78.691202 -57.179665)
			(xy 78.600919 -57.124458) (xy 78.51507 -57.06258) (xy 78.434147 -56.994387) (xy 78.358613 -56.920269)
			(xy 78.288901 -56.840651) (xy 78.22541 -56.755988) (xy 78.168503 -56.666767) (xy 78.118507 -56.573497)
			(xy 78.075709 -56.476713) (xy 78.040352 -56.376969) (xy 78.012641 -56.274837) (xy 77.992732 -56.170902)
			(xy 77.980742 -56.065759) (xy 77.976737 -55.96001) (xy 69.469762 -55.96001) (xy 69.469262 -56.012922)
			(xy 69.461258 -56.118444) (xy 69.445297 -56.223058) (xy 69.42147 -56.326165) (xy 69.389913 -56.427176)
			(xy 69.350808 -56.52551) (xy 69.304377 -56.620605) (xy 69.250888 -56.711916) (xy 69.190646 -56.79892)
			(xy 69.123996 -56.88112) (xy 69.051321 -56.958043) (xy 68.973037 -57.029249) (xy 68.889591 -57.094331)
			(xy 68.801462 -57.152916) (xy 68.709155 -57.204668) (xy 68.613198 -57.24929) (xy 68.514141 -57.286528)
			(xy 68.412552 -57.316168) (xy 68.309012 -57.338039) (xy 68.204115 -57.352018) (xy 68.098461 -57.358023)
			(xy 67.992655 -57.35602) (xy 67.887304 -57.346021) (xy 67.783011 -57.328083) (xy 67.680373 -57.302309)
			(xy 67.579978 -57.268847) (xy 67.482401 -57.227887) (xy 67.388202 -57.179665) (xy 67.297919 -57.124458)
			(xy 67.21207 -57.06258) (xy 67.131147 -56.994387) (xy 67.055613 -56.920269) (xy 66.985901 -56.840651)
			(xy 66.92241 -56.755988) (xy 66.865503 -56.666767) (xy 66.815507 -56.573497) (xy 66.772709 -56.476713)
			(xy 66.737352 -56.376969) (xy 66.709641 -56.274837) (xy 66.689732 -56.170902) (xy 66.677742 -56.065759)
			(xy 66.673737 -55.96001) (xy 47.565849 -55.96001) (xy 47.570215 -55.982664) (xy 47.578268 -56.067001)
			(xy 47.578772 -56.109362) (xy 47.578268 -56.151723) (xy 47.570215 -56.23606) (xy 47.554181 -56.31925)
			(xy 47.530313 -56.40054) (xy 47.498825 -56.479192) (xy 47.460003 -56.554495) (xy 47.4142 -56.625767)
			(xy 47.361829 -56.692363) (xy 47.303364 -56.753678) (xy 47.239336 -56.809159) (xy 47.170324 -56.858302)
			(xy 47.096954 -56.900662) (xy 47.019889 -56.935857) (xy 46.939827 -56.963566) (xy 46.857494 -56.98354)
			(xy 46.773635 -56.995597) (xy 46.68901 -56.999629) (xy 46.604385 -56.995597) (xy 46.520526 -56.98354)
			(xy 46.438193 -56.963566) (xy 46.358131 -56.935857) (xy 46.281066 -56.900662) (xy 46.207696 -56.858302)
			(xy 46.138684 -56.809159) (xy 46.074656 -56.753678) (xy 46.016191 -56.692363) (xy 45.96382 -56.625767)
			(xy 45.918017 -56.554495) (xy 45.879195 -56.479192) (xy 45.847707 -56.40054) (xy 45.823839 -56.31925)
			(xy 45.807805 -56.23606) (xy 45.799752 -56.151723) (xy 45.369284 -56.151723) (xy 45.362719 -56.159871)
			(xy 45.302427 -56.221416) (xy 45.236465 -56.27684) (xy 45.16545 -56.325622) (xy 45.090048 -56.367305)
			(xy 45.010968 -56.401498) (xy 44.928951 -56.42788) (xy 44.844766 -56.446203) (xy 44.802044 -56.451754)
			(xy 44.793195 -56.453171) (xy 44.777202 -56.461221) (xy 44.764992 -56.474316) (xy 44.758078 -56.490831)
			(xy 44.75734 -56.49976) (xy 44.754638 -56.541945) (xy 44.742374 -56.625587) (xy 44.722231 -56.707688)
			(xy 44.694389 -56.787507) (xy 44.6591 -56.864325) (xy 44.616681 -56.937448) (xy 44.567517 -57.006217)
			(xy 44.51205 -57.070011) (xy 44.45078 -57.128255) (xy 44.384261 -57.180423) (xy 44.313092 -57.226045)
			(xy 44.237917 -57.264709) (xy 44.159412 -57.296066) (xy 44.078286 -57.319834) (xy 43.995271 -57.335797)
			(xy 43.911116 -57.343813) (xy 43.868848 -57.34431) (xy 43.827746 -57.343802) (xy 43.745891 -57.336221)
			(xy 43.665086 -57.32112) (xy 43.586018 -57.298627) (xy 43.509363 -57.268935) (xy 43.435776 -57.232296)
			(xy 43.365882 -57.189023) (xy 43.30028 -57.139486) (xy 43.239528 -57.084107) (xy 43.184146 -57.023359)
			(xy 43.134605 -56.957759) (xy 43.091328 -56.887868) (xy 43.054685 -56.814282) (xy 43.024989 -56.737629)
			(xy 43.002491 -56.658563) (xy 42.987386 -56.577758) (xy 42.9798 -56.495904) (xy 42.97934 -56.454802)
			(xy 40.049273 -56.454802) (xy 40.05916 -56.465481) (xy 40.109668 -56.531428) (xy 40.153809 -56.601797)
			(xy 40.191198 -56.675974) (xy 40.221509 -56.753314) (xy 40.244479 -56.833142) (xy 40.259907 -56.914764)
			(xy 40.267659 -56.997468) (xy 40.268144 -57.039002) (xy 40.268144 -57.03951) (xy 40.267634 -57.083274)
			(xy 40.259058 -57.170381) (xy 40.241961 -57.256222) (xy 40.216507 -57.339968) (xy 40.182945 -57.420805)
			(xy 40.162734 -57.459626) (xy 40.157403 -57.470978) (xy 40.157404 -57.496026) (xy 40.162734 -57.507378)
			(xy 40.182945 -57.546255) (xy 40.216517 -57.627194) (xy 40.241974 -57.711041) (xy 40.25907 -57.796983)
			(xy 40.26764 -57.884189) (xy 40.268144 -57.928002) (xy 40.267644 -57.971817) (xy 40.259099 -58.059028)
			(xy 40.242014 -58.144974) (xy 40.216553 -58.228823) (xy 40.182965 -58.309758) (xy 40.162734 -58.348626)
			(xy 40.157403 -58.359978) (xy 40.157404 -58.385026) (xy 40.162734 -58.396378) (xy 40.182923 -58.435209)
			(xy 40.216465 -58.516051) (xy 40.241912 -58.599794) (xy 40.259018 -58.685631) (xy 40.267617 -58.772732)
			(xy 40.268144 -58.816494) (xy 40.268144 -58.817002) (xy 40.267689 -58.858109) (xy 40.260105 -58.939973)
			(xy 40.245 -59.020789) (xy 40.222505 -59.099866) (xy 40.19281 -59.17653) (xy 40.156169 -59.250129)
			(xy 40.112895 -59.320033) (xy 40.063357 -59.385647) (xy 40.007977 -59.446411) (xy 39.947227 -59.501807)
			(xy 39.881626 -59.551363) (xy 39.811733 -59.594655) (xy 39.738145 -59.631315) (xy 39.661488 -59.66103)
			(xy 39.582416 -59.683546) (xy 39.501605 -59.698672) (xy 39.419743 -59.706279) (xy 39.378636 -59.706764)
			(xy 39.336925 -59.706314) (xy 39.25387 -59.698512) (xy 39.17191 -59.682965) (xy 39.091767 -59.659809)
			(xy 39.014146 -59.629247) (xy 38.939728 -59.591549) (xy 38.869169 -59.547045) (xy 38.803089 -59.496128)
			(xy 38.742069 -59.439245) (xy 38.686646 -59.376897) (xy 38.661594 -59.343544) (xy 38.654652 -59.335001)
			(xy 38.635433 -59.324324) (xy 38.62451 -59.32297) (xy 38.583139 -59.319256) (xy 38.501275 -59.305169)
			(xy 38.42108 -59.283512) (xy 38.343252 -59.254474) (xy 38.268471 -59.218308) (xy 38.197386 -59.175329)
			(xy 38.130618 -59.12591) (xy 38.068746 -59.070482) (xy 38.012311 -59.009529) (xy 37.961804 -58.94358)
			(xy 37.917663 -58.873211) (xy 37.880275 -58.799033) (xy 37.849964 -58.721692) (xy 37.826994 -58.641864)
			(xy 37.811565 -58.560241) (xy 37.803813 -58.477536) (xy 37.803328 -58.436002) (xy 37.803328 -58.435494)
			(xy 37.803843 -58.39173) (xy 37.812418 -58.304624) (xy 37.829515 -58.218782) (xy 37.854967 -58.135037)
			(xy 37.888528 -58.054199) (xy 37.908738 -58.015378) (xy 37.914061 -58.004024) (xy 37.914062 -57.978979)
			(xy 37.908738 -57.967626) (xy 37.888526 -57.92875) (xy 37.854955 -57.84781) (xy 37.829498 -57.763963)
			(xy 37.812402 -57.678021) (xy 37.803832 -57.590815) (xy 37.803328 -57.547002) (xy 37.803821 -57.503187)
			(xy 37.812366 -57.415976) (xy 37.829453 -57.330029) (xy 37.854915 -57.24618) (xy 37.888506 -57.165245)
			(xy 37.908738 -57.126378) (xy 37.914061 -57.115024) (xy 37.914062 -57.089979) (xy 37.908738 -57.078626)
			(xy 37.888526 -57.03975) (xy 37.854955 -56.95881) (xy 37.829498 -56.874963) (xy 37.812402 -56.789021)
			(xy 37.803832 -56.701815) (xy 37.803328 -56.658002) (xy 37.803969 -56.607847) (xy 37.815177 -56.508167)
			(xy 37.82568 -56.45912) (xy 37.827479 -56.448604) (xy 37.823362 -56.427696) (xy 37.811147 -56.410236)
			(xy 37.802312 -56.404256) (xy 37.766912 -56.382369) (xy 37.699929 -56.332962) (xy 37.637853 -56.277515)
			(xy 37.581226 -56.216513) (xy 37.530544 -56.15049) (xy 37.48625 -56.080021) (xy 37.44873 -56.005724)
			(xy 37.418313 -55.928248) (xy 37.395264 -55.84827) (xy 37.379785 -55.766488) (xy 37.372012 -55.683619)
			(xy 37.371528 -55.642002) (xy 35.433 -55.642002) (xy 35.433 -56.918606) (xy 35.433424 -56.928676)
			(xy 35.44114 -56.947279) (xy 35.447986 -56.954674) (xy 38.79977 -60.306458) (xy 38.806503 -60.312705)
			(xy 38.823187 -60.320351) (xy 38.841496 -60.321612) (xy 38.859071 -60.316328) (xy 38.866572 -60.31103)
			(xy 38.899761 -60.286326) (xy 38.969941 -60.242494) (xy 39.043887 -60.205367) (xy 39.12096 -60.175267)
			(xy 39.200496 -60.152453) (xy 39.281806 -60.137123) (xy 39.364189 -60.129409) (xy 39.40556 -60.128912)
			(xy 39.446664 -60.12937) (xy 39.528522 -60.136952) (xy 39.60933 -60.152055) (xy 39.688401 -60.17455)
			(xy 39.765059 -60.204244) (xy 39.838649 -60.240886) (xy 39.908545 -60.284161) (xy 39.974149 -60.333701)
			(xy 40.034902 -60.389084) (xy 40.090286 -60.449836) (xy 40.139828 -60.515439) (xy 40.183105 -60.585333)
			(xy 40.219748 -60.658923) (xy 40.249444 -60.73558) (xy 40.271941 -60.81465) (xy 40.287045 -60.895459)
			(xy 40.294629 -60.977316) (xy 40.295068 -61.01842) (xy 40.294542 -61.061908) (xy 40.286057 -61.148469)
			(xy 40.26917 -61.233789) (xy 40.244042 -61.317056) (xy 40.210913 -61.397476) (xy 40.170098 -61.47428)
			(xy 40.121988 -61.546738) (xy 40.094916 -61.580776) (xy 40.089106 -61.588513) (xy 40.083222 -61.606928)
			(xy 40.08455 -61.626216) (xy 40.088312 -61.635132) (xy 40.103623 -61.668151) (xy 40.125676 -61.737511)
			(xy 40.132254 -61.773308) (xy 40.136318 -61.786516) (xy 40.15221 -61.821803) (xy 40.178535 -61.894586)
			(xy 40.198447 -61.969377) (xy 40.211796 -62.045614) (xy 40.218482 -62.122721) (xy 40.218868 -62.16142)
			(xy 40.218287 -62.207675) (xy 40.213321 -62.2554) (xy 47.309532 -62.2554) (xy 47.309532 -62.254892)
			(xy 47.310135 -62.20856) (xy 47.319807 -62.116402) (xy 47.339003 -62.025748) (xy 47.367516 -61.937579)
			(xy 47.385732 -61.894974) (xy 47.389541 -61.885032) (xy 47.389541 -61.863768) (xy 47.385732 -61.853826)
			(xy 47.367506 -61.811225) (xy 47.33899 -61.723056) (xy 47.319799 -61.632401) (xy 47.31014 -61.54024)
			(xy 47.309532 -61.493908) (xy 47.309532 -61.4934) (xy 47.309952 -61.452296) (xy 47.317538 -61.370438)
			(xy 47.332644 -61.289629) (xy 47.355142 -61.210559) (xy 47.38484 -61.133902) (xy 47.421485 -61.060312)
			(xy 47.464763 -60.990417) (xy 47.514306 -60.924814) (xy 47.569691 -60.864063) (xy 47.630445 -60.80868)
			(xy 47.69605 -60.75914) (xy 47.765947 -60.715865) (xy 47.839538 -60.679224) (xy 47.916197 -60.649529)
			(xy 47.995268 -60.627035) (xy 48.076077 -60.611932) (xy 48.157936 -60.60435) (xy 48.19904 -60.603892)
			(xy 48.199548 -60.603892) (xy 48.245879 -60.604519) (xy 48.338037 -60.614184) (xy 48.428691 -60.633374)
			(xy 48.51686 -60.66188) (xy 48.559466 -60.680092) (xy 48.569408 -60.683898) (xy 48.590672 -60.683898)
			(xy 48.600614 -60.680092) (xy 48.643271 -60.661834) (xy 48.731565 -60.633293) (xy 48.822352 -60.614104)
			(xy 48.914643 -60.604475) (xy 48.96104 -60.603892) (xy 49.007435 -60.604496) (xy 49.099723 -60.614135)
			(xy 49.190507 -60.633325) (xy 49.278801 -60.661857) (xy 49.321466 -60.680092) (xy 49.331408 -60.683898)
			(xy 49.352672 -60.683898) (xy 49.362614 -60.680092) (xy 49.405271 -60.661834) (xy 49.493565 -60.633293)
			(xy 49.584352 -60.614104) (xy 49.676643 -60.604475) (xy 49.72304 -60.603892) (xy 49.769435 -60.604496)
			(xy 49.861723 -60.614135) (xy 49.952507 -60.633325) (xy 50.040801 -60.661857) (xy 50.083466 -60.680092)
			(xy 50.093408 -60.683898) (xy 50.114672 -60.683898) (xy 50.124614 -60.680092) (xy 50.167271 -60.661834)
			(xy 50.255565 -60.633293) (xy 50.346352 -60.614104) (xy 50.438643 -60.604475) (xy 50.48504 -60.603892)
			(xy 50.531435 -60.604496) (xy 50.623723 -60.614135) (xy 50.714507 -60.633325) (xy 50.802801 -60.661857)
			(xy 50.845466 -60.680092) (xy 50.855408 -60.683898) (xy 50.876672 -60.683898) (xy 50.886614 -60.680092)
			(xy 50.929211 -60.661857) (xy 51.017381 -60.633343) (xy 51.108038 -60.614154) (xy 51.200199 -60.604498)
			(xy 51.246532 -60.603892) (xy 51.24704 -60.603892) (xy 51.288143 -60.604328) (xy 51.369998 -60.611917)
			(xy 51.450804 -60.627026) (xy 51.529872 -60.649525) (xy 51.606526 -60.679224) (xy 51.680113 -60.715869)
			(xy 51.750005 -60.759147) (xy 51.815606 -60.808689) (xy 51.876355 -60.864073) (xy 51.931736 -60.924825)
			(xy 51.981275 -60.990428) (xy 52.02455 -61.060322) (xy 52.061192 -61.133911) (xy 52.090887 -61.210566)
			(xy 52.113384 -61.289634) (xy 52.128489 -61.370441) (xy 52.136073 -61.452297) (xy 52.136548 -61.4934)
			(xy 52.136548 -61.493908) (xy 52.135939 -61.54024) (xy 52.126268 -61.632397) (xy 52.107073 -61.723052)
			(xy 52.078562 -61.81122) (xy 52.060348 -61.853826) (xy 52.05654 -61.863768) (xy 52.05654 -61.885032)
			(xy 52.060348 -61.894974) (xy 52.078573 -61.937576) (xy 52.107089 -62.025744) (xy 52.126281 -62.1164)
			(xy 52.13594 -62.20856) (xy 52.136548 -62.254892) (xy 52.136548 -62.2554) (xy 52.136033 -62.296501)
			(xy 52.128449 -62.378353) (xy 52.113345 -62.459156) (xy 52.090849 -62.538221) (xy 52.061155 -62.614873)
			(xy 52.024515 -62.688458) (xy 51.981242 -62.758349) (xy 51.931705 -62.823949) (xy 51.894284 -62.865)
			(xy 60.705492 -62.865) (xy 60.705492 -62.864746) (xy 60.705976 -62.82326) (xy 60.71375 -62.740651)
			(xy 60.729179 -62.659125) (xy 60.752129 -62.579388) (xy 60.782401 -62.502134) (xy 60.819731 -62.428033)
			(xy 60.863796 -62.357727) (xy 60.888626 -62.324488) (xy 60.894965 -62.315288) (xy 60.899791 -62.2935)
			(xy 60.894965 -62.271712) (xy 60.888626 -62.262512) (xy 60.863786 -62.229279) (xy 60.8197 -62.158983)
			(xy 60.782357 -62.084885) (xy 60.752082 -62.007629) (xy 60.729138 -61.927888) (xy 60.713726 -61.846356)
			(xy 60.705978 -61.763742) (xy 60.705492 -61.722254) (xy 60.705492 -61.722) (xy 60.706009 -61.680858)
			(xy 60.713624 -61.598926) (xy 60.72877 -61.518046) (xy 60.751319 -61.438911) (xy 60.781077 -61.362195)
			(xy 60.81779 -61.288554) (xy 60.861145 -61.218617) (xy 60.910772 -61.152982) (xy 60.966246 -61.092208)
			(xy 61.027093 -61.036815) (xy 61.092795 -60.987276) (xy 61.16279 -60.944014) (xy 61.236479 -60.907398)
			(xy 61.313235 -60.877743) (xy 61.3924 -60.855299) (xy 61.473299 -60.840261) (xy 61.514228 -60.836048)
			(xy 61.514482 -60.836048) (xy 61.524785 -60.834611) (xy 61.54302 -60.824644) (xy 61.549788 -60.816744)
			(xy 61.601858 -60.749688) (xy 61.607192 -60.729368) (xy 61.605414 -60.718954) (xy 61.600256 -60.684197)
			(xy 61.594792 -60.614137) (xy 61.594492 -60.579) (xy 61.595075 -60.532604) (xy 61.60472 -60.440316)
			(xy 61.623916 -60.349532) (xy 61.652454 -60.261239) (xy 61.670692 -60.218574) (xy 61.674498 -60.208632)
			(xy 61.674498 -60.187368) (xy 61.670692 -60.177426) (xy 61.65247 -60.134823) (xy 61.623952 -60.046656)
			(xy 61.60476 -59.956) (xy 61.5951 -59.86384) (xy 61.594492 -59.817508) (xy 61.594492 -59.817) (xy 61.594996 -59.774652)
			(xy 61.603047 -59.690338) (xy 61.619076 -59.607172) (xy 61.642937 -59.525905) (xy 61.674416 -59.447275)
			(xy 61.713227 -59.371994) (xy 61.759017 -59.300742) (xy 61.811373 -59.234166) (xy 61.869821 -59.172868)
			(xy 61.933831 -59.117403) (xy 62.002823 -59.068274) (xy 62.076173 -59.025925) (xy 62.153216 -58.990741)
			(xy 62.233255 -58.963039) (xy 62.315564 -58.943071) (xy 62.399399 -58.931018) (xy 62.484 -58.926988)
			(xy 62.568601 -58.931018) (xy 62.652436 -58.943071) (xy 62.734745 -58.963039) (xy 62.814784 -58.990741)
			(xy 62.891827 -59.025925) (xy 62.965177 -59.068274) (xy 63.034169 -59.117403) (xy 63.098179 -59.172868)
			(xy 63.156627 -59.234166) (xy 63.208983 -59.300742) (xy 63.254773 -59.371994) (xy 63.293584 -59.447275)
			(xy 63.325063 -59.525905) (xy 63.348924 -59.607172) (xy 63.364953 -59.690338) (xy 63.373004 -59.774652)
			(xy 63.373508 -59.817) (xy 63.373508 -59.817508) (xy 63.372902 -59.86384) (xy 63.363231 -59.955998)
			(xy 63.344035 -60.046652) (xy 63.315523 -60.134821) (xy 63.297308 -60.177426) (xy 63.293502 -60.187368)
			(xy 63.293502 -60.208632) (xy 63.297308 -60.218574) (xy 63.31553 -60.261177) (xy 63.344048 -60.349344)
			(xy 63.36324 -60.44) (xy 63.3729 -60.53216) (xy 63.373508 -60.578492) (xy 63.373508 -60.579) (xy 63.372991 -60.620142)
			(xy 63.365376 -60.702074) (xy 63.35023 -60.782954) (xy 63.327681 -60.862089) (xy 63.297923 -60.938805)
			(xy 63.26121 -61.012446) (xy 63.217855 -61.082383) (xy 63.168228 -61.148018) (xy 63.112754 -61.208792)
			(xy 63.051907 -61.264185) (xy 62.986205 -61.313724) (xy 62.91621 -61.356986) (xy 62.842521 -61.393602)
			(xy 62.765765 -61.423257) (xy 62.6866 -61.445701) (xy 62.605701 -61.460739) (xy 62.564772 -61.464952)
			(xy 62.564518 -61.464952) (xy 62.554215 -61.466389) (xy 62.53598 -61.476356) (xy 62.529212 -61.484256)
			(xy 62.477142 -61.551312) (xy 62.471808 -61.571632) (xy 62.473586 -61.582046) (xy 62.478744 -61.616803)
			(xy 62.484208 -61.686863) (xy 62.484508 -61.722) (xy 62.484035 -61.763505) (xy 62.476278 -61.846151)
			(xy 62.460859 -61.927716) (xy 62.437912 -62.007491) (xy 62.407636 -62.084783) (xy 62.370296 -62.15892)
			(xy 62.326214 -62.229258) (xy 62.301374 -62.262512) (xy 62.295035 -62.271712) (xy 62.290209 -62.2935)
			(xy 62.295035 -62.315288) (xy 62.301374 -62.324488) (xy 62.326214 -62.357721) (xy 62.3703 -62.428017)
			(xy 62.407643 -62.502115) (xy 62.437918 -62.579371) (xy 62.460862 -62.659112) (xy 62.475774 -62.738)
			(xy 100.329492 -62.738) (xy 100.329492 -62.737746) (xy 100.329976 -62.69626) (xy 100.33775 -62.613651)
			(xy 100.353179 -62.532125) (xy 100.376129 -62.452388) (xy 100.406401 -62.375134) (xy 100.443731 -62.301033)
			(xy 100.487796 -62.230727) (xy 100.512626 -62.197488) (xy 100.518965 -62.188288) (xy 100.523791 -62.1665)
			(xy 100.518965 -62.144712) (xy 100.512626 -62.135512) (xy 100.487786 -62.102279) (xy 100.4437 -62.031983)
			(xy 100.406357 -61.957885) (xy 100.376082 -61.880629) (xy 100.353138 -61.800888) (xy 100.337726 -61.719356)
			(xy 100.329978 -61.636742) (xy 100.329492 -61.595254) (xy 100.329492 -61.595) (xy 100.330009 -61.553858)
			(xy 100.337624 -61.471926) (xy 100.35277 -61.391046) (xy 100.375319 -61.311911) (xy 100.405077 -61.235195)
			(xy 100.44179 -61.161554) (xy 100.485145 -61.091617) (xy 100.534772 -61.025982) (xy 100.590246 -60.965208)
			(xy 100.651093 -60.909815) (xy 100.716795 -60.860276) (xy 100.78679 -60.817014) (xy 100.860479 -60.780398)
			(xy 100.937235 -60.750743) (xy 101.0164 -60.728299) (xy 101.097299 -60.713261) (xy 101.138228 -60.709048)
			(xy 101.138482 -60.709048) (xy 101.148785 -60.707611) (xy 101.16702 -60.697644) (xy 101.173788 -60.689744)
			(xy 101.225858 -60.622688) (xy 101.231192 -60.602368) (xy 101.229414 -60.591954) (xy 101.224256 -60.557197)
			(xy 101.218792 -60.487137) (xy 101.218492 -60.452) (xy 101.219075 -60.405604) (xy 101.22872 -60.313316)
			(xy 101.247916 -60.222532) (xy 101.276454 -60.134239) (xy 101.294692 -60.091574) (xy 101.298498 -60.081632)
			(xy 101.298498 -60.060368) (xy 101.294692 -60.050426) (xy 101.27647 -60.007823) (xy 101.247952 -59.919656)
			(xy 101.22876 -59.829) (xy 101.2191 -59.73684) (xy 101.218492 -59.690508) (xy 101.218492 -59.69)
			(xy 101.218996 -59.647652) (xy 101.227047 -59.563338) (xy 101.243076 -59.480172) (xy 101.266937 -59.398905)
			(xy 101.298416 -59.320275) (xy 101.337227 -59.244994) (xy 101.383017 -59.173742) (xy 101.435373 -59.107166)
			(xy 101.493821 -59.045868) (xy 101.557831 -58.990403) (xy 101.626823 -58.941274) (xy 101.700173 -58.898925)
			(xy 101.777216 -58.863741) (xy 101.857255 -58.836039) (xy 101.939564 -58.816071) (xy 102.023399 -58.804018)
			(xy 102.108 -58.799988) (xy 102.192601 -58.804018) (xy 102.276436 -58.816071) (xy 102.358745 -58.836039)
			(xy 102.438784 -58.863741) (xy 102.515827 -58.898925) (xy 102.589177 -58.941274) (xy 102.658169 -58.990403)
			(xy 102.722179 -59.045868) (xy 102.780627 -59.107166) (xy 102.832983 -59.173742) (xy 102.878773 -59.244994)
			(xy 102.917584 -59.320275) (xy 102.949063 -59.398905) (xy 102.972924 -59.480172) (xy 102.988953 -59.563338)
			(xy 102.997004 -59.647652) (xy 102.997508 -59.69) (xy 102.997508 -59.690508) (xy 102.996902 -59.73684)
			(xy 102.987231 -59.828998) (xy 102.968035 -59.919652) (xy 102.939523 -60.007821) (xy 102.921308 -60.050426)
			(xy 102.917502 -60.060368) (xy 102.917502 -60.081632) (xy 102.921308 -60.091574) (xy 102.93953 -60.134177)
			(xy 102.968048 -60.222344) (xy 102.98724 -60.313) (xy 102.9969 -60.40516) (xy 102.997508 -60.451492)
			(xy 102.997508 -60.452) (xy 102.996991 -60.493142) (xy 102.989376 -60.575074) (xy 102.97423 -60.655954)
			(xy 102.951681 -60.735089) (xy 102.921923 -60.811805) (xy 102.88521 -60.885446) (xy 102.841855 -60.955383)
			(xy 102.792228 -61.021018) (xy 102.736754 -61.081792) (xy 102.675907 -61.137185) (xy 102.610205 -61.186724)
			(xy 102.54021 -61.229986) (xy 102.466521 -61.266602) (xy 102.389765 -61.296257) (xy 102.3106 -61.318701)
			(xy 102.229701 -61.333739) (xy 102.188772 -61.337952) (xy 102.188518 -61.337952) (xy 102.178215 -61.339389)
			(xy 102.15998 -61.349356) (xy 102.153212 -61.357256) (xy 102.101142 -61.424312) (xy 102.095808 -61.444632)
			(xy 102.097586 -61.455046) (xy 102.102744 -61.489803) (xy 102.108208 -61.559863) (xy 102.108508 -61.595)
			(xy 102.108035 -61.636505) (xy 102.100278 -61.719151) (xy 102.084859 -61.800716) (xy 102.061912 -61.880491)
			(xy 102.031636 -61.957783) (xy 101.994296 -62.03192) (xy 101.950214 -62.102258) (xy 101.925374 -62.135512)
			(xy 101.919035 -62.144712) (xy 101.914209 -62.1665) (xy 101.919035 -62.188288) (xy 101.925374 -62.197488)
			(xy 101.950214 -62.230721) (xy 101.9943 -62.301017) (xy 102.031643 -62.375115) (xy 102.061918 -62.452371)
			(xy 102.084862 -62.532112) (xy 102.100274 -62.613644) (xy 102.108022 -62.696258) (xy 102.108508 -62.737746)
			(xy 102.108508 -62.738) (xy 139.318492 -62.738) (xy 139.318492 -62.737492) (xy 139.319011 -62.693728)
			(xy 139.327586 -62.606622) (xy 139.344682 -62.520781) (xy 139.370133 -62.437035) (xy 139.403693 -62.356197)
			(xy 139.423902 -62.317376) (xy 139.429229 -62.306023) (xy 139.429229 -62.280977) (xy 139.423902 -62.269624)
			(xy 139.403708 -62.230796) (xy 139.370168 -62.149953) (xy 139.344723 -62.066208) (xy 139.327618 -61.980371)
			(xy 139.319019 -61.89327) (xy 139.318492 -61.849508) (xy 139.318492 -61.849) (xy 139.319009 -61.807858)
			(xy 139.326624 -61.725926) (xy 139.34177 -61.645046) (xy 139.364319 -61.565911) (xy 139.394077 -61.489195)
			(xy 139.43079 -61.415554) (xy 139.474145 -61.345617) (xy 139.523772 -61.279982) (xy 139.579246 -61.219208)
			(xy 139.640093 -61.163815) (xy 139.705795 -61.114276) (xy 139.77579 -61.071014) (xy 139.849479 -61.034398)
			(xy 139.926235 -61.004743) (xy 140.0054 -60.982299) (xy 140.086299 -60.967261) (xy 140.127228 -60.963048)
			(xy 140.127482 -60.963048) (xy 140.137785 -60.961611) (xy 140.15602 -60.951644) (xy 140.162788 -60.943744)
			(xy 140.214858 -60.876688) (xy 140.220192 -60.856368) (xy 140.218414 -60.845954) (xy 140.213256 -60.811197)
			(xy 140.207792 -60.741137) (xy 140.207492 -60.706) (xy 140.208075 -60.659604) (xy 140.21772 -60.567316)
			(xy 140.236916 -60.476532) (xy 140.265454 -60.388239) (xy 140.283692 -60.345574) (xy 140.287498 -60.335632)
			(xy 140.287498 -60.314368) (xy 140.283692 -60.304426) (xy 140.26547 -60.261823) (xy 140.236952 -60.173656)
			(xy 140.21776 -60.083) (xy 140.2081 -59.99084) (xy 140.207492 -59.944508) (xy 140.207492 -59.944)
			(xy 140.207996 -59.901652) (xy 140.216047 -59.817338) (xy 140.232076 -59.734172) (xy 140.255937 -59.652905)
			(xy 140.287416 -59.574275) (xy 140.326227 -59.498994) (xy 140.372017 -59.427742) (xy 140.424373 -59.361166)
			(xy 140.482821 -59.299868) (xy 140.546831 -59.244403) (xy 140.615823 -59.195274) (xy 140.689173 -59.152925)
			(xy 140.766216 -59.117741) (xy 140.846255 -59.090039) (xy 140.928564 -59.070071) (xy 141.012399 -59.058018)
			(xy 141.097 -59.053988) (xy 141.181601 -59.058018) (xy 141.265436 -59.070071) (xy 141.347745 -59.090039)
			(xy 141.427784 -59.117741) (xy 141.504827 -59.152925) (xy 141.578177 -59.195274) (xy 141.647169 -59.244403)
			(xy 141.711179 -59.299868) (xy 141.769627 -59.361166) (xy 141.821983 -59.427742) (xy 141.867773 -59.498994)
			(xy 141.906584 -59.574275) (xy 141.938063 -59.652905) (xy 141.961924 -59.734172) (xy 141.977953 -59.817338)
			(xy 141.986004 -59.901652) (xy 141.986508 -59.944) (xy 141.986508 -59.944508) (xy 141.985902 -59.99084)
			(xy 141.976231 -60.082998) (xy 141.957035 -60.173652) (xy 141.928523 -60.261821) (xy 141.910308 -60.304426)
			(xy 141.906502 -60.314368) (xy 141.906502 -60.335632) (xy 141.910308 -60.345574) (xy 141.92853 -60.388177)
			(xy 141.957048 -60.476344) (xy 141.97624 -60.567) (xy 141.9859 -60.65916) (xy 141.986508 -60.705492)
			(xy 141.986508 -60.706) (xy 141.985991 -60.747142) (xy 141.978376 -60.829074) (xy 141.96323 -60.909954)
			(xy 141.940681 -60.989089) (xy 141.910923 -61.065805) (xy 141.87421 -61.139446) (xy 141.830855 -61.209383)
			(xy 141.781228 -61.275018) (xy 141.725754 -61.335792) (xy 141.664907 -61.391185) (xy 141.599205 -61.440724)
			(xy 141.52921 -61.483986) (xy 141.455521 -61.520602) (xy 141.378765 -61.550257) (xy 141.2996 -61.572701)
			(xy 141.218701 -61.587739) (xy 141.177772 -61.591952) (xy 141.177518 -61.591952) (xy 141.167215 -61.593389)
			(xy 141.14898 -61.603356) (xy 141.142212 -61.611256) (xy 141.090142 -61.678312) (xy 141.084808 -61.698632)
			(xy 141.086586 -61.709046) (xy 141.091744 -61.743803) (xy 141.097208 -61.813863) (xy 141.097508 -61.849)
			(xy 179.318412 -61.849) (xy 179.31886 -61.807844) (xy 179.326447 -61.725881) (xy 179.341575 -61.644971)
			(xy 179.364115 -61.565804) (xy 179.393873 -61.489059) (xy 179.430594 -61.415391) (xy 179.473966 -61.345432)
			(xy 179.523616 -61.27978) (xy 179.57912 -61.218996) (xy 179.640003 -61.163601) (xy 179.705744 -61.114068)
			(xy 179.775781 -61.070821) (xy 179.849513 -61.034231) (xy 179.926312 -61.004611) (xy 180.005519 -60.982213)
			(xy 180.086456 -60.967229) (xy 180.127402 -60.963048) (xy 180.127656 -60.963048) (xy 180.137957 -60.961598)
			(xy 180.156192 -60.95164) (xy 180.162962 -60.943744) (xy 180.215032 -60.876688) (xy 180.220366 -60.856368)
			(xy 180.218588 -60.845954) (xy 180.213368 -60.811201) (xy 180.207773 -60.741141) (xy 180.207412 -60.706)
			(xy 180.208036 -60.659598) (xy 180.217726 -60.5673) (xy 180.236981 -60.476515) (xy 180.26559 -60.38823)
			(xy 180.283866 -60.345574) (xy 180.287673 -60.335632) (xy 180.287673 -60.314368) (xy 180.283866 -60.304426)
			(xy 180.2656 -60.261767) (xy 180.237009 -60.173478) (xy 180.217753 -60.082695) (xy 180.208041 -59.990401)
			(xy 180.207412 -59.944) (xy 180.207916 -59.901639) (xy 180.215969 -59.817302) (xy 180.232003 -59.734112)
			(xy 180.255871 -59.652822) (xy 180.287359 -59.57417) (xy 180.326181 -59.498867) (xy 180.371984 -59.427595)
			(xy 180.424355 -59.360999) (xy 180.48282 -59.299684) (xy 180.546848 -59.244203) (xy 180.61586 -59.19506)
			(xy 180.68923 -59.1527) (xy 180.766295 -59.117505) (xy 180.846357 -59.089796) (xy 180.92869 -59.069822)
			(xy 181.012549 -59.057765) (xy 181.097174 -59.053734) (xy 181.181799 -59.057765) (xy 181.265658 -59.069822)
			(xy 181.347991 -59.089796) (xy 181.428053 -59.117505) (xy 181.505118 -59.1527) (xy 181.578488 -59.19506)
			(xy 181.6475 -59.244203) (xy 181.711528 -59.299684) (xy 181.769993 -59.360999) (xy 181.822364 -59.427595)
			(xy 181.868167 -59.498867) (xy 181.906989 -59.57417) (xy 181.938477 -59.652822) (xy 181.962345 -59.734112)
			(xy 181.978379 -59.817302) (xy 181.986432 -59.901639) (xy 181.986936 -59.944) (xy 181.986308 -59.990402)
			(xy 181.976618 -60.082699) (xy 181.957365 -60.173485) (xy 181.928758 -60.26177) (xy 181.910482 -60.304426)
			(xy 181.906678 -60.314369) (xy 181.906678 -60.335631) (xy 181.910482 -60.345574) (xy 181.928745 -60.388234)
			(xy 181.957338 -60.476523) (xy 181.976595 -60.567306) (xy 181.986307 -60.659599) (xy 181.986936 -60.706)
			(xy 181.986444 -60.747155) (xy 181.978858 -60.829115) (xy 181.963731 -60.910023) (xy 181.941193 -60.989187)
			(xy 181.911437 -61.065931) (xy 181.874717 -61.139596) (xy 181.831349 -61.209554) (xy 181.781702 -61.275206)
			(xy 181.726201 -61.335989) (xy 181.665322 -61.391385) (xy 181.599584 -61.440918) (xy 181.529552 -61.484166)
			(xy 181.455822 -61.520758) (xy 181.379028 -61.550381) (xy 181.299825 -61.572782) (xy 181.21889 -61.587769)
			(xy 181.177946 -61.591952) (xy 181.177692 -61.591952) (xy 181.167386 -61.593376) (xy 181.149153 -61.603353)
			(xy 181.142386 -61.611256) (xy 181.090316 -61.678312) (xy 181.084982 -61.698632) (xy 181.08676 -61.709046)
			(xy 181.09198 -61.743799) (xy 181.097575 -61.813859) (xy 181.097936 -61.849) (xy 181.097398 -61.892337)
			(xy 181.088935 -61.978598) (xy 181.07212 -62.063626) (xy 181.047112 -62.146614) (xy 181.014148 -62.226775)
			(xy 180.994304 -62.265306) (xy 180.989053 -62.276759) (xy 180.989173 -62.301923) (xy 180.994558 -62.313312)
			(xy 181.015235 -62.352477) (xy 181.049579 -62.434116) (xy 181.075639 -62.518765) (xy 181.093157 -62.605585)
			(xy 181.101959 -62.693715) (xy 181.102508 -62.738) (xy 181.102004 -62.780348) (xy 181.093953 -62.864662)
			(xy 181.077924 -62.947828) (xy 181.054063 -63.029095) (xy 181.022584 -63.107725) (xy 180.983773 -63.183006)
			(xy 180.937983 -63.254258) (xy 180.885627 -63.320834) (xy 180.827179 -63.382132) (xy 180.763169 -63.437597)
			(xy 180.694177 -63.486726) (xy 180.620827 -63.529075) (xy 180.543784 -63.564259) (xy 180.463745 -63.591961)
			(xy 180.381436 -63.611929) (xy 180.297601 -63.623982) (xy 180.213 -63.628013) (xy 180.128399 -63.623982)
			(xy 180.044564 -63.611929) (xy 179.962255 -63.591961) (xy 179.882216 -63.564259) (xy 179.805173 -63.529075)
			(xy 179.731823 -63.486726) (xy 179.662831 -63.437597) (xy 179.598821 -63.382132) (xy 179.540373 -63.320834)
			(xy 179.488017 -63.254258) (xy 179.442227 -63.183006) (xy 179.403416 -63.107725) (xy 179.371937 -63.029095)
			(xy 179.348076 -62.947828) (xy 179.332047 -62.864662) (xy 179.323996 -62.780348) (xy 179.323492 -62.738)
			(xy 179.323492 -62.737746) (xy 179.324008 -62.69444) (xy 179.332429 -62.608238) (xy 179.349197 -62.523264)
			(xy 179.374152 -62.440324) (xy 179.407057 -62.360206) (xy 179.42687 -62.321694) (xy 179.432123 -62.310241)
			(xy 179.432003 -62.285077) (xy 179.426616 -62.273688) (xy 179.405927 -62.234523) (xy 179.371528 -62.152893)
			(xy 179.345413 -62.068249) (xy 179.327841 -61.981428) (xy 179.318986 -61.89329) (xy 179.318412 -61.849)
			(xy 141.097508 -61.849) (xy 141.097012 -61.892815) (xy 141.088467 -61.980026) (xy 141.07138 -62.065973)
			(xy 141.045919 -62.149821) (xy 141.012329 -62.230757) (xy 140.992098 -62.269624) (xy 140.986771 -62.280977)
			(xy 140.986771 -62.306023) (xy 140.992098 -62.317376) (xy 141.012292 -62.356204) (xy 141.045832 -62.437047)
			(xy 141.071277 -62.520792) (xy 141.088382 -62.606629) (xy 141.096981 -62.69373) (xy 141.097508 -62.737492)
			(xy 141.097508 -62.738) (xy 141.097004 -62.780348) (xy 141.088953 -62.864662) (xy 141.072924 -62.947828)
			(xy 141.049063 -63.029095) (xy 141.017584 -63.107725) (xy 140.978773 -63.183006) (xy 140.932983 -63.254258)
			(xy 140.880627 -63.320834) (xy 140.822179 -63.382132) (xy 140.758169 -63.437597) (xy 140.689177 -63.486726)
			(xy 140.615827 -63.529075) (xy 140.538784 -63.564259) (xy 140.458745 -63.591961) (xy 140.376436 -63.611929)
			(xy 140.292601 -63.623982) (xy 140.208 -63.628013) (xy 140.123399 -63.623982) (xy 140.039564 -63.611929)
			(xy 139.957255 -63.591961) (xy 139.877216 -63.564259) (xy 139.800173 -63.529075) (xy 139.726823 -63.486726)
			(xy 139.657831 -63.437597) (xy 139.593821 -63.382132) (xy 139.535373 -63.320834) (xy 139.483017 -63.254258)
			(xy 139.437227 -63.183006) (xy 139.398416 -63.107725) (xy 139.366937 -63.029095) (xy 139.343076 -62.947828)
			(xy 139.327047 -62.864662) (xy 139.318996 -62.780348) (xy 139.318492 -62.738) (xy 102.108508 -62.738)
			(xy 102.108004 -62.780348) (xy 102.099953 -62.864662) (xy 102.083924 -62.947828) (xy 102.060063 -63.029095)
			(xy 102.028584 -63.107725) (xy 101.989773 -63.183006) (xy 101.943983 -63.254258) (xy 101.891627 -63.320834)
			(xy 101.833179 -63.382132) (xy 101.769169 -63.437597) (xy 101.700177 -63.486726) (xy 101.626827 -63.529075)
			(xy 101.549784 -63.564259) (xy 101.469745 -63.591961) (xy 101.387436 -63.611929) (xy 101.303601 -63.623982)
			(xy 101.219 -63.628013) (xy 101.134399 -63.623982) (xy 101.050564 -63.611929) (xy 100.968255 -63.591961)
			(xy 100.888216 -63.564259) (xy 100.811173 -63.529075) (xy 100.737823 -63.486726) (xy 100.668831 -63.437597)
			(xy 100.604821 -63.382132) (xy 100.546373 -63.320834) (xy 100.494017 -63.254258) (xy 100.448227 -63.183006)
			(xy 100.409416 -63.107725) (xy 100.377937 -63.029095) (xy 100.354076 -62.947828) (xy 100.338047 -62.864662)
			(xy 100.329996 -62.780348) (xy 100.329492 -62.738) (xy 62.475774 -62.738) (xy 62.476274 -62.740644)
			(xy 62.484022 -62.823258) (xy 62.484508 -62.864746) (xy 62.484508 -62.865) (xy 62.484004 -62.907348)
			(xy 62.475953 -62.991662) (xy 62.459924 -63.074828) (xy 62.436063 -63.156095) (xy 62.404584 -63.234725)
			(xy 62.365773 -63.310006) (xy 62.319983 -63.381258) (xy 62.267627 -63.447834) (xy 62.209179 -63.509132)
			(xy 62.145169 -63.564597) (xy 62.076177 -63.613726) (xy 62.002827 -63.656075) (xy 61.925784 -63.691259)
			(xy 61.845745 -63.718961) (xy 61.763436 -63.738929) (xy 61.679601 -63.750982) (xy 61.595 -63.755013)
			(xy 61.510399 -63.750982) (xy 61.426564 -63.738929) (xy 61.344255 -63.718961) (xy 61.264216 -63.691259)
			(xy 61.187173 -63.656075) (xy 61.113823 -63.613726) (xy 61.044831 -63.564597) (xy 60.980821 -63.509132)
			(xy 60.922373 -63.447834) (xy 60.870017 -63.381258) (xy 60.824227 -63.310006) (xy 60.785416 -63.234725)
			(xy 60.753937 -63.156095) (xy 60.730076 -63.074828) (xy 60.714047 -62.991662) (xy 60.705996 -62.907348)
			(xy 60.705492 -62.865) (xy 51.894284 -62.865) (xy 51.876327 -62.884699) (xy 51.81558 -62.94008) (xy 51.749982 -62.98962)
			(xy 51.680093 -63.032896) (xy 51.60651 -63.069539) (xy 51.529859 -63.099237) (xy 51.450795 -63.121736)
			(xy 51.369993 -63.136843) (xy 51.288141 -63.144432) (xy 51.24704 -63.144908) (xy 51.246532 -63.144908)
			(xy 51.200201 -63.144288) (xy 51.108043 -63.134621) (xy 51.017389 -63.115429) (xy 50.92922 -63.086921)
			(xy 50.886614 -63.068708) (xy 50.876672 -63.064902) (xy 50.855408 -63.064902) (xy 50.845466 -63.068708)
			(xy 50.802798 -63.08694) (xy 50.714508 -63.115487) (xy 50.623725 -63.134684) (xy 50.531436 -63.144321)
			(xy 50.48504 -63.144908) (xy 50.438645 -63.144311) (xy 50.346357 -63.13467) (xy 50.255573 -63.115478)
			(xy 50.167279 -63.086944) (xy 50.124614 -63.068708) (xy 50.114672 -63.064902) (xy 50.093408 -63.064902)
			(xy 50.083466 -63.068708) (xy 50.040798 -63.08694) (xy 49.952508 -63.115487) (xy 49.861725 -63.134684)
			(xy 49.769436 -63.144321) (xy 49.72304 -63.144908) (xy 49.676645 -63.144311) (xy 49.584357 -63.13467)
			(xy 49.493573 -63.115478) (xy 49.405279 -63.086944) (xy 49.362614 -63.068708) (xy 49.352672 -63.064902)
			(xy 49.331408 -63.064902) (xy 49.321466 -63.068708) (xy 49.278798 -63.08694) (xy 49.190508 -63.115487)
			(xy 49.099725 -63.134684) (xy 49.007436 -63.144321) (xy 48.96104 -63.144908) (xy 48.914645 -63.144311)
			(xy 48.822357 -63.13467) (xy 48.731573 -63.115478) (xy 48.643279 -63.086944) (xy 48.600614 -63.068708)
			(xy 48.590672 -63.064902) (xy 48.569408 -63.064902) (xy 48.559466 -63.068708) (xy 48.516858 -63.086917)
			(xy 48.428692 -63.115438) (xy 48.338038 -63.134634) (xy 48.24588 -63.144298) (xy 48.199548 -63.144908)
			(xy 48.19904 -63.144908) (xy 48.157937 -63.14441) (xy 48.076083 -63.136828) (xy 47.995277 -63.121726)
			(xy 47.916209 -63.099233) (xy 47.839554 -63.06954) (xy 47.765966 -63.0329) (xy 47.696073 -62.989627)
			(xy 47.630471 -62.940089) (xy 47.569719 -62.884709) (xy 47.514337 -62.82396) (xy 47.464796 -62.75836)
			(xy 47.42152 -62.688469) (xy 47.384877 -62.614882) (xy 47.35518 -62.538229) (xy 47.332683 -62.459162)
			(xy 47.317577 -62.378357) (xy 47.309992 -62.296502) (xy 47.309532 -62.2554) (xy 40.213321 -62.2554)
			(xy 40.208713 -62.299688) (xy 40.189651 -62.390212) (xy 40.161304 -62.478272) (xy 40.143176 -62.52083)
			(xy 40.141144 -62.525728) (xy 40.138963 -62.536103) (xy 40.138858 -62.541404) (xy 40.138858 -66.944748)
			(xy 40.139291 -66.954813) (xy 40.147025 -66.973399) (xy 40.153844 -66.980816) (xy 41.103042 -67.930014)
			(xy 41.110438 -67.936863) (xy 41.129038 -67.944596) (xy 41.13911 -67.945) (xy 49.45253 -67.945) (xy 49.462406 -67.944538)
			(xy 49.480702 -67.937091) (xy 49.48809 -67.930522) (xy 49.546256 -67.873372) (xy 49.55413 -67.855338)
			(xy 49.55413 -67.845432) (xy 49.555563 -67.79516) (xy 49.565265 -67.695048) (xy 49.582698 -67.59599)
			(xy 49.607757 -67.498581) (xy 49.64029 -67.403407) (xy 49.680102 -67.311041) (xy 49.726953 -67.222038)
			(xy 49.780562 -67.136935) (xy 49.840605 -67.056243) (xy 49.906723 -66.980447) (xy 49.978516 -66.910004)
			(xy 50.055553 -66.845338) (xy 50.13737 -66.786837) (xy 50.223476 -66.734853) (xy 50.313352 -66.6897)
			(xy 50.406457 -66.651649) (xy 50.502231 -66.620928) (xy 50.600099 -66.597723) (xy 50.69947 -66.582174)
			(xy 50.799748 -66.574373) (xy 50.850038 -66.573908) (xy 50.850546 -66.573908) (xy 50.902195 -66.574421)
			(xy 51.005163 -66.582663) (xy 51.107149 -66.599076) (xy 51.207505 -66.623556) (xy 51.305593 -66.655946)
			(xy 51.400792 -66.696042) (xy 51.492496 -66.743589) (xy 51.580125 -66.798285) (xy 51.663122 -66.859783)
			(xy 51.74096 -66.927693) (xy 51.777392 -66.964306) (xy 51.784844 -66.971355) (xy 51.803719 -66.979338)
			(xy 51.813968 -66.9798) (xy 51.886104 -66.9798) (xy 51.896352 -66.97934) (xy 51.915229 -66.971355)
			(xy 51.92268 -66.964306) (xy 51.959145 -66.927688) (xy 52.037015 -66.859734) (xy 52.120051 -66.7982)
			(xy 52.207725 -66.743476) (xy 52.29948 -66.695912) (xy 52.394733 -66.655808) (xy 52.492878 -66.62342)
			(xy 52.593291 -66.598954) (xy 52.695334 -66.582565) (xy 52.798358 -66.574358) (xy 52.850034 -66.573908)
			(xy 52.901707 -66.574405) (xy 53.004726 -66.582623) (xy 53.106763 -66.599019) (xy 53.20717 -66.623488)
			(xy 53.305309 -66.655877) (xy 53.400557 -66.695979) (xy 53.492309 -66.743539) (xy 53.579982 -66.798255)
			(xy 53.663018 -66.85978) (xy 53.740891 -66.927722) (xy 53.777388 -66.964306) (xy 53.78484 -66.971355)
			(xy 53.803715 -66.97934) (xy 53.813964 -66.9798) (xy 53.8861 -66.9798) (xy 53.896348 -66.979341)
			(xy 53.915226 -66.971357) (xy 53.922676 -66.964306) (xy 53.959141 -66.927688) (xy 54.037011 -66.859734)
			(xy 54.120046 -66.798199) (xy 54.207721 -66.743475) (xy 54.299476 -66.69591) (xy 54.394728 -66.655806)
			(xy 54.492873 -66.623418) (xy 54.593287 -66.598952) (xy 54.69533 -66.582563) (xy 54.798354 -66.574356)
			(xy 54.85003 -66.573908) (xy 54.901703 -66.574405) (xy 55.004722 -66.582622) (xy 55.106759 -66.599018)
			(xy 55.207166 -66.623488) (xy 55.305306 -66.655876) (xy 55.400554 -66.695978) (xy 55.492306 -66.743537)
			(xy 55.579979 -66.798253) (xy 55.663016 -66.859778) (xy 55.740889 -66.92772) (xy 55.777384 -66.964306)
			(xy 55.784836 -66.971356) (xy 55.803711 -66.979342) (xy 55.81396 -66.9798) (xy 55.886096 -66.9798)
			(xy 55.896345 -66.979342) (xy 55.915223 -66.971359) (xy 55.922672 -66.964306) (xy 55.959138 -66.92769)
			(xy 56.037009 -66.859742) (xy 56.120047 -66.798214) (xy 56.207722 -66.743497) (xy 56.299477 -66.695939)
			(xy 56.39473 -66.655842) (xy 56.492875 -66.623461) (xy 56.593287 -66.599002) (xy 56.695329 -66.58262)
			(xy 56.798352 -66.574421) (xy 56.850026 -66.573908) (xy 56.901699 -66.574405) (xy 57.004718 -66.582622)
			(xy 57.106755 -66.599017) (xy 57.207163 -66.623487) (xy 57.305302 -66.655875) (xy 57.400551 -66.695976)
			(xy 57.492303 -66.743536) (xy 57.579977 -66.798252) (xy 57.663014 -66.859776) (xy 57.740887 -66.927718)
			(xy 57.77738 -66.964306) (xy 57.784832 -66.971357) (xy 57.803707 -66.979344) (xy 57.813956 -66.9798)
			(xy 57.886092 -66.9798) (xy 57.896333 -66.979324) (xy 57.915185 -66.971316) (xy 57.922668 -66.964306)
			(xy 57.959134 -66.92769) (xy 58.037005 -66.859742) (xy 58.120042 -66.798213) (xy 58.207717 -66.743496)
			(xy 58.299473 -66.695937) (xy 58.394726 -66.65584) (xy 58.492871 -66.623459) (xy 58.593283 -66.599)
			(xy 58.695325 -66.582618) (xy 58.798348 -66.574418) (xy 58.850022 -66.573908) (xy 58.901695 -66.574405)
			(xy 59.004714 -66.582621) (xy 59.106752 -66.599016) (xy 59.207159 -66.623486) (xy 59.305299 -66.655874)
			(xy 59.400548 -66.695975) (xy 59.492301 -66.743534) (xy 59.579974 -66.79825) (xy 59.663011 -66.859774)
			(xy 59.740885 -66.927716) (xy 59.777376 -66.964306) (xy 59.784828 -66.971357) (xy 59.803703 -66.979346)
			(xy 59.813952 -66.9798) (xy 59.886088 -66.9798) (xy 59.896329 -66.979325) (xy 59.915183 -66.971318)
			(xy 59.922664 -66.964306) (xy 59.95913 -66.92769) (xy 60.037001 -66.859742) (xy 60.120038 -66.798213)
			(xy 60.207713 -66.743495) (xy 60.299469 -66.695936) (xy 60.394722 -66.655839) (xy 60.492866 -66.623457)
			(xy 60.593279 -66.598998) (xy 60.695321 -66.582616) (xy 60.798344 -66.574415) (xy 60.850018 -66.573908)
			(xy 60.901691 -66.574405) (xy 61.00471 -66.582621) (xy 61.106748 -66.599016) (xy 61.207156 -66.623485)
			(xy 61.305296 -66.655872) (xy 61.400545 -66.695973) (xy 61.492298 -66.743533) (xy 61.579971 -66.798248)
			(xy 61.663009 -66.859772) (xy 61.740883 -66.927714) (xy 61.777372 -66.964306) (xy 61.784823 -66.971358)
			(xy 61.803698 -66.979349) (xy 61.813948 -66.9798) (xy 61.886084 -66.9798) (xy 61.896325 -66.979325)
			(xy 61.91518 -66.97132) (xy 61.92266 -66.964306) (xy 61.959108 -66.927708) (xy 62.036938 -66.859789)
			(xy 62.119929 -66.798284) (xy 62.207554 -66.743582) (xy 62.299257 -66.696032) (xy 62.394456 -66.655935)
			(xy 62.492545 -66.623546) (xy 62.592901 -66.599071) (xy 62.694888 -66.582665) (xy 62.797857 -66.574432)
			(xy 62.849506 -66.573908) (xy 62.850014 -66.573908) (xy 62.90091 -66.574408) (xy 63.002387 -66.582396)
			(xy 63.102926 -66.59832) (xy 63.201904 -66.622084) (xy 63.298714 -66.65354) (xy 63.392756 -66.692495)
			(xy 63.483453 -66.738708) (xy 63.570244 -66.791894) (xy 63.652595 -66.851726) (xy 63.729997 -66.917835)
			(xy 63.801974 -66.989813) (xy 63.868082 -67.067216) (xy 63.927913 -67.149568) (xy 63.981099 -67.236359)
			(xy 64.027311 -67.327056) (xy 64.066265 -67.4211) (xy 64.09772 -67.517909) (xy 64.121483 -67.616888)
			(xy 64.137406 -67.717427) (xy 64.145393 -67.818904) (xy 64.145393 -67.920696) (xy 64.137406 -68.022173)
			(xy 64.121483 -68.122712) (xy 64.09772 -68.221691) (xy 64.066265 -68.3185) (xy 64.027311 -68.412544)
			(xy 63.981099 -68.503241) (xy 63.927913 -68.590032) (xy 63.868082 -68.672384) (xy 63.801974 -68.749787)
			(xy 63.729997 -68.821765) (xy 63.652595 -68.887874) (xy 63.570244 -68.947706) (xy 63.483453 -69.000892)
			(xy 63.392756 -69.047105) (xy 63.298714 -69.08606) (xy 63.201904 -69.117516) (xy 63.102926 -69.14128)
			(xy 63.002387 -69.157204) (xy 62.90091 -69.165192) (xy 62.850014 -69.165724) (xy 62.849506 -69.165724)
			(xy 62.797858 -69.165209) (xy 62.694891 -69.156963) (xy 62.592907 -69.140547) (xy 62.492553 -69.116065)
			(xy 62.394467 -69.083673) (xy 62.29927 -69.043575) (xy 62.207567 -68.996027) (xy 62.11994 -68.94133)
			(xy 62.036945 -68.879832) (xy 61.959109 -68.811922) (xy 61.92266 -68.775326) (xy 61.915212 -68.768266)
			(xy 61.896337 -68.760258) (xy 61.886084 -68.759832) (xy 61.813948 -68.759832) (xy 61.803702 -68.760299)
			(xy 61.784832 -68.768288) (xy 61.777372 -68.775326) (xy 61.740906 -68.811942) (xy 61.663035 -68.879891)
			(xy 61.579998 -68.941421) (xy 61.492323 -68.99614) (xy 61.400567 -69.0437) (xy 61.305315 -69.083799)
			(xy 61.20717 -69.116182) (xy 61.106758 -69.140644) (xy 61.004716 -69.157028) (xy 60.901693 -69.165232)
			(xy 60.850018 -69.165724) (xy 60.798344 -69.165229) (xy 60.695323 -69.157015) (xy 60.593284 -69.140624)
			(xy 60.492874 -69.116157) (xy 60.394732 -69.083772) (xy 60.29948 -69.043674) (xy 60.207724 -68.996117)
			(xy 60.120048 -68.941404) (xy 60.037007 -68.879882) (xy 59.95913 -68.811941) (xy 59.922664 -68.775326)
			(xy 59.915216 -68.768265) (xy 59.896341 -68.760256) (xy 59.886088 -68.759832) (xy 59.813952 -68.759832)
			(xy 59.803706 -68.760298) (xy 59.784835 -68.768286) (xy 59.777376 -68.775326) (xy 59.74091 -68.811942)
			(xy 59.663039 -68.879892) (xy 59.580002 -68.941422) (xy 59.492327 -68.996141) (xy 59.400572 -69.043701)
			(xy 59.305319 -69.083801) (xy 59.207174 -69.116184) (xy 59.106762 -69.140646) (xy 59.00472 -69.157031)
			(xy 58.901697 -69.165234) (xy 58.850022 -69.165724) (xy 58.798348 -69.165229) (xy 58.695327 -69.157016)
			(xy 58.593287 -69.140624) (xy 58.492877 -69.116158) (xy 58.394735 -69.083773) (xy 58.299483 -69.043675)
			(xy 58.207727 -68.996118) (xy 58.12005 -68.941405) (xy 58.037009 -68.879883) (xy 57.959132 -68.811943)
			(xy 57.922668 -68.775326) (xy 57.91522 -68.768264) (xy 57.896345 -68.760254) (xy 57.886092 -68.759832)
			(xy 57.813956 -68.759832) (xy 57.80371 -68.760297) (xy 57.784837 -68.768285) (xy 57.77738 -68.775326)
			(xy 57.740914 -68.811942) (xy 57.663043 -68.879892) (xy 57.580006 -68.941422) (xy 57.492331 -68.996142)
			(xy 57.400576 -69.043702) (xy 57.305323 -69.083802) (xy 57.207179 -69.116186) (xy 57.106766 -69.140648)
			(xy 57.004724 -69.157033) (xy 56.901701 -69.165237) (xy 56.850026 -69.165724) (xy 56.798352 -69.165229)
			(xy 56.695331 -69.157016) (xy 56.593291 -69.140625) (xy 56.492881 -69.116159) (xy 56.394738 -69.083775)
			(xy 56.299486 -69.043677) (xy 56.20773 -68.99612) (xy 56.120053 -68.941407) (xy 56.037012 -68.879885)
			(xy 55.959134 -68.811945) (xy 55.922672 -68.775326) (xy 55.915225 -68.768264) (xy 55.89635 -68.760251)
			(xy 55.886096 -68.759832) (xy 55.81396 -68.759832) (xy 55.803713 -68.760296) (xy 55.78484 -68.768283)
			(xy 55.777384 -68.775326) (xy 55.740918 -68.811942) (xy 55.663047 -68.879892) (xy 55.58001 -68.941423)
			(xy 55.492335 -68.996142) (xy 55.40058 -69.043703) (xy 55.305327 -69.083803) (xy 55.207183 -69.116188)
			(xy 55.10677 -69.14065) (xy 55.004728 -69.157036) (xy 54.901705 -69.16524) (xy 54.85003 -69.165724)
			(xy 54.798356 -69.165229) (xy 54.695335 -69.157017) (xy 54.593295 -69.140626) (xy 54.492884 -69.11616)
			(xy 54.394741 -69.083776) (xy 54.299489 -69.043678) (xy 54.207733 -68.996122) (xy 54.120055 -68.941409)
			(xy 54.037014 -68.879887) (xy 53.959136 -68.811947) (xy 53.922676 -68.775326) (xy 53.915229 -68.768263)
			(xy 53.896354 -68.760249) (xy 53.8861 -68.759832) (xy 53.813964 -68.759832) (xy 53.803717 -68.760296)
			(xy 53.784842 -68.768281) (xy 53.777388 -68.775326) (xy 53.740922 -68.811943) (xy 53.663051 -68.879893)
			(xy 53.580014 -68.941423) (xy 53.49234 -68.996143) (xy 53.400584 -69.043705) (xy 53.305332 -69.083805)
			(xy 53.207187 -69.11619) (xy 53.106775 -69.140652) (xy 53.004732 -69.157038) (xy 52.901709 -69.165242)
			(xy 52.850034 -69.165724) (xy 52.79836 -69.165229) (xy 52.695338 -69.157017) (xy 52.593298 -69.140626)
			(xy 52.492888 -69.116161) (xy 52.394745 -69.083777) (xy 52.299492 -69.043679) (xy 52.207736 -68.996123)
			(xy 52.120058 -68.941411) (xy 52.037016 -68.879889) (xy 51.959138 -68.811949) (xy 51.92268 -68.775326)
			(xy 51.915233 -68.768262) (xy 51.896358 -68.760247) (xy 51.886104 -68.759832) (xy 51.813968 -68.759832)
			(xy 51.803721 -68.760295) (xy 51.784845 -68.768279) (xy 51.777392 -68.775326) (xy 51.739301 -68.813527)
			(xy 51.657754 -68.884166) (xy 51.570615 -68.947777) (xy 51.478487 -69.003921) (xy 51.382008 -69.052207)
			(xy 51.33213 -69.07276) (xy 51.320192 -69.077586) (xy 51.303936 -69.097144) (xy 51.284378 -69.192902)
			(xy 51.282498 -69.205365) (xy 51.289683 -69.229491) (xy 51.298094 -69.238876) (xy 56.369204 -74.309986)
			(xy 56.376602 -74.316833) (xy 56.3952 -74.324568) (xy 56.405272 -74.324972)
		)
		(stroke
			(width 0)
			(type solid)
		)
		(fill yes)
		(layer "In4.Cu")
		(net "P12V_BRICK")
	)
	(gr_poly
		(pts
			(xy 237.996984 -145.98396) (xy 238.007479 -145.983431) (xy 238.026715 -145.975027) (xy 238.041004 -145.959648)
			(xy 238.04499 -145.949924) (xy 238.04499 -145.94967) (xy 238.059208 -145.909656) (xy 238.094243 -145.832295)
			(xy 238.136493 -145.758626) (xy 238.185573 -145.689319) (xy 238.241035 -145.625006) (xy 238.302374 -145.566273)
			(xy 238.369033 -145.513653) (xy 238.440404 -145.467627) (xy 238.515837 -145.428613) (xy 238.594645 -145.396967)
			(xy 238.67611 -145.372977) (xy 238.759492 -145.356861) (xy 238.84403 -145.348766) (xy 238.928954 -145.348766)
			(xy 239.013492 -145.356861) (xy 239.096874 -145.372977) (xy 239.178339 -145.396967) (xy 239.257147 -145.428613)
			(xy 239.33258 -145.467627) (xy 239.403951 -145.513653) (xy 239.47061 -145.566273) (xy 239.531949 -145.625006)
			(xy 239.587411 -145.689319) (xy 239.636491 -145.758626) (xy 239.678741 -145.832295) (xy 239.713776 -145.909656)
			(xy 239.727994 -145.94967) (xy 239.727994 -145.949924) (xy 239.731946 -145.959668) (xy 239.746235 -145.975063)
			(xy 239.765497 -145.983442) (xy 239.776 -145.98396) (xy 243.076984 -145.98396) (xy 243.087479 -145.983431)
			(xy 243.106715 -145.975027) (xy 243.121004 -145.959648) (xy 243.12499 -145.949924) (xy 243.12499 -145.94967)
			(xy 243.139208 -145.909656) (xy 243.174243 -145.832295) (xy 243.216493 -145.758626) (xy 243.265573 -145.689319)
			(xy 243.321035 -145.625006) (xy 243.382374 -145.566273) (xy 243.449033 -145.513653) (xy 243.520404 -145.467627)
			(xy 243.595837 -145.428613) (xy 243.674645 -145.396967) (xy 243.75611 -145.372977) (xy 243.839492 -145.356861)
			(xy 243.92403 -145.348766) (xy 244.008954 -145.348766) (xy 244.093492 -145.356861) (xy 244.176874 -145.372977)
			(xy 244.258339 -145.396967) (xy 244.337147 -145.428613) (xy 244.41258 -145.467627) (xy 244.483951 -145.513653)
			(xy 244.55061 -145.566273) (xy 244.611949 -145.625006) (xy 244.667411 -145.689319) (xy 244.716491 -145.758626)
			(xy 244.758741 -145.832295) (xy 244.793776 -145.909656) (xy 244.807994 -145.94967) (xy 244.807994 -145.949924)
			(xy 244.811946 -145.959668) (xy 244.826235 -145.975063) (xy 244.845497 -145.983442) (xy 244.856 -145.98396)
			(xy 248.156984 -145.98396) (xy 248.167479 -145.983431) (xy 248.186715 -145.975027) (xy 248.201004 -145.959648)
			(xy 248.20499 -145.949924) (xy 248.20499 -145.94967) (xy 248.219208 -145.909656) (xy 248.254243 -145.832295)
			(xy 248.296493 -145.758626) (xy 248.345573 -145.689319) (xy 248.401035 -145.625006) (xy 248.462374 -145.566273)
			(xy 248.529033 -145.513653) (xy 248.600404 -145.467627) (xy 248.675837 -145.428613) (xy 248.754645 -145.396967)
			(xy 248.83611 -145.372977) (xy 248.919492 -145.356861) (xy 249.00403 -145.348766) (xy 249.088954 -145.348766)
			(xy 249.173492 -145.356861) (xy 249.256874 -145.372977) (xy 249.338339 -145.396967) (xy 249.417147 -145.428613)
			(xy 249.49258 -145.467627) (xy 249.563951 -145.513653) (xy 249.63061 -145.566273) (xy 249.691949 -145.625006)
			(xy 249.747411 -145.689319) (xy 249.796491 -145.758626) (xy 249.838741 -145.832295) (xy 249.873776 -145.909656)
			(xy 249.887994 -145.94967) (xy 249.887994 -145.949924) (xy 249.891946 -145.959668) (xy 249.906235 -145.975063)
			(xy 249.925497 -145.983442) (xy 249.936 -145.98396) (xy 253.236984 -145.98396) (xy 253.247479 -145.983431)
			(xy 253.266715 -145.975027) (xy 253.281004 -145.959648) (xy 253.28499 -145.949924) (xy 253.28499 -145.94967)
			(xy 253.299208 -145.909656) (xy 253.334243 -145.832295) (xy 253.376493 -145.758626) (xy 253.425573 -145.689319)
			(xy 253.481035 -145.625006) (xy 253.542374 -145.566273) (xy 253.609033 -145.513653) (xy 253.680404 -145.467627)
			(xy 253.755837 -145.428613) (xy 253.834645 -145.396967) (xy 253.91611 -145.372977) (xy 253.999492 -145.356861)
			(xy 254.08403 -145.348766) (xy 254.168954 -145.348766) (xy 254.253492 -145.356861) (xy 254.336874 -145.372977)
			(xy 254.418339 -145.396967) (xy 254.497147 -145.428613) (xy 254.57258 -145.467627) (xy 254.643951 -145.513653)
			(xy 254.71061 -145.566273) (xy 254.771949 -145.625006) (xy 254.827411 -145.689319) (xy 254.876491 -145.758626)
			(xy 254.918741 -145.832295) (xy 254.953776 -145.909656) (xy 254.967994 -145.94967) (xy 254.967994 -145.949924)
			(xy 254.971946 -145.959668) (xy 254.986235 -145.975063) (xy 255.005497 -145.983442) (xy 255.016 -145.98396)
			(xy 258.316984 -145.98396) (xy 258.327479 -145.983431) (xy 258.346715 -145.975027) (xy 258.361004 -145.959648)
			(xy 258.36499 -145.949924) (xy 258.36499 -145.94967) (xy 258.379208 -145.909656) (xy 258.414243 -145.832295)
			(xy 258.456493 -145.758626) (xy 258.505573 -145.689319) (xy 258.561035 -145.625006) (xy 258.622374 -145.566273)
			(xy 258.689033 -145.513653) (xy 258.760404 -145.467627) (xy 258.835837 -145.428613) (xy 258.914645 -145.396967)
			(xy 258.99611 -145.372977) (xy 259.079492 -145.356861) (xy 259.16403 -145.348766) (xy 259.248954 -145.348766)
			(xy 259.333492 -145.356861) (xy 259.416874 -145.372977) (xy 259.498339 -145.396967) (xy 259.577147 -145.428613)
			(xy 259.65258 -145.467627) (xy 259.723951 -145.513653) (xy 259.79061 -145.566273) (xy 259.851949 -145.625006)
			(xy 259.907411 -145.689319) (xy 259.956491 -145.758626) (xy 259.998741 -145.832295) (xy 260.033776 -145.909656)
			(xy 260.047994 -145.94967) (xy 260.047994 -145.949924) (xy 260.051946 -145.959668) (xy 260.066235 -145.975063)
			(xy 260.085497 -145.983442) (xy 260.096 -145.98396) (xy 263.396984 -145.98396) (xy 263.407479 -145.983431)
			(xy 263.426715 -145.975027) (xy 263.441004 -145.959648) (xy 263.44499 -145.949924) (xy 263.44499 -145.94967)
			(xy 263.459208 -145.909656) (xy 263.494243 -145.832295) (xy 263.536493 -145.758626) (xy 263.585573 -145.689319)
			(xy 263.641035 -145.625006) (xy 263.702374 -145.566273) (xy 263.769033 -145.513653) (xy 263.840404 -145.467627)
			(xy 263.915837 -145.428613) (xy 263.994645 -145.396967) (xy 264.07611 -145.372977) (xy 264.159492 -145.356861)
			(xy 264.24403 -145.348766) (xy 264.328954 -145.348766) (xy 264.413492 -145.356861) (xy 264.496874 -145.372977)
			(xy 264.578339 -145.396967) (xy 264.657147 -145.428613) (xy 264.73258 -145.467627) (xy 264.803951 -145.513653)
			(xy 264.87061 -145.566273) (xy 264.931949 -145.625006) (xy 264.987411 -145.689319) (xy 265.036491 -145.758626)
			(xy 265.078741 -145.832295) (xy 265.113776 -145.909656) (xy 265.127994 -145.94967) (xy 265.127994 -145.949924)
			(xy 265.131946 -145.959668) (xy 265.146235 -145.975063) (xy 265.165497 -145.983442) (xy 265.176 -145.98396)
			(xy 268.476984 -145.98396) (xy 268.487479 -145.983431) (xy 268.506715 -145.975027) (xy 268.521004 -145.959648)
			(xy 268.52499 -145.949924) (xy 268.52499 -145.94967) (xy 268.539208 -145.909656) (xy 268.574243 -145.832295)
			(xy 268.616493 -145.758626) (xy 268.665573 -145.689319) (xy 268.721035 -145.625006) (xy 268.782374 -145.566273)
			(xy 268.849033 -145.513653) (xy 268.920404 -145.467627) (xy 268.995837 -145.428613) (xy 269.074645 -145.396967)
			(xy 269.15611 -145.372977) (xy 269.239492 -145.356861) (xy 269.32403 -145.348766) (xy 269.408954 -145.348766)
			(xy 269.493492 -145.356861) (xy 269.576874 -145.372977) (xy 269.658339 -145.396967) (xy 269.737147 -145.428613)
			(xy 269.81258 -145.467627) (xy 269.883951 -145.513653) (xy 269.95061 -145.566273) (xy 270.011949 -145.625006)
			(xy 270.067411 -145.689319) (xy 270.116491 -145.758626) (xy 270.158741 -145.832295) (xy 270.193776 -145.909656)
			(xy 270.207994 -145.94967) (xy 270.207994 -145.949924) (xy 270.211946 -145.959668) (xy 270.226235 -145.975063)
			(xy 270.245497 -145.983442) (xy 270.256 -145.98396) (xy 273.556984 -145.98396) (xy 273.567479 -145.983431)
			(xy 273.586715 -145.975027) (xy 273.601004 -145.959648) (xy 273.60499 -145.949924) (xy 273.60499 -145.94967)
			(xy 273.619208 -145.909656) (xy 273.654243 -145.832295) (xy 273.696493 -145.758626) (xy 273.745573 -145.689319)
			(xy 273.801035 -145.625006) (xy 273.862374 -145.566273) (xy 273.929033 -145.513653) (xy 274.000404 -145.467627)
			(xy 274.075837 -145.428613) (xy 274.154645 -145.396967) (xy 274.23611 -145.372977) (xy 274.319492 -145.356861)
			(xy 274.40403 -145.348766) (xy 274.488954 -145.348766) (xy 274.573492 -145.356861) (xy 274.656874 -145.372977)
			(xy 274.738339 -145.396967) (xy 274.817147 -145.428613) (xy 274.89258 -145.467627) (xy 274.963951 -145.513653)
			(xy 275.03061 -145.566273) (xy 275.091949 -145.625006) (xy 275.147411 -145.689319) (xy 275.196491 -145.758626)
			(xy 275.238741 -145.832295) (xy 275.273776 -145.909656) (xy 275.287994 -145.94967) (xy 275.287994 -145.949924)
			(xy 275.291946 -145.959668) (xy 275.306235 -145.975063) (xy 275.325497 -145.983442) (xy 275.336 -145.98396)
			(xy 276.984714 -145.98396) (xy 276.994782 -145.983533) (xy 277.013379 -145.975811) (xy 277.020782 -145.968974)
			(xy 277.676864 -145.312892) (xy 277.683713 -145.305495) (xy 277.69145 -145.286896) (xy 277.69185 -145.276824)
			(xy 277.69185 -106.78033) (xy 277.69146 -106.770804) (xy 277.684511 -106.753065) (xy 277.671563 -106.73909)
			(xy 277.663148 -106.73461) (xy 277.567136 -106.688382) (xy 277.538688 -106.691684) (xy 277.527004 -106.700828)
			(xy 277.493246 -106.7271) (xy 277.421553 -106.77377) (xy 277.34571 -106.813342) (xy 277.266419 -106.84545)
			(xy 277.184411 -106.869797) (xy 277.100444 -106.886159) (xy 277.015295 -106.894383) (xy 276.972522 -106.894884)
			(xy 276.930159 -106.894397) (xy 276.845816 -106.886345) (xy 276.762621 -106.870312) (xy 276.681326 -106.846444)
			(xy 276.602669 -106.814956) (xy 276.527361 -106.776133) (xy 276.456084 -106.730328) (xy 276.389484 -106.677955)
			(xy 276.328164 -106.619488) (xy 276.27268 -106.555457) (xy 276.223533 -106.486441) (xy 276.181169 -106.413067)
			(xy 276.145972 -106.335998) (xy 276.118261 -106.255931) (xy 276.098285 -106.173594) (xy 276.086227 -106.08973)
			(xy 276.082196 -106.0051) (xy 276.086227 -105.92047) (xy 276.098285 -105.836606) (xy 276.118261 -105.754269)
			(xy 276.145972 -105.674202) (xy 276.181169 -105.597133) (xy 276.223533 -105.523759) (xy 276.27268 -105.454743)
			(xy 276.328164 -105.390712) (xy 276.389484 -105.332245) (xy 276.456084 -105.279872) (xy 276.527361 -105.234067)
			(xy 276.602669 -105.195244) (xy 276.681326 -105.163756) (xy 276.762621 -105.139888) (xy 276.845816 -105.123855)
			(xy 276.930159 -105.115803) (xy 276.972522 -105.11536) (xy 277.015293 -105.115883) (xy 277.100438 -105.124121)
			(xy 277.184399 -105.14049) (xy 277.266403 -105.164839) (xy 277.345692 -105.196943) (xy 277.421535 -105.236507)
			(xy 277.493232 -105.283165) (xy 277.527004 -105.309416) (xy 277.538688 -105.31856) (xy 277.567136 -105.321862)
			(xy 277.663148 -105.275634) (xy 277.671544 -105.271132) (xy 277.684474 -105.257158) (xy 277.691419 -105.239433)
			(xy 277.69185 -105.229914) (xy 277.69185 -96.417384) (xy 277.691469 -96.407957) (xy 277.684645 -96.39038)
			(xy 277.671926 -96.376461) (xy 277.663656 -96.371918) (xy 277.56866 -96.325182) (xy 277.539958 -96.327976)
			(xy 277.528528 -96.336866) (xy 277.49526 -96.361768) (xy 277.42488 -96.405964) (xy 277.350683 -96.443403)
			(xy 277.273319 -96.473757) (xy 277.19346 -96.496762) (xy 277.111803 -96.512218) (xy 277.029061 -96.519989)
			(xy 276.987508 -96.520508) (xy 276.987 -96.520508) (xy 276.944652 -96.520004) (xy 276.860338 -96.511953)
			(xy 276.777172 -96.495924) (xy 276.695905 -96.472063) (xy 276.617275 -96.440584) (xy 276.541994 -96.401773)
			(xy 276.470742 -96.355983) (xy 276.404166 -96.303627) (xy 276.342868 -96.245179) (xy 276.287403 -96.181169)
			(xy 276.238274 -96.112177) (xy 276.195925 -96.038827) (xy 276.160741 -95.961784) (xy 276.133039 -95.881745)
			(xy 276.113071 -95.799436) (xy 276.101018 -95.715601) (xy 276.096988 -95.631) (xy 276.101018 -95.546399)
			(xy 276.113071 -95.462564) (xy 276.133039 -95.380255) (xy 276.160741 -95.300216) (xy 276.195925 -95.223173)
			(xy 276.238274 -95.149823) (xy 276.287403 -95.080831) (xy 276.342868 -95.016821) (xy 276.404166 -94.958373)
			(xy 276.470742 -94.906017) (xy 276.541994 -94.860227) (xy 276.617275 -94.821416) (xy 276.695905 -94.789937)
			(xy 276.777172 -94.766076) (xy 276.860338 -94.750047) (xy 276.944652 -94.741996) (xy 276.987 -94.741492)
			(xy 276.987508 -94.741492) (xy 277.029062 -94.741983) (xy 277.111807 -94.749755) (xy 277.193466 -94.765211)
			(xy 277.273328 -94.788217) (xy 277.350695 -94.818572) (xy 277.424893 -94.856011) (xy 277.495276 -94.900209)
			(xy 277.528528 -94.925134) (xy 277.539958 -94.934024) (xy 277.56866 -94.936818) (xy 277.663656 -94.890082)
			(xy 277.67189 -94.885498) (xy 277.684574 -94.871584) (xy 277.691378 -94.85403) (xy 277.69185 -94.844616)
			(xy 277.69185 -53.90515) (xy 277.692368 -53.871888) (xy 277.701049 -53.805934) (xy 277.718268 -53.741678)
			(xy 277.743731 -53.680221) (xy 277.777001 -53.622616) (xy 277.817509 -53.569848) (xy 277.840694 -53.545994)
			(xy 278.61006 -52.776628) (xy 278.616171 -52.769989) (xy 278.623697 -52.753603) (xy 278.625093 -52.735626)
			(xy 278.623014 -52.726844) (xy 278.59482 -52.628038) (xy 278.575262 -52.609242) (xy 278.561546 -52.60594)
			(xy 278.520205 -52.595707) (xy 278.439537 -52.568379) (xy 278.36185 -52.533467) (xy 278.287854 -52.491292)
			(xy 278.218227 -52.442238) (xy 278.153606 -52.386756) (xy 278.094583 -52.325352) (xy 278.041697 -52.25859)
			(xy 277.995433 -52.187079) (xy 277.956215 -52.111474) (xy 277.9244 -52.032468) (xy 277.900281 -51.950783)
			(xy 277.884078 -51.867167) (xy 277.875939 -51.782386) (xy 277.875492 -51.7398) (xy 277.875967 -51.698698)
			(xy 277.883552 -51.616843) (xy 277.898657 -51.536038) (xy 277.921153 -51.456971) (xy 277.950849 -51.380317)
			(xy 277.987491 -51.30673) (xy 278.030766 -51.236838) (xy 278.080306 -51.171237) (xy 278.135687 -51.110487)
			(xy 278.196437 -51.055106) (xy 278.262038 -51.005566) (xy 278.33193 -50.962291) (xy 278.405517 -50.925649)
			(xy 278.482171 -50.895953) (xy 278.561238 -50.873457) (xy 278.642043 -50.858352) (xy 278.723898 -50.850767)
			(xy 278.765 -50.850292) (xy 278.765762 -50.850292) (xy 278.803981 -50.850715) (xy 278.880136 -50.857297)
			(xy 278.955447 -50.870381) (xy 279.029359 -50.889871) (xy 279.065482 -50.902362) (xy 279.073798 -50.904948)
			(xy 279.091202 -50.904948) (xy 279.099518 -50.902362) (xy 279.135724 -50.889817) (xy 279.209823 -50.870277)
			(xy 279.28533 -50.857192) (xy 279.361684 -50.85066) (xy 279.4 -50.850292) (xy 279.44246 -50.850771)
			(xy 279.526997 -50.858838) (xy 279.610379 -50.874926) (xy 279.691848 -50.89889) (xy 279.770662 -50.93051)
			(xy 279.846102 -50.9695) (xy 279.917483 -51.015503) (xy 279.984152 -51.068101) (xy 280.045505 -51.126816)
			(xy 280.073608 -51.158648) (xy 280.080856 -51.166223) (xy 280.099739 -51.175282) (xy 280.110184 -51.176174)
			(xy 280.184606 -51.179222) (xy 280.195132 -51.179075) (xy 280.214687 -51.171342) (xy 280.222452 -51.164236)
			(xy 282.578556 -48.808132) (xy 282.586069 -48.799869) (xy 282.593696 -48.778909) (xy 282.593288 -48.767746)
			(xy 282.586938 -48.690784) (xy 282.585452 -48.679811) (xy 282.574539 -48.660569) (xy 282.565856 -48.6537)
			(xy 282.531744 -48.628708) (xy 282.467915 -48.57323) (xy 282.409639 -48.511945) (xy 282.357442 -48.445406)
			(xy 282.311796 -48.374214) (xy 282.273111 -48.299012) (xy 282.241738 -48.220478) (xy 282.217959 -48.13932)
			(xy 282.20199 -48.056273) (xy 282.193973 -47.972085) (xy 282.193492 -47.9298) (xy 282.193967 -47.888698)
			(xy 282.201552 -47.806843) (xy 282.216657 -47.726038) (xy 282.239153 -47.646971) (xy 282.268849 -47.570317)
			(xy 282.305491 -47.49673) (xy 282.348766 -47.426838) (xy 282.398306 -47.361237) (xy 282.453687 -47.300487)
			(xy 282.514437 -47.245106) (xy 282.580038 -47.195566) (xy 282.64993 -47.152291) (xy 282.723517 -47.115649)
			(xy 282.800171 -47.085953) (xy 282.879238 -47.063457) (xy 282.960043 -47.048352) (xy 283.041898 -47.040767)
			(xy 283.083 -47.040292) (xy 283.083254 -47.040292) (xy 283.124826 -47.040786) (xy 283.207605 -47.048566)
			(xy 283.289297 -47.064036) (xy 283.36919 -47.087061) (xy 283.446586 -47.117438) (xy 283.520811 -47.154904)
			(xy 283.591216 -47.199132) (xy 283.657187 -47.249735) (xy 283.71815 -47.306272) (xy 283.746194 -47.336964)
			(xy 283.754202 -47.344957) (xy 283.775057 -47.353661) (xy 283.79763 -47.352608) (xy 283.807916 -47.347886)
			(xy 283.84659 -47.327891) (xy 283.927071 -47.29467) (xy 284.010412 -47.26947) (xy 284.095816 -47.252532)
			(xy 284.182466 -47.244017) (xy 284.226 -47.243492) (xy 284.226508 -47.243492) (xy 284.261946 -47.243857)
			(xy 284.332594 -47.249535) (xy 284.402567 -47.260814) (xy 284.437074 -47.268892) (xy 284.446452 -47.270746)
			(xy 284.465373 -47.268126) (xy 284.473904 -47.263812) (xy 284.500066 -47.249334) (xy 284.508232 -47.244357)
			(xy 284.520377 -47.229604) (xy 284.523688 -47.220632) (xy 284.537564 -47.180031) (xy 284.572063 -47.101464)
			(xy 284.613965 -47.026583) (xy 284.66288 -46.956083) (xy 284.718354 -46.890619) (xy 284.779873 -46.830799)
			(xy 284.846864 -46.777179) (xy 284.918705 -46.730256) (xy 284.99473 -46.690467) (xy 285.074232 -46.658181)
			(xy 285.156473 -46.633698) (xy 285.240688 -46.617245) (xy 285.326096 -46.608976) (xy 285.369 -46.608492)
			(xy 285.410102 -46.608967) (xy 285.491957 -46.616552) (xy 285.53287 -46.6242) (xy 288.755312 -46.6242)
			(xy 288.759342 -46.539599) (xy 288.771396 -46.455763) (xy 288.791365 -46.373454) (xy 288.819068 -46.293415)
			(xy 288.854253 -46.216372) (xy 288.896603 -46.143023) (xy 288.945734 -46.074031) (xy 289.0012 -46.010023)
			(xy 289.0625 -45.951576) (xy 289.129078 -45.899222) (xy 289.200331 -45.853433) (xy 289.275615 -45.814625)
			(xy 289.354246 -45.783149) (xy 289.435514 -45.759291) (xy 289.518681 -45.743265) (xy 289.602995 -45.735218)
			(xy 289.645344 -45.734732) (xy 289.684501 -45.735152) (xy 289.76251 -45.742051) (xy 289.839611 -45.755782)
			(xy 289.915206 -45.776238) (xy 289.988709 -45.803263) (xy 290.024312 -45.819568) (xy 290.034699 -45.823803)
			(xy 290.057105 -45.823803) (xy 290.067492 -45.819568) (xy 290.103102 -45.803279) (xy 290.176607 -45.776266)
			(xy 290.2522 -45.755814) (xy 290.329298 -45.74208) (xy 290.407304 -45.735172) (xy 290.44646 -45.734732)
			(xy 290.488812 -45.735138) (xy 290.573134 -45.743186) (xy 290.656308 -45.759214) (xy 290.737583 -45.783075)
			(xy 290.816221 -45.814554) (xy 290.891511 -45.853365) (xy 290.96277 -45.899158) (xy 291.029354 -45.951517)
			(xy 291.090659 -46.009969) (xy 291.14613 -46.073983) (xy 291.195265 -46.142981) (xy 291.237618 -46.216336)
			(xy 291.272807 -46.293386) (xy 291.300512 -46.373432) (xy 291.320482 -46.455749) (xy 291.332537 -46.539591)
			(xy 291.336568 -46.6242) (xy 291.332537 -46.708809) (xy 291.320482 -46.792651) (xy 291.300512 -46.874968)
			(xy 291.272807 -46.955014) (xy 291.237618 -47.032064) (xy 291.195265 -47.105419) (xy 291.14613 -47.174417)
			(xy 291.090659 -47.238431) (xy 291.029354 -47.296883) (xy 290.96277 -47.349242) (xy 290.891511 -47.395035)
			(xy 290.816221 -47.433846) (xy 290.737583 -47.465325) (xy 290.656308 -47.489186) (xy 290.573134 -47.505214)
			(xy 290.488812 -47.513262) (xy 290.44646 -47.513748) (xy 290.407303 -47.513328) (xy 290.329294 -47.50643)
			(xy 290.252193 -47.492699) (xy 290.176598 -47.472242) (xy 290.103095 -47.445218) (xy 290.067492 -47.428912)
			(xy 290.057105 -47.424677) (xy 290.034699 -47.424677) (xy 290.024312 -47.428912) (xy 289.988701 -47.445198)
			(xy 289.915197 -47.472212) (xy 289.839603 -47.492665) (xy 289.762506 -47.506399) (xy 289.6845 -47.513308)
			(xy 289.645344 -47.513748) (xy 289.602995 -47.513182) (xy 289.518681 -47.505135) (xy 289.435514 -47.489109)
			(xy 289.354246 -47.465251) (xy 289.275615 -47.433775) (xy 289.200331 -47.394967) (xy 289.129078 -47.349178)
			(xy 289.0625 -47.296824) (xy 289.0012 -47.238377) (xy 288.945734 -47.174369) (xy 288.896603 -47.105377)
			(xy 288.854253 -47.032028) (xy 288.819068 -46.954985) (xy 288.791365 -46.874946) (xy 288.771396 -46.792637)
			(xy 288.759342 -46.708801) (xy 288.755312 -46.6242) (xy 285.53287 -46.6242) (xy 285.572762 -46.631657)
			(xy 285.651829 -46.654153) (xy 285.728483 -46.683849) (xy 285.80207 -46.720491) (xy 285.871962 -46.763766)
			(xy 285.937563 -46.813306) (xy 285.998313 -46.868687) (xy 286.053694 -46.929437) (xy 286.103234 -46.995038)
			(xy 286.146509 -47.06493) (xy 286.183151 -47.138517) (xy 286.212847 -47.215171) (xy 286.235343 -47.294238)
			(xy 286.250448 -47.375043) (xy 286.258033 -47.456898) (xy 286.258508 -47.498) (xy 286.258508 -47.498254)
			(xy 286.258002 -47.541028) (xy 286.249792 -47.626182) (xy 286.233444 -47.710153) (xy 286.209108 -47.792167)
			(xy 286.17701 -47.871466) (xy 286.137447 -47.947316) (xy 286.090783 -48.019016) (xy 286.03745 -48.085905)
			(xy 285.977941 -48.147364) (xy 285.912806 -48.202825) (xy 285.842647 -48.251776) (xy 285.805626 -48.273208)
			(xy 285.79064 -48.28159) (xy 285.777178 -48.31334) (xy 285.806388 -48.425354) (xy 285.809794 -48.435987)
			(xy 285.82408 -48.453114) (xy 285.844261 -48.462606) (xy 285.85541 -48.4632) (xy 295.35755 -48.4632)
			(xy 295.367616 -48.462768) (xy 295.386207 -48.45504) (xy 295.393618 -48.448214) (xy 295.564814 -48.277018)
			(xy 295.571657 -48.269619) (xy 295.579375 -48.25102) (xy 295.5798 -48.24095) (xy 295.5798 -42.446194)
			(xy 295.579376 -42.436124) (xy 295.57166 -42.417521) (xy 295.564814 -42.410126) (xy 294.571674 -41.416986)
			(xy 294.564278 -41.410134) (xy 294.545679 -41.402396) (xy 294.535606 -41.402) (xy 293.60368 -41.402)
			(xy 293.594337 -41.40247) (xy 293.576916 -41.409246) (xy 293.563057 -41.421789) (xy 293.558468 -41.42994)
			(xy 293.51732 -41.510966) (xy 293.513485 -41.519533) (xy 293.511648 -41.538195) (xy 293.516648 -41.556268)
			(xy 293.521892 -41.564052) (xy 293.545557 -41.596846) (xy 293.587523 -41.665983) (xy 293.623044 -41.738643)
			(xy 293.651825 -41.814225) (xy 293.67363 -41.892108) (xy 293.688279 -41.971647) (xy 293.695651 -42.052188)
			(xy 293.696136 -42.092626) (xy 293.695632 -42.134987) (xy 293.687579 -42.219324) (xy 293.671545 -42.302514)
			(xy 293.647677 -42.383804) (xy 293.616189 -42.462456) (xy 293.577367 -42.537759) (xy 293.531564 -42.609031)
			(xy 293.479193 -42.675627) (xy 293.420728 -42.736942) (xy 293.3567 -42.792423) (xy 293.287688 -42.841566)
			(xy 293.214318 -42.883926) (xy 293.137253 -42.919121) (xy 293.057191 -42.94683) (xy 292.974858 -42.966804)
			(xy 292.890999 -42.978861) (xy 292.806374 -42.982893) (xy 292.721749 -42.978861) (xy 292.63789 -42.966804)
			(xy 292.555557 -42.94683) (xy 292.475495 -42.919121) (xy 292.39843 -42.883926) (xy 292.32506 -42.841566)
			(xy 292.256048 -42.792423) (xy 292.19202 -42.736942) (xy 292.133555 -42.675627) (xy 292.081184 -42.609031)
			(xy 292.035381 -42.537759) (xy 291.996559 -42.462456) (xy 291.965071 -42.383804) (xy 291.941203 -42.302514)
			(xy 291.925169 -42.219324) (xy 291.917116 -42.134987) (xy 291.916612 -42.092626) (xy 291.917078 -42.052186)
			(xy 291.924436 -41.971641) (xy 291.939077 -41.892097) (xy 291.960879 -41.81421) (xy 291.989663 -41.738625)
			(xy 292.025189 -41.665964) (xy 292.067166 -41.59683) (xy 292.090856 -41.564052) (xy 292.099492 -41.552368)
			(xy 292.101778 -41.52392) (xy 292.05428 -41.42994) (xy 292.049712 -41.421763) (xy 292.035872 -41.409169)
			(xy 292.018424 -41.402405) (xy 292.009068 -41.402) (xy 290.449 -41.402) (xy 290.424454 -41.401656)
			(xy 290.3756 -41.396826) (xy 290.351464 -41.392348) (xy 290.341562 -41.390793) (xy 290.321916 -41.394686)
			(xy 290.305265 -41.405817) (xy 290.299394 -41.413938) (xy 290.274682 -41.449926) (xy 290.219269 -41.517393)
			(xy 290.157512 -41.579105) (xy 290.090005 -41.634468) (xy 290.017398 -41.682951) (xy 289.94039 -41.724086)
			(xy 289.859722 -41.757477) (xy 289.776171 -41.782803) (xy 289.69054 -41.799821) (xy 289.603653 -41.808366)
			(xy 289.56 -41.808908) (xy 289.559492 -41.808908) (xy 289.520745 -41.808475) (xy 289.443545 -41.801707)
			(xy 289.367228 -41.788249) (xy 289.29237 -41.768204) (xy 289.219539 -41.741723) (xy 289.149289 -41.709007)
			(xy 289.1155 -41.690036) (xy 289.107626 -41.685877) (xy 289.0901 -41.682783) (xy 289.072574 -41.685877)
			(xy 289.0647 -41.690036) (xy 289.03092 -41.709024) (xy 288.960669 -41.74174) (xy 288.887836 -41.768219)
			(xy 288.812977 -41.788261) (xy 288.736657 -41.801713) (xy 288.659456 -41.808474) (xy 288.620708 -41.808908)
			(xy 288.6202 -41.808908) (xy 288.577852 -41.808404) (xy 288.493538 -41.800353) (xy 288.410372 -41.784324)
			(xy 288.329105 -41.760463) (xy 288.250475 -41.728984) (xy 288.175194 -41.690173) (xy 288.103942 -41.644383)
			(xy 288.037366 -41.592027) (xy 287.976068 -41.533579) (xy 287.920603 -41.469569) (xy 287.871474 -41.400577)
			(xy 287.829125 -41.327227) (xy 287.793941 -41.250184) (xy 287.766239 -41.170145) (xy 287.746271 -41.087836)
			(xy 287.734218 -41.004001) (xy 287.730188 -40.9194) (xy 287.734218 -40.834799) (xy 287.746271 -40.750964)
			(xy 287.766239 -40.668655) (xy 287.793941 -40.588616) (xy 287.829125 -40.511573) (xy 287.871474 -40.438223)
			(xy 287.920603 -40.369231) (xy 287.976068 -40.305221) (xy 288.037366 -40.246773) (xy 288.103942 -40.194417)
			(xy 288.175194 -40.148627) (xy 288.250475 -40.109816) (xy 288.329105 -40.078337) (xy 288.410372 -40.054476)
			(xy 288.493538 -40.038447) (xy 288.577852 -40.030396) (xy 288.6202 -40.029892) (xy 288.620708 -40.029892)
			(xy 288.659455 -40.030325) (xy 288.736655 -40.037093) (xy 288.812972 -40.050551) (xy 288.88783 -40.070596)
			(xy 288.960661 -40.097077) (xy 289.030911 -40.129793) (xy 289.0647 -40.148764) (xy 289.072574 -40.152923)
			(xy 289.0901 -40.156017) (xy 289.107626 -40.152923) (xy 289.1155 -40.148764) (xy 289.151568 -40.129206)
			(xy 289.15965 -40.124578) (xy 289.172043 -40.110698) (xy 289.17864 -40.093299) (xy 289.179 -40.083994)
			(xy 289.179 -34.654998) (xy 289.178825 -34.648268) (xy 289.175343 -34.635267) (xy 289.172142 -34.629344)
			(xy 289.151149 -34.592254) (xy 289.11554 -34.514817) (xy 289.087499 -34.43433) (xy 289.067283 -34.35153)
			(xy 289.055077 -34.267177) (xy 289.050993 -34.182043) (xy 289.055069 -34.096909) (xy 289.067267 -34.012554)
			(xy 289.087475 -33.929753) (xy 289.115508 -33.849263) (xy 289.151109 -33.771823) (xy 289.172142 -33.734756)
			(xy 289.17531 -33.72882) (xy 289.178784 -33.715827) (xy 289.179 -33.709102) (xy 289.179 -32.076898)
			(xy 289.178825 -32.070168) (xy 289.175343 -32.057167) (xy 289.172142 -32.051244) (xy 289.151147 -32.014156)
			(xy 289.115536 -31.936723) (xy 289.087495 -31.856238) (xy 289.067281 -31.773441) (xy 289.05508 -31.689089)
			(xy 289.051003 -31.603957) (xy 289.055088 -31.518825) (xy 289.067297 -31.434475) (xy 289.087519 -31.351679)
			(xy 289.115568 -31.271197) (xy 289.151187 -31.193767) (xy 289.172142 -31.156656) (xy 289.175444 -31.150814)
			(xy 289.179 -31.138114) (xy 289.179 -31.072836) (xy 289.175444 -31.060136) (xy 289.172142 -31.054294)
			(xy 289.152865 -31.020316) (xy 289.119656 -30.9496) (xy 289.092777 -30.876243) (xy 289.072434 -30.800812)
			(xy 289.058784 -30.723888) (xy 289.051933 -30.646063) (xy 289.051492 -30.607) (xy 289.051492 -30.606492)
			(xy 289.051978 -30.565131) (xy 289.059682 -30.482769) (xy 289.074994 -30.401476) (xy 289.097783 -30.321955)
			(xy 289.127852 -30.244892) (xy 289.14598 -30.207712) (xy 289.153346 -30.19298) (xy 289.148266 -30.160722)
			(xy 289.10153 -30.113986) (xy 289.094132 -30.107141) (xy 289.075533 -30.099419) (xy 289.065462 -30.099)
			(xy 284.584394 -30.099) (xy 284.574324 -30.099424) (xy 284.555721 -30.10714) (xy 284.548326 -30.113986)
			(xy 284.367986 -30.294326) (xy 284.361134 -30.301722) (xy 284.353396 -30.320321) (xy 284.353 -30.330394)
			(xy 284.353 -34.18967) (xy 284.353535 -34.200691) (xy 284.362746 -34.220716) (xy 284.37078 -34.228278)
			(xy 284.429962 -34.27857) (xy 284.438663 -34.285208) (xy 284.459714 -34.291116) (xy 284.470602 -34.29)
			(xy 284.470856 -34.29) (xy 284.506167 -34.28458) (xy 284.577374 -34.278732) (xy 284.613096 -34.278316)
			(xy 284.65514 -34.278818) (xy 284.73885 -34.286772) (xy 284.821437 -34.302583) (xy 284.902167 -34.326109)
			(xy 284.980319 -34.35714) (xy 285.017972 -34.375852) (xy 285.018226 -34.375852) (xy 285.028629 -34.380646)
			(xy 285.051503 -34.381302) (xy 285.062168 -34.377122) (xy 285.144718 -34.339784) (xy 285.159704 -34.322512)
			(xy 285.162498 -34.311336) (xy 285.173563 -34.271061) (xy 285.202252 -34.192612) (xy 285.238166 -34.117196)
			(xy 285.280989 -34.045478) (xy 285.330344 -33.978089) (xy 285.385798 -33.915621) (xy 285.446861 -33.858625)
			(xy 285.512997 -33.807602) (xy 285.583623 -33.763002) (xy 285.658118 -33.725216) (xy 285.735826 -33.694577)
			(xy 285.816063 -33.671355) (xy 285.898124 -33.655755) (xy 285.981285 -33.647913) (xy 286.02305 -33.64738)
			(xy 286.065365 -33.64788) (xy 286.149612 -33.655914) (xy 286.232715 -33.671914) (xy 286.313923 -33.695736)
			(xy 286.3925 -33.727165) (xy 286.467737 -33.765915) (xy 286.503618 -33.78835) (xy 286.512125 -33.793327)
			(xy 286.531465 -33.797019) (xy 286.550767 -33.793127) (xy 286.559244 -33.788096) (xy 286.595761 -33.764442)
			(xy 286.672571 -33.723562) (xy 286.753006 -33.690379) (xy 286.836298 -33.665212) (xy 286.921649 -33.6483)
			(xy 287.008245 -33.639806) (xy 287.05175 -33.639252) (xy 287.094103 -33.639738) (xy 287.178425 -33.647785)
			(xy 287.2616 -33.663812) (xy 287.342875 -33.687672) (xy 287.421515 -33.719151) (xy 287.496805 -33.757962)
			(xy 287.568065 -33.803754) (xy 287.63465 -33.856114) (xy 287.695956 -33.914565) (xy 287.751428 -33.97858)
			(xy 287.800563 -34.047578) (xy 287.842917 -34.120934) (xy 287.878106 -34.197984) (xy 287.905811 -34.27803)
			(xy 287.925782 -34.360348) (xy 287.937837 -34.444191) (xy 287.941868 -34.5288) (xy 287.937837 -34.613409)
			(xy 287.925782 -34.697252) (xy 287.905811 -34.77957) (xy 287.878106 -34.859616) (xy 287.842917 -34.936666)
			(xy 287.800563 -35.010022) (xy 287.751428 -35.07902) (xy 287.695956 -35.143035) (xy 287.63465 -35.201486)
			(xy 287.568065 -35.253846) (xy 287.496805 -35.299638) (xy 287.421515 -35.338449) (xy 287.342875 -35.369928)
			(xy 287.2616 -35.393788) (xy 287.178425 -35.409815) (xy 287.094103 -35.417862) (xy 287.05175 -35.418268)
			(xy 287.051242 -35.418268) (xy 287.008976 -35.417769) (xy 286.924824 -35.409749) (xy 286.841814 -35.393776)
			(xy 286.760695 -35.369995) (xy 286.6822 -35.33862) (xy 286.607038 -35.299936) (xy 286.571182 -35.277552)
			(xy 286.562676 -35.272574) (xy 286.543335 -35.268883) (xy 286.524033 -35.272775) (xy 286.515556 -35.277806)
			(xy 286.479046 -35.301484) (xy 286.402247 -35.342412) (xy 286.321816 -35.375642) (xy 286.238524 -35.400855)
			(xy 286.153167 -35.417811) (xy 286.066562 -35.426347) (xy 286.02305 -35.426904) (xy 285.981007 -35.4264)
			(xy 285.897298 -35.418441) (xy 285.814713 -35.402626) (xy 285.733986 -35.379096) (xy 285.655836 -35.348061)
			(xy 285.618174 -35.329368) (xy 285.61792 -35.329368) (xy 285.607516 -35.324569) (xy 285.584635 -35.323895)
			(xy 285.573978 -35.328098) (xy 285.491428 -35.365436) (xy 285.476442 -35.382708) (xy 285.473648 -35.393884)
			(xy 285.461341 -35.438467) (xy 285.428708 -35.525013) (xy 285.387264 -35.607701) (xy 285.337455 -35.685638)
			(xy 285.279821 -35.75798) (xy 285.247842 -35.791394) (xy 285.240205 -35.800029) (xy 285.232704 -35.821793)
			(xy 285.233364 -35.833304) (xy 285.243016 -35.91179) (xy 285.244828 -35.923068) (xy 285.256987 -35.942381)
			(xy 285.266384 -35.948874) (xy 285.300812 -35.97098) (xy 285.365882 -36.020586) (xy 285.426123 -36.075957)
			(xy 285.481025 -36.136625) (xy 285.530125 -36.202078) (xy 285.573009 -36.271762) (xy 285.609313 -36.345089)
			(xy 285.638731 -36.42144) (xy 285.661015 -36.500169) (xy 285.675977 -36.580612) (xy 285.683489 -36.662089)
			(xy 285.68396 -36.703) (xy 285.6835 -36.744102) (xy 285.675915 -36.825956) (xy 285.660809 -36.906761)
			(xy 285.638312 -36.985828) (xy 285.608615 -37.062481) (xy 285.571972 -37.136067) (xy 285.528696 -37.205958)
			(xy 285.479155 -37.271558) (xy 285.423772 -37.332306) (xy 285.363021 -37.387686) (xy 285.297418 -37.437223)
			(xy 285.227525 -37.480496) (xy 285.153937 -37.517135) (xy 285.077282 -37.546827) (xy 284.998215 -37.56932)
			(xy 284.917409 -37.584421) (xy 284.835554 -37.592002) (xy 284.794452 -37.592508) (xy 284.793944 -37.592508)
			(xy 284.755081 -37.592084) (xy 284.677654 -37.585281) (xy 284.601115 -37.571748) (xy 284.526049 -37.551589)
			(xy 284.489398 -37.53866) (xy 284.477714 -37.534342) (xy 284.453076 -37.537644) (xy 284.37459 -37.592508)
			(xy 284.364959 -37.600129) (xy 284.353681 -37.621901) (xy 284.353 -37.634164) (xy 284.353 -38.889686)
			(xy 284.353572 -38.900129) (xy 284.361975 -38.919259) (xy 284.369256 -38.92677) (xy 284.431994 -38.984936)
			(xy 284.451806 -38.991794) (xy 284.462474 -38.991032) (xy 284.479529 -38.989818) (xy 284.513702 -38.988547)
			(xy 284.5308 -38.988492) (xy 284.573148 -38.988996) (xy 284.657462 -38.997047) (xy 284.740628 -39.013076)
			(xy 284.821895 -39.036937) (xy 284.900525 -39.068416) (xy 284.975806 -39.107227) (xy 285.047058 -39.153017)
			(xy 285.113634 -39.205373) (xy 285.174932 -39.263821) (xy 285.230397 -39.327831) (xy 285.279526 -39.396823)
			(xy 285.321875 -39.470173) (xy 285.357059 -39.547216) (xy 285.384761 -39.627255) (xy 285.404729 -39.709564)
			(xy 285.416782 -39.793399) (xy 285.420813 -39.878) (xy 285.418795 -39.920361) (xy 285.876742 -39.920361)
			(xy 285.876742 -39.835639) (xy 285.884795 -39.751302) (xy 285.900829 -39.668112) (xy 285.924697 -39.586822)
			(xy 285.956185 -39.50817) (xy 285.995007 -39.432867) (xy 286.04081 -39.361595) (xy 286.093181 -39.294999)
			(xy 286.151646 -39.233684) (xy 286.215674 -39.178203) (xy 286.284686 -39.12906) (xy 286.358056 -39.0867)
			(xy 286.435121 -39.051505) (xy 286.515183 -39.023796) (xy 286.597516 -39.003822) (xy 286.681375 -38.991765)
			(xy 286.766 -38.987734) (xy 286.850625 -38.991765) (xy 286.934484 -39.003822) (xy 287.016817 -39.023796)
			(xy 287.096879 -39.051505) (xy 287.173944 -39.0867) (xy 287.247314 -39.12906) (xy 287.316326 -39.178203)
			(xy 287.380354 -39.233684) (xy 287.438819 -39.294999) (xy 287.49119 -39.361595) (xy 287.536993 -39.432867)
			(xy 287.575815 -39.50817) (xy 287.607303 -39.586822) (xy 287.631171 -39.668112) (xy 287.647205 -39.751302)
			(xy 287.655258 -39.835639) (xy 287.655762 -39.878) (xy 287.655258 -39.920361) (xy 287.647205 -40.004698)
			(xy 287.631171 -40.087888) (xy 287.607303 -40.169178) (xy 287.575815 -40.24783) (xy 287.536993 -40.323133)
			(xy 287.49119 -40.394405) (xy 287.438819 -40.461001) (xy 287.380354 -40.522316) (xy 287.316326 -40.577797)
			(xy 287.247314 -40.62694) (xy 287.173944 -40.6693) (xy 287.096879 -40.704495) (xy 287.016817 -40.732204)
			(xy 286.934484 -40.752178) (xy 286.850625 -40.764235) (xy 286.766 -40.768267) (xy 286.681375 -40.764235)
			(xy 286.597516 -40.752178) (xy 286.515183 -40.732204) (xy 286.435121 -40.704495) (xy 286.358056 -40.6693)
			(xy 286.284686 -40.62694) (xy 286.215674 -40.577797) (xy 286.151646 -40.522316) (xy 286.093181 -40.461001)
			(xy 286.04081 -40.394405) (xy 285.995007 -40.323133) (xy 285.956185 -40.24783) (xy 285.924697 -40.169178)
			(xy 285.900829 -40.087888) (xy 285.884795 -40.004698) (xy 285.876742 -39.920361) (xy 285.418795 -39.920361)
			(xy 285.416782 -39.962601) (xy 285.404729 -40.046436) (xy 285.384761 -40.128745) (xy 285.357059 -40.208784)
			(xy 285.321875 -40.285827) (xy 285.279526 -40.359177) (xy 285.230397 -40.428169) (xy 285.174932 -40.492179)
			(xy 285.113634 -40.550627) (xy 285.047058 -40.602983) (xy 284.975806 -40.648773) (xy 284.900525 -40.687584)
			(xy 284.821895 -40.719063) (xy 284.740628 -40.742924) (xy 284.657462 -40.758953) (xy 284.573148 -40.767004)
			(xy 284.5308 -40.767508) (xy 284.489377 -40.767033) (xy 284.406888 -40.75933) (xy 284.325474 -40.743992)
			(xy 284.245838 -40.72115) (xy 284.168671 -40.691003) (xy 284.094641 -40.653812) (xy 284.02439 -40.609899)
			(xy 283.958525 -40.559644) (xy 283.897619 -40.503484) (xy 283.842198 -40.441904) (xy 283.792742 -40.375438)
			(xy 283.770832 -40.34028) (xy 283.770832 -40.340026) (xy 283.764335 -40.330473) (xy 283.744891 -40.31804)
			(xy 283.733494 -40.31615) (xy 283.654246 -40.306752) (xy 283.642654 -40.305866) (xy 283.620696 -40.313421)
			(xy 283.612082 -40.32123) (xy 282.93822 -40.995092) (xy 282.932077 -41.001786) (xy 282.924549 -41.018307)
			(xy 282.923242 -41.036416) (xy 282.928319 -41.053847) (xy 282.933394 -41.061386) (xy 282.963493 -41.103054)
			(xy 283.014931 -41.192051) (xy 283.03601 -41.238932) (xy 283.040362 -41.247999) (xy 283.054765 -41.262014)
			(xy 283.06395 -41.26611) (xy 283.104068 -41.282646) (xy 283.181181 -41.322447) (xy 283.25405 -41.36957)
			(xy 283.321982 -41.423567) (xy 283.384331 -41.483925) (xy 283.440505 -41.550069) (xy 283.489968 -41.62137)
			(xy 283.53225 -41.69715) (xy 283.56695 -41.776689) (xy 283.58084 -41.817798) (xy 283.584278 -41.826907)
			(xy 283.596767 -41.841824) (xy 283.613899 -41.851044) (xy 283.623512 -41.852596) (xy 283.71546 -41.86301)
			(xy 283.72525 -41.863635) (xy 283.744116 -41.858321) (xy 283.759622 -41.846332) (xy 283.76499 -41.838118)
			(xy 283.786751 -41.802287) (xy 283.836041 -41.73447) (xy 283.891492 -41.671592) (xy 283.952614 -41.614209)
			(xy 284.018863 -41.562832) (xy 284.089652 -41.517916) (xy 284.164353 -41.479859) (xy 284.242304 -41.448999)
			(xy 284.322812 -41.42561) (xy 284.405163 -41.409899) (xy 284.488628 -41.402006) (xy 284.530546 -41.401492)
			(xy 284.5308 -41.401492) (xy 284.573148 -41.401996) (xy 284.657462 -41.410047) (xy 284.740628 -41.426076)
			(xy 284.821895 -41.449937) (xy 284.900525 -41.481416) (xy 284.975806 -41.520227) (xy 285.047058 -41.566017)
			(xy 285.113634 -41.618373) (xy 285.174932 -41.676821) (xy 285.230397 -41.740831) (xy 285.279526 -41.809823)
			(xy 285.321875 -41.883173) (xy 285.357059 -41.960216) (xy 285.384761 -42.040255) (xy 285.404729 -42.122564)
			(xy 285.416782 -42.206399) (xy 285.420813 -42.291) (xy 285.418795 -42.333361) (xy 285.876742 -42.333361)
			(xy 285.876742 -42.248639) (xy 285.884795 -42.164302) (xy 285.900829 -42.081112) (xy 285.924697 -41.999822)
			(xy 285.956185 -41.92117) (xy 285.995007 -41.845867) (xy 286.04081 -41.774595) (xy 286.093181 -41.707999)
			(xy 286.151646 -41.646684) (xy 286.215674 -41.591203) (xy 286.284686 -41.54206) (xy 286.358056 -41.4997)
			(xy 286.435121 -41.464505) (xy 286.515183 -41.436796) (xy 286.597516 -41.416822) (xy 286.681375 -41.404765)
			(xy 286.766 -41.400734) (xy 286.850625 -41.404765) (xy 286.934484 -41.416822) (xy 287.016817 -41.436796)
			(xy 287.096879 -41.464505) (xy 287.173944 -41.4997) (xy 287.247314 -41.54206) (xy 287.316326 -41.591203)
			(xy 287.380354 -41.646684) (xy 287.438819 -41.707999) (xy 287.49119 -41.774595) (xy 287.536993 -41.845867)
			(xy 287.575815 -41.92117) (xy 287.607303 -41.999822) (xy 287.631171 -42.081112) (xy 287.647205 -42.164302)
			(xy 287.655258 -42.248639) (xy 287.655762 -42.291) (xy 287.655258 -42.333361) (xy 287.647205 -42.417698)
			(xy 287.631171 -42.500888) (xy 287.607303 -42.582178) (xy 287.575815 -42.66083) (xy 287.536993 -42.736133)
			(xy 287.49119 -42.807405) (xy 287.438819 -42.874001) (xy 287.380354 -42.935316) (xy 287.316326 -42.990797)
			(xy 287.247314 -43.03994) (xy 287.173944 -43.0823) (xy 287.096879 -43.117495) (xy 287.016817 -43.145204)
			(xy 286.934484 -43.165178) (xy 286.850625 -43.177235) (xy 286.766 -43.181267) (xy 286.681375 -43.177235)
			(xy 286.597516 -43.165178) (xy 286.515183 -43.145204) (xy 286.435121 -43.117495) (xy 286.358056 -43.0823)
			(xy 286.284686 -43.03994) (xy 286.215674 -42.990797) (xy 286.151646 -42.935316) (xy 286.093181 -42.874001)
			(xy 286.04081 -42.807405) (xy 285.995007 -42.736133) (xy 285.956185 -42.66083) (xy 285.924697 -42.582178)
			(xy 285.900829 -42.500888) (xy 285.884795 -42.417698) (xy 285.876742 -42.333361) (xy 285.418795 -42.333361)
			(xy 285.416782 -42.375601) (xy 285.404729 -42.459436) (xy 285.384761 -42.541745) (xy 285.357059 -42.621784)
			(xy 285.321875 -42.698827) (xy 285.279526 -42.772177) (xy 285.230397 -42.841169) (xy 285.174932 -42.905179)
			(xy 285.113634 -42.963627) (xy 285.047058 -43.015983) (xy 284.975806 -43.061773) (xy 284.900525 -43.100584)
			(xy 284.821895 -43.132063) (xy 284.740628 -43.155924) (xy 284.657462 -43.171953) (xy 284.573148 -43.180004)
			(xy 284.5308 -43.180508) (xy 284.487797 -43.179984) (xy 284.402194 -43.171675) (xy 284.317792 -43.155144)
			(xy 284.235379 -43.130546) (xy 284.155724 -43.09811) (xy 284.079571 -43.058139) (xy 284.007631 -43.011005)
			(xy 283.940575 -42.95715) (xy 283.879028 -42.897075) (xy 283.823566 -42.831341) (xy 283.774706 -42.760562)
			(xy 283.732904 -42.685399) (xy 283.69855 -42.606552) (xy 283.684726 -42.565828) (xy 283.681294 -42.556709)
			(xy 283.668812 -42.541769) (xy 283.65168 -42.532523) (xy 283.642054 -42.53103) (xy 283.550106 -42.520616)
			(xy 283.540308 -42.519978) (xy 283.521417 -42.525271) (xy 283.505877 -42.537245) (xy 283.500576 -42.545508)
			(xy 283.478757 -42.581444) (xy 283.429319 -42.64945) (xy 283.373681 -42.712484) (xy 283.34335 -42.741596)
			(xy 283.335729 -42.749475) (xy 283.327452 -42.769749) (xy 283.327348 -42.780712) (xy 283.330396 -42.857674)
			(xy 283.331355 -42.868564) (xy 283.341244 -42.888036) (xy 283.349446 -42.895266) (xy 283.38386 -42.923345)
			(xy 283.447497 -42.985314) (xy 283.50464 -43.053317) (xy 283.554721 -43.126677) (xy 283.59724 -43.204664)
			(xy 283.631775 -43.2865) (xy 283.65798 -43.371371) (xy 283.675596 -43.458431) (xy 283.684447 -43.546814)
			(xy 283.68498 -43.591226) (xy 283.684504 -43.632332) (xy 283.676918 -43.714194) (xy 283.667571 -43.7642)
			(xy 287.730188 -43.7642) (xy 287.734218 -43.679599) (xy 287.746271 -43.595764) (xy 287.766239 -43.513455)
			(xy 287.793941 -43.433416) (xy 287.829125 -43.356373) (xy 287.871474 -43.283023) (xy 287.920603 -43.214031)
			(xy 287.976068 -43.150021) (xy 288.037366 -43.091573) (xy 288.103942 -43.039217) (xy 288.175194 -42.993427)
			(xy 288.250475 -42.954616) (xy 288.329105 -42.923137) (xy 288.410372 -42.899276) (xy 288.493538 -42.883247)
			(xy 288.577852 -42.875196) (xy 288.6202 -42.874692) (xy 288.620708 -42.874692) (xy 288.659456 -42.875126)
			(xy 288.736657 -42.881887) (xy 288.812977 -42.895339) (xy 288.887836 -42.915381) (xy 288.960669 -42.94186)
			(xy 289.03092 -42.974576) (xy 289.0647 -42.993564) (xy 289.072574 -42.997723) (xy 289.0901 -43.000817)
			(xy 289.107626 -42.997723) (xy 289.1155 -42.993564) (xy 289.149289 -42.974593) (xy 289.219539 -42.941877)
			(xy 289.29237 -42.915396) (xy 289.367228 -42.895351) (xy 289.443545 -42.881893) (xy 289.520745 -42.875125)
			(xy 289.559492 -42.874692) (xy 289.56 -42.874692) (xy 289.602348 -42.875196) (xy 289.686662 -42.883247)
			(xy 289.769828 -42.899276) (xy 289.851095 -42.923137) (xy 289.929725 -42.954616) (xy 290.005006 -42.993427)
			(xy 290.076258 -43.039217) (xy 290.142834 -43.091573) (xy 290.204132 -43.150021) (xy 290.259597 -43.214031)
			(xy 290.308726 -43.283023) (xy 290.351075 -43.356373) (xy 290.386259 -43.433416) (xy 290.413961 -43.513455)
			(xy 290.433929 -43.595764) (xy 290.445982 -43.679599) (xy 290.450013 -43.7642) (xy 290.445982 -43.848801)
			(xy 290.433929 -43.932636) (xy 290.413961 -44.014945) (xy 290.386259 -44.094984) (xy 290.351075 -44.172027)
			(xy 290.308726 -44.245377) (xy 290.259597 -44.314369) (xy 290.204132 -44.378379) (xy 290.142834 -44.436827)
			(xy 290.076258 -44.489183) (xy 290.005006 -44.534973) (xy 289.929725 -44.573784) (xy 289.851095 -44.605263)
			(xy 289.769828 -44.629124) (xy 289.686662 -44.645153) (xy 289.602348 -44.653204) (xy 289.56 -44.653708)
			(xy 289.559492 -44.653708) (xy 289.520744 -44.653274) (xy 289.443543 -44.646513) (xy 289.367223 -44.633061)
			(xy 289.292364 -44.613019) (xy 289.219531 -44.58654) (xy 289.14928 -44.553824) (xy 289.1155 -44.534836)
			(xy 289.107626 -44.530677) (xy 289.0901 -44.527583) (xy 289.072574 -44.530677) (xy 289.0647 -44.534836)
			(xy 289.030911 -44.553807) (xy 288.960661 -44.586523) (xy 288.88783 -44.613004) (xy 288.812972 -44.633049)
			(xy 288.736655 -44.646507) (xy 288.659455 -44.653275) (xy 288.620708 -44.653708) (xy 288.6202 -44.653708)
			(xy 288.577852 -44.653204) (xy 288.493538 -44.645153) (xy 288.410372 -44.629124) (xy 288.329105 -44.605263)
			(xy 288.250475 -44.573784) (xy 288.175194 -44.534973) (xy 288.103942 -44.489183) (xy 288.037366 -44.436827)
			(xy 287.976068 -44.378379) (xy 287.920603 -44.314369) (xy 287.871474 -44.245377) (xy 287.829125 -44.172027)
			(xy 287.793941 -44.094984) (xy 287.766239 -44.014945) (xy 287.746271 -43.932636) (xy 287.734218 -43.848801)
			(xy 287.730188 -43.7642) (xy 283.667571 -43.7642) (xy 283.661812 -43.795007) (xy 283.639316 -43.874082)
			(xy 283.609621 -43.950744) (xy 283.572981 -44.024341) (xy 283.529708 -44.094243) (xy 283.480171 -44.159855)
			(xy 283.424792 -44.220618) (xy 283.364045 -44.276014) (xy 283.298446 -44.325569) (xy 283.228556 -44.368861)
			(xy 283.154969 -44.405522) (xy 283.078315 -44.435238) (xy 282.999247 -44.457756) (xy 282.918438 -44.472884)
			(xy 282.836578 -44.480493) (xy 282.795472 -44.480988) (xy 282.751643 -44.480455) (xy 282.664412 -44.471817)
			(xy 282.578454 -44.454637) (xy 282.494603 -44.429082) (xy 282.413675 -44.3954) (xy 282.336453 -44.353918)
			(xy 282.263688 -44.305039) (xy 282.22956 -44.277534) (xy 282.229052 -44.277026) (xy 282.221408 -44.271344)
			(xy 282.203266 -44.265589) (xy 282.193746 -44.26585) (xy 282.113736 -44.271438) (xy 282.095956 -44.280074)
			(xy 282.089606 -44.287186) (xy 282.061564 -44.317242) (xy 282.000814 -44.372627) (xy 281.935214 -44.42217)
			(xy 281.865323 -44.465451) (xy 281.791737 -44.5021) (xy 281.715084 -44.531804) (xy 281.636018 -44.554311)
			(xy 281.555213 -44.569427) (xy 281.473357 -44.577025) (xy 281.432254 -44.577508) (xy 281.432 -44.577508)
			(xy 281.390898 -44.577033) (xy 281.309043 -44.569448) (xy 281.228238 -44.554343) (xy 281.149171 -44.531847)
			(xy 281.072517 -44.502151) (xy 280.99893 -44.465509) (xy 280.929038 -44.422234) (xy 280.863437 -44.372694)
			(xy 280.802687 -44.317313) (xy 280.747306 -44.256563) (xy 280.697766 -44.190962) (xy 280.654491 -44.12107)
			(xy 280.617849 -44.047483) (xy 280.588153 -43.970829) (xy 280.565657 -43.891762) (xy 280.550552 -43.810957)
			(xy 280.542967 -43.729102) (xy 280.542492 -43.688) (xy 280.542492 -43.687492) (xy 280.542981 -43.646377)
			(xy 280.550597 -43.5645) (xy 280.565734 -43.483674) (xy 280.588264 -43.40459) (xy 280.617995 -43.327922)
			(xy 280.654673 -43.254325) (xy 280.697986 -43.184425) (xy 280.747562 -43.11882) (xy 280.802981 -43.058069)
			(xy 280.863768 -43.00269) (xy 280.896314 -42.977562) (xy 280.903869 -42.97136) (xy 280.913942 -42.954631)
			(xy 280.915872 -42.94505) (xy 280.920698 -42.914824) (xy 280.921785 -42.905078) (xy 280.917356 -42.885993)
			(xy 280.912062 -42.87774) (xy 280.886504 -42.840299) (xy 280.84228 -42.761159) (xy 280.806328 -42.677935)
			(xy 280.77902 -42.591487) (xy 280.760639 -42.502712) (xy 280.751375 -42.412529) (xy 280.750772 -42.3672)
			(xy 280.751297 -42.323383) (xy 280.759913 -42.236174) (xy 280.777061 -42.150234) (xy 280.802575 -42.066396)
			(xy 280.836208 -41.985473) (xy 280.877634 -41.908249) (xy 280.926451 -41.835472) (xy 280.982187 -41.767846)
			(xy 281.044301 -41.706028) (xy 281.112193 -41.650616) (xy 281.185203 -41.602147) (xy 281.262624 -41.561091)
			(xy 281.302968 -41.543986) (xy 281.311316 -41.540141) (xy 281.324759 -41.527627) (xy 281.332923 -41.511176)
			(xy 281.33421 -41.502076) (xy 281.339544 -41.46042) (xy 281.340052 -41.45661) (xy 281.340052 -41.4528)
			(xy 281.339632 -41.442782) (xy 281.33196 -41.424274) (xy 281.317786 -41.410113) (xy 281.29927 -41.402459)
			(xy 281.289252 -41.402) (xy 277.397972 -41.402) (xy 277.396448 -41.402) (xy 277.368 -41.402508) (xy 277.339552 -41.402)
			(xy 276.702774 -41.402) (xy 276.691758 -41.402546) (xy 276.671751 -41.411771) (xy 276.664166 -41.41978)
			(xy 276.606762 -41.48709) (xy 276.600666 -41.508172) (xy 276.602444 -41.519094) (xy 276.607429 -41.553101)
			(xy 276.612772 -41.621631) (xy 276.613112 -41.656) (xy 276.612574 -41.699794) (xy 276.603944 -41.786957)
			(xy 276.586795 -41.872851) (xy 276.561295 -41.956645) (xy 276.52769 -42.037531) (xy 276.507448 -42.07637)
			(xy 276.502027 -42.087836) (xy 276.502027 -42.113164) (xy 276.507448 -42.12463) (xy 276.527694 -42.163469)
			(xy 276.561322 -42.244348) (xy 276.586835 -42.328142) (xy 276.603985 -42.414038) (xy 276.612607 -42.501204)
			(xy 276.613112 -42.545) (xy 276.612574 -42.588794) (xy 276.603944 -42.675957) (xy 276.586795 -42.761851)
			(xy 276.561295 -42.845645) (xy 276.52769 -42.926531) (xy 276.507448 -42.96537) (xy 276.502027 -42.976836)
			(xy 276.502027 -43.002164) (xy 276.507448 -43.01363) (xy 276.527694 -43.052469) (xy 276.561322 -43.133348)
			(xy 276.586835 -43.217142) (xy 276.603985 -43.303038) (xy 276.612607 -43.390204) (xy 276.613112 -43.434)
			(xy 276.612574 -43.477794) (xy 276.603944 -43.564957) (xy 276.586795 -43.650851) (xy 276.561295 -43.734645)
			(xy 276.52769 -43.815531) (xy 276.507448 -43.85437) (xy 276.502027 -43.865836) (xy 276.502027 -43.891164)
			(xy 276.507448 -43.90263) (xy 276.527694 -43.941469) (xy 276.561322 -44.022348) (xy 276.586835 -44.106142)
			(xy 276.603985 -44.192038) (xy 276.612607 -44.279204) (xy 276.613112 -44.323) (xy 276.612608 -44.365361)
			(xy 276.604555 -44.449698) (xy 276.588521 -44.532888) (xy 276.564653 -44.614178) (xy 276.533165 -44.69283)
			(xy 276.494343 -44.768133) (xy 276.44854 -44.839405) (xy 276.396169 -44.906001) (xy 276.337704 -44.967316)
			(xy 276.273676 -45.022797) (xy 276.204664 -45.07194) (xy 276.131294 -45.1143) (xy 276.054229 -45.149495)
			(xy 275.974167 -45.177204) (xy 275.891834 -45.197178) (xy 275.807975 -45.209235) (xy 275.72335 -45.213267)
			(xy 275.638725 -45.209235) (xy 275.554866 -45.197178) (xy 275.472533 -45.177204) (xy 275.392471 -45.149495)
			(xy 275.315406 -45.1143) (xy 275.242036 -45.07194) (xy 275.173024 -45.022797) (xy 275.108996 -44.967316)
			(xy 275.050531 -44.906001) (xy 274.99816 -44.839405) (xy 274.952357 -44.768133) (xy 274.913535 -44.69283)
			(xy 274.882047 -44.614178) (xy 274.858179 -44.532888) (xy 274.842145 -44.449698) (xy 274.834092 -44.365361)
			(xy 274.833588 -44.323) (xy 274.834126 -44.279206) (xy 274.842756 -44.192043) (xy 274.859905 -44.106149)
			(xy 274.885405 -44.022355) (xy 274.91901 -43.941469) (xy 274.939252 -43.90263) (xy 274.944673 -43.891164)
			(xy 274.944673 -43.865836) (xy 274.939252 -43.85437) (xy 274.919006 -43.815531) (xy 274.885378 -43.734652)
			(xy 274.859865 -43.650858) (xy 274.842715 -43.564962) (xy 274.834093 -43.477796) (xy 274.833588 -43.434)
			(xy 274.834126 -43.390206) (xy 274.842756 -43.303043) (xy 274.859905 -43.217149) (xy 274.885405 -43.133355)
			(xy 274.91901 -43.052469) (xy 274.939252 -43.01363) (xy 274.944673 -43.002164) (xy 274.944673 -42.976836)
			(xy 274.939252 -42.96537) (xy 274.919006 -42.926531) (xy 274.885378 -42.845652) (xy 274.859865 -42.761858)
			(xy 274.842715 -42.675962) (xy 274.834093 -42.588796) (xy 274.833588 -42.545) (xy 274.834126 -42.501206)
			(xy 274.842756 -42.414043) (xy 274.859905 -42.328149) (xy 274.885405 -42.244355) (xy 274.91901 -42.163469)
			(xy 274.939252 -42.12463) (xy 274.944673 -42.113164) (xy 274.944673 -42.087836) (xy 274.939252 -42.07637)
			(xy 274.919006 -42.037531) (xy 274.885378 -41.956652) (xy 274.859865 -41.872858) (xy 274.842715 -41.786962)
			(xy 274.834093 -41.699796) (xy 274.833588 -41.656) (xy 274.833935 -41.621631) (xy 274.839272 -41.553101)
			(xy 274.844256 -41.519094) (xy 274.846034 -41.508172) (xy 274.839938 -41.48709) (xy 274.782534 -41.41978)
			(xy 274.774963 -41.411753) (xy 274.754947 -41.402523) (xy 274.743926 -41.402) (xy 274.297394 -41.402)
			(xy 274.287324 -41.402424) (xy 274.268721 -41.41014) (xy 274.261326 -41.416986) (xy 272.302986 -43.375326)
			(xy 272.296134 -43.382722) (xy 272.288396 -43.401321) (xy 272.288 -43.411394) (xy 272.288 -44.499276)
			(xy 272.288456 -44.509115) (xy 272.295883 -44.527336) (xy 272.309646 -44.5414) (xy 272.31848 -44.545758)
			(xy 272.357596 -44.563453) (xy 272.432558 -44.605316) (xy 272.503138 -44.654206) (xy 272.568679 -44.709669)
			(xy 272.628571 -44.771188) (xy 272.682257 -44.838193) (xy 272.729238 -44.910058) (xy 272.769076 -44.986115)
			(xy 272.8014 -45.065656) (xy 272.825911 -45.147942) (xy 272.842379 -45.232207) (xy 272.850652 -45.317667)
			(xy 272.850652 -45.403525) (xy 272.84238 -45.488985) (xy 272.825913 -45.57325) (xy 272.807412 -45.635361)
			(xy 276.992838 -45.635361) (xy 276.992838 -45.550639) (xy 277.000891 -45.466302) (xy 277.016925 -45.383112)
			(xy 277.040793 -45.301822) (xy 277.072281 -45.22317) (xy 277.111103 -45.147867) (xy 277.156906 -45.076595)
			(xy 277.209277 -45.009999) (xy 277.267742 -44.948684) (xy 277.33177 -44.893203) (xy 277.400782 -44.84406)
			(xy 277.474152 -44.8017) (xy 277.551217 -44.766505) (xy 277.631279 -44.738796) (xy 277.713612 -44.718822)
			(xy 277.797471 -44.706765) (xy 277.882096 -44.702734) (xy 277.966721 -44.706765) (xy 278.05058 -44.718822)
			(xy 278.132913 -44.738796) (xy 278.212975 -44.766505) (xy 278.29004 -44.8017) (xy 278.36341 -44.84406)
			(xy 278.404558 -44.873361) (xy 283.641542 -44.873361) (xy 283.641542 -44.788639) (xy 283.649595 -44.704302)
			(xy 283.665629 -44.621112) (xy 283.689497 -44.539822) (xy 283.720985 -44.46117) (xy 283.759807 -44.385867)
			(xy 283.80561 -44.314595) (xy 283.857981 -44.247999) (xy 283.916446 -44.186684) (xy 283.980474 -44.131203)
			(xy 284.049486 -44.08206) (xy 284.122856 -44.0397) (xy 284.199921 -44.004505) (xy 284.279983 -43.976796)
			(xy 284.362316 -43.956822) (xy 284.446175 -43.944765) (xy 284.5308 -43.940734) (xy 284.615425 -43.944765)
			(xy 284.699284 -43.956822) (xy 284.781617 -43.976796) (xy 284.861679 -44.004505) (xy 284.938744 -44.0397)
			(xy 285.012114 -44.08206) (xy 285.081126 -44.131203) (xy 285.145154 -44.186684) (xy 285.203619 -44.247999)
			(xy 285.25599 -44.314595) (xy 285.301793 -44.385867) (xy 285.340615 -44.46117) (xy 285.372103 -44.539822)
			(xy 285.395971 -44.621112) (xy 285.412005 -44.704302) (xy 285.420058 -44.788639) (xy 285.420562 -44.831)
			(xy 285.420058 -44.873361) (xy 285.876742 -44.873361) (xy 285.876742 -44.788639) (xy 285.884795 -44.704302)
			(xy 285.900829 -44.621112) (xy 285.924697 -44.539822) (xy 285.956185 -44.46117) (xy 285.995007 -44.385867)
			(xy 286.04081 -44.314595) (xy 286.093181 -44.247999) (xy 286.151646 -44.186684) (xy 286.215674 -44.131203)
			(xy 286.284686 -44.08206) (xy 286.358056 -44.0397) (xy 286.435121 -44.004505) (xy 286.515183 -43.976796)
			(xy 286.597516 -43.956822) (xy 286.681375 -43.944765) (xy 286.766 -43.940734) (xy 286.850625 -43.944765)
			(xy 286.934484 -43.956822) (xy 287.016817 -43.976796) (xy 287.096879 -44.004505) (xy 287.173944 -44.0397)
			(xy 287.247314 -44.08206) (xy 287.316326 -44.131203) (xy 287.380354 -44.186684) (xy 287.438819 -44.247999)
			(xy 287.49119 -44.314595) (xy 287.536993 -44.385867) (xy 287.575815 -44.46117) (xy 287.607303 -44.539822)
			(xy 287.631171 -44.621112) (xy 287.647205 -44.704302) (xy 287.655258 -44.788639) (xy 287.655762 -44.831)
			(xy 287.655258 -44.873361) (xy 287.647205 -44.957698) (xy 287.631171 -45.040888) (xy 287.607303 -45.122178)
			(xy 287.575815 -45.20083) (xy 287.536993 -45.276133) (xy 287.49119 -45.347405) (xy 287.438819 -45.414001)
			(xy 287.380354 -45.475316) (xy 287.342218 -45.508361) (xy 293.242742 -45.508361) (xy 293.242742 -45.423639)
			(xy 293.250795 -45.339302) (xy 293.266829 -45.256112) (xy 293.290697 -45.174822) (xy 293.322185 -45.09617)
			(xy 293.361007 -45.020867) (xy 293.40681 -44.949595) (xy 293.459181 -44.882999) (xy 293.517646 -44.821684)
			(xy 293.581674 -44.766203) (xy 293.650686 -44.71706) (xy 293.724056 -44.6747) (xy 293.801121 -44.639505)
			(xy 293.881183 -44.611796) (xy 293.963516 -44.591822) (xy 294.047375 -44.579765) (xy 294.132 -44.575734)
			(xy 294.216625 -44.579765) (xy 294.300484 -44.591822) (xy 294.382817 -44.611796) (xy 294.462879 -44.639505)
			(xy 294.539944 -44.6747) (xy 294.613314 -44.71706) (xy 294.682326 -44.766203) (xy 294.746354 -44.821684)
			(xy 294.804819 -44.882999) (xy 294.85719 -44.949595) (xy 294.902993 -45.020867) (xy 294.941815 -45.09617)
			(xy 294.973303 -45.174822) (xy 294.997171 -45.256112) (xy 295.013205 -45.339302) (xy 295.021258 -45.423639)
			(xy 295.021762 -45.466) (xy 295.021258 -45.508361) (xy 295.013205 -45.592698) (xy 294.997171 -45.675888)
			(xy 294.973303 -45.757178) (xy 294.941815 -45.83583) (xy 294.902993 -45.911133) (xy 294.85719 -45.982405)
			(xy 294.804819 -46.049001) (xy 294.746354 -46.110316) (xy 294.682326 -46.165797) (xy 294.613314 -46.21494)
			(xy 294.539944 -46.2573) (xy 294.462879 -46.292495) (xy 294.382817 -46.320204) (xy 294.300484 -46.340178)
			(xy 294.216625 -46.352235) (xy 294.132 -46.356267) (xy 294.047375 -46.352235) (xy 293.963516 -46.340178)
			(xy 293.881183 -46.320204) (xy 293.801121 -46.292495) (xy 293.724056 -46.2573) (xy 293.650686 -46.21494)
			(xy 293.581674 -46.165797) (xy 293.517646 -46.110316) (xy 293.459181 -46.049001) (xy 293.40681 -45.982405)
			(xy 293.361007 -45.911133) (xy 293.322185 -45.83583) (xy 293.290697 -45.757178) (xy 293.266829 -45.675888)
			(xy 293.250795 -45.592698) (xy 293.242742 -45.508361) (xy 287.342218 -45.508361) (xy 287.316326 -45.530797)
			(xy 287.247314 -45.57994) (xy 287.173944 -45.6223) (xy 287.096879 -45.657495) (xy 287.016817 -45.685204)
			(xy 286.934484 -45.705178) (xy 286.850625 -45.717235) (xy 286.766 -45.721267) (xy 286.681375 -45.717235)
			(xy 286.597516 -45.705178) (xy 286.515183 -45.685204) (xy 286.435121 -45.657495) (xy 286.358056 -45.6223)
			(xy 286.284686 -45.57994) (xy 286.215674 -45.530797) (xy 286.151646 -45.475316) (xy 286.093181 -45.414001)
			(xy 286.04081 -45.347405) (xy 285.995007 -45.276133) (xy 285.956185 -45.20083) (xy 285.924697 -45.122178)
			(xy 285.900829 -45.040888) (xy 285.884795 -44.957698) (xy 285.876742 -44.873361) (xy 285.420058 -44.873361)
			(xy 285.412005 -44.957698) (xy 285.395971 -45.040888) (xy 285.372103 -45.122178) (xy 285.340615 -45.20083)
			(xy 285.301793 -45.276133) (xy 285.25599 -45.347405) (xy 285.203619 -45.414001) (xy 285.145154 -45.475316)
			(xy 285.081126 -45.530797) (xy 285.012114 -45.57994) (xy 284.938744 -45.6223) (xy 284.861679 -45.657495)
			(xy 284.781617 -45.685204) (xy 284.699284 -45.705178) (xy 284.615425 -45.717235) (xy 284.5308 -45.721267)
			(xy 284.446175 -45.717235) (xy 284.362316 -45.705178) (xy 284.279983 -45.685204) (xy 284.199921 -45.657495)
			(xy 284.122856 -45.6223) (xy 284.049486 -45.57994) (xy 283.980474 -45.530797) (xy 283.916446 -45.475316)
			(xy 283.857981 -45.414001) (xy 283.80561 -45.347405) (xy 283.759807 -45.276133) (xy 283.720985 -45.20083)
			(xy 283.689497 -45.122178) (xy 283.665629 -45.040888) (xy 283.649595 -44.957698) (xy 283.641542 -44.873361)
			(xy 278.404558 -44.873361) (xy 278.432422 -44.893203) (xy 278.49645 -44.948684) (xy 278.554915 -45.009999)
			(xy 278.607286 -45.076595) (xy 278.653089 -45.147867) (xy 278.691911 -45.22317) (xy 278.723399 -45.301822)
			(xy 278.747267 -45.383112) (xy 278.763301 -45.466302) (xy 278.771354 -45.550639) (xy 278.771858 -45.593)
			(xy 278.771354 -45.635361) (xy 278.763301 -45.719698) (xy 278.747267 -45.802888) (xy 278.723399 -45.884178)
			(xy 278.691911 -45.96283) (xy 278.653089 -46.038133) (xy 278.607286 -46.109405) (xy 278.554915 -46.176001)
			(xy 278.49645 -46.237316) (xy 278.432422 -46.292797) (xy 278.36341 -46.34194) (xy 278.29004 -46.3843)
			(xy 278.212975 -46.419495) (xy 278.132913 -46.447204) (xy 278.05058 -46.467178) (xy 277.966721 -46.479235)
			(xy 277.882096 -46.483267) (xy 277.797471 -46.479235) (xy 277.713612 -46.467178) (xy 277.631279 -46.447204)
			(xy 277.551217 -46.419495) (xy 277.474152 -46.3843) (xy 277.400782 -46.34194) (xy 277.33177 -46.292797)
			(xy 277.267742 -46.237316) (xy 277.209277 -46.176001) (xy 277.156906 -46.109405) (xy 277.111103 -46.038133)
			(xy 277.072281 -45.96283) (xy 277.040793 -45.884178) (xy 277.016925 -45.802888) (xy 277.000891 -45.719698)
			(xy 276.992838 -45.635361) (xy 272.807412 -45.635361) (xy 272.801403 -45.655536) (xy 272.769079 -45.735078)
			(xy 272.729242 -45.811136) (xy 272.682262 -45.883001) (xy 272.628576 -45.950005) (xy 272.568685 -46.011526)
			(xy 272.503144 -46.066989) (xy 272.432565 -46.11588) (xy 272.357604 -46.157743) (xy 272.31848 -46.175422)
			(xy 272.309646 -46.179778) (xy 272.295898 -46.193856) (xy 272.28844 -46.212067) (xy 272.288 -46.221904)
			(xy 272.288 -46.882) (xy 273.302784 -46.882) (xy 273.306814 -46.79738) (xy 273.318871 -46.713525)
			(xy 273.338844 -46.631197) (xy 273.366552 -46.55114) (xy 273.401744 -46.474079) (xy 273.444102 -46.400713)
			(xy 273.493243 -46.331705) (xy 273.54872 -46.26768) (xy 273.610032 -46.209219) (xy 273.676624 -46.156851)
			(xy 273.747892 -46.11105) (xy 273.823191 -46.072231) (xy 273.901839 -46.040745) (xy 273.983124 -46.016877)
			(xy 274.066309 -46.000845) (xy 274.150642 -45.992792) (xy 274.193 -45.992288) (xy 274.236489 -45.992841)
			(xy 274.323051 -46.001349) (xy 274.408369 -46.018263) (xy 274.49163 -46.043422) (xy 274.572038 -46.076587)
			(xy 274.648826 -46.11744) (xy 274.72126 -46.165591) (xy 274.78865 -46.220581) (xy 274.819872 -46.25086)
			(xy 274.820126 -46.251114) (xy 274.82751 -46.257689) (xy 274.845809 -46.265133) (xy 274.855686 -46.265592)
			(xy 274.927314 -46.265592) (xy 274.937197 -46.265171) (xy 274.955496 -46.257705) (xy 274.962874 -46.251114)
			(xy 274.963128 -46.25086) (xy 274.994367 -46.220599) (xy 275.061755 -46.165608) (xy 275.134187 -46.117455)
			(xy 275.210972 -46.0766) (xy 275.291377 -46.043431) (xy 275.374635 -46.018266) (xy 275.459951 -46.001345)
			(xy 275.546511 -45.992829) (xy 275.59 -45.992288) (xy 275.632363 -45.992692) (xy 275.716705 -46.000746)
			(xy 275.7999 -46.01678) (xy 275.881194 -46.04065) (xy 275.959851 -46.07214) (xy 276.035158 -46.110963)
			(xy 276.106434 -46.15677) (xy 276.173033 -46.209144) (xy 276.234352 -46.267611) (xy 276.289836 -46.331643)
			(xy 276.338982 -46.400659) (xy 276.381345 -46.474033) (xy 276.416541 -46.551103) (xy 276.444252 -46.631169)
			(xy 276.464227 -46.713506) (xy 276.476285 -46.79737) (xy 276.480317 -46.882) (xy 276.476285 -46.96663)
			(xy 276.464227 -47.050494) (xy 276.444252 -47.132831) (xy 276.416541 -47.212897) (xy 276.381345 -47.289967)
			(xy 276.338982 -47.363341) (xy 276.289836 -47.432357) (xy 276.234352 -47.496389) (xy 276.173033 -47.554856)
			(xy 276.106434 -47.60723) (xy 276.035158 -47.653037) (xy 275.959851 -47.69186) (xy 275.881194 -47.72335)
			(xy 275.7999 -47.74722) (xy 275.716705 -47.763254) (xy 275.632363 -47.771308) (xy 275.59 -47.771812)
			(xy 275.546511 -47.771259) (xy 275.459949 -47.762751) (xy 275.374631 -47.745837) (xy 275.29137 -47.720678)
			(xy 275.210962 -47.687513) (xy 275.134174 -47.64666) (xy 275.06174 -47.598509) (xy 274.99435 -47.543519)
			(xy 274.963128 -47.51324) (xy 274.962874 -47.512986) (xy 274.95549 -47.506411) (xy 274.937191 -47.498967)
			(xy 274.927314 -47.498508) (xy 274.855686 -47.498508) (xy 274.845803 -47.498929) (xy 274.827504 -47.506395)
			(xy 274.820126 -47.512986) (xy 274.819872 -47.51324) (xy 274.788633 -47.543501) (xy 274.721245 -47.598492)
			(xy 274.648813 -47.646645) (xy 274.572028 -47.6875) (xy 274.491623 -47.720669) (xy 274.408365 -47.745834)
			(xy 274.323049 -47.762755) (xy 274.236489 -47.771271) (xy 274.193 -47.771812) (xy 274.150642 -47.771208)
			(xy 274.066309 -47.763155) (xy 273.983124 -47.747123) (xy 273.901839 -47.723255) (xy 273.823191 -47.691769)
			(xy 273.747892 -47.65295) (xy 273.676624 -47.607149) (xy 273.610032 -47.554781) (xy 273.54872 -47.49632)
			(xy 273.493243 -47.432295) (xy 273.444102 -47.363287) (xy 273.401744 -47.289921) (xy 273.366552 -47.21286)
			(xy 273.338844 -47.132803) (xy 273.318871 -47.050475) (xy 273.306814 -46.96662) (xy 273.302784 -46.882)
			(xy 272.288 -46.882) (xy 272.288 -47.760128) (xy 272.288508 -47.766732) (xy 272.290464 -47.777521)
			(xy 272.302113 -47.796072) (xy 272.320431 -47.808084) (xy 272.342087 -47.811375) (xy 272.35277 -47.808896)
			(xy 272.35658 -47.807626) (xy 272.394077 -47.794047) (xy 272.470963 -47.77285) (xy 272.549436 -47.758616)
			(xy 272.628869 -47.751458) (xy 272.668746 -47.750984) (xy 272.669 -47.750984) (xy 272.711373 -47.751488)
			(xy 272.795734 -47.759544) (xy 272.878948 -47.775582) (xy 272.960261 -47.799457) (xy 273.038936 -47.830954)
			(xy 273.11426 -47.869787) (xy 273.185553 -47.915603) (xy 273.252167 -47.96799) (xy 273.3135 -48.02647)
			(xy 273.368996 -48.090517) (xy 273.418154 -48.159548) (xy 273.460526 -48.23294) (xy 273.495731 -48.310027)
			(xy 273.523448 -48.390111) (xy 273.543428 -48.472468) (xy 273.555488 -48.556351) (xy 273.559521 -48.641)
			(xy 273.555488 -48.725649) (xy 273.543428 -48.809532) (xy 273.523448 -48.891889) (xy 273.495731 -48.971973)
			(xy 273.460526 -49.04906) (xy 273.418154 -49.122452) (xy 273.368996 -49.191483) (xy 273.3135 -49.25553)
			(xy 273.252167 -49.31401) (xy 273.185553 -49.366397) (xy 273.11426 -49.412213) (xy 273.038936 -49.451046)
			(xy 272.960261 -49.482543) (xy 272.878948 -49.506418) (xy 272.795734 -49.522456) (xy 272.711373 -49.530512)
			(xy 272.669 -49.531016) (xy 272.668746 -49.531016) (xy 272.628869 -49.53056) (xy 272.549435 -49.523399)
			(xy 272.470962 -49.509158) (xy 272.394078 -49.487952) (xy 272.35658 -49.474374) (xy 272.35277 -49.473104)
			(xy 272.342089 -49.470596) (xy 272.32042 -49.473889) (xy 272.302092 -49.485908) (xy 272.290437 -49.504469)
			(xy 272.288508 -49.515268) (xy 272.288 -49.521872) (xy 272.288 -50.419) (xy 272.287479 -50.45226)
			(xy 272.278791 -50.51821) (xy 272.261566 -50.582461) (xy 272.236097 -50.643912) (xy 272.202821 -50.701511)
			(xy 272.162308 -50.754271) (xy 272.139156 -50.778156) (xy 270.996156 -51.921156) (xy 270.972276 -51.944312)
			(xy 270.919512 -51.984818) (xy 270.861911 -52.018089) (xy 270.80046 -52.043553) (xy 270.736209 -52.060775)
			(xy 270.670259 -52.069461) (xy 270.637 -52.07) (xy 258.784344 -52.07) (xy 258.774278 -52.070434)
			(xy 258.755689 -52.078162) (xy 258.748276 -52.084986) (xy 255.429004 -55.404258) (xy 255.424432 -55.437786)
			(xy 255.433068 -55.452772) (xy 255.481287 -55.539122) (xy 255.571682 -55.715057) (xy 255.655051 -55.894429)
			(xy 255.731262 -56.076957) (xy 255.800198 -56.262355) (xy 255.86175 -56.450334) (xy 255.915822 -56.640599)
			(xy 255.96233 -56.832853) (xy 256.0012 -57.026795) (xy 256.032372 -57.222123) (xy 256.055797 -57.41853)
			(xy 256.071439 -57.61571) (xy 256.079273 -57.813354) (xy 256.079752 -57.912254) (xy 256.079246 -58.012957)
			(xy 256.071138 -58.214198) (xy 256.054934 -58.41495) (xy 256.03066 -58.614887) (xy 255.998354 -58.813684)
			(xy 255.958071 -59.01102) (xy 255.909874 -59.206573) (xy 255.853843 -59.400027) (xy 255.790067 -59.591068)
			(xy 255.718651 -59.779386) (xy 255.639711 -59.964676) (xy 255.553373 -60.146637) (xy 255.459779 -60.324974)
			(xy 255.35908 -60.499398) (xy 255.251439 -60.669626) (xy 255.137032 -60.835381) (xy 255.016043 -60.996396)
			(xy 254.888669 -61.152408) (xy 254.755116 -61.303165) (xy 254.615602 -61.448422) (xy 254.470352 -61.587944)
			(xy 254.319601 -61.721504) (xy 254.163596 -61.848886) (xy 254.002587 -61.969883) (xy 253.836838 -62.084299)
			(xy 253.666615 -62.191948) (xy 253.492196 -62.292656) (xy 253.313864 -62.38626) (xy 253.131908 -62.472606)
			(xy 252.946622 -62.551556) (xy 252.758307 -62.622982) (xy 252.567269 -62.686767) (xy 252.373818 -62.742809)
			(xy 252.178268 -62.791015) (xy 251.980934 -62.831309) (xy 251.782139 -62.863624) (xy 251.582203 -62.887908)
			(xy 251.381452 -62.904123) (xy 251.18021 -62.912241) (xy 251.079508 -62.912752) (xy 230.521256 -62.912752)
			(xy 230.511191 -62.913185) (xy 230.492603 -62.920916) (xy 230.485188 -62.927738) (xy 221.410326 -72.0026)
			(xy 221.994784 -72.0026) (xy 221.998814 -71.91798) (xy 222.010871 -71.834125) (xy 222.030844 -71.751797)
			(xy 222.058552 -71.67174) (xy 222.093744 -71.594679) (xy 222.136102 -71.521313) (xy 222.185243 -71.452305)
			(xy 222.24072 -71.38828) (xy 222.302032 -71.329819) (xy 222.368624 -71.277451) (xy 222.439892 -71.23165)
			(xy 222.515191 -71.192831) (xy 222.593839 -71.161345) (xy 222.675124 -71.137477) (xy 222.758309 -71.121445)
			(xy 222.842642 -71.113392) (xy 222.885 -71.112888) (xy 222.928791 -71.113422) (xy 223.01595 -71.12202)
			(xy 223.101841 -71.139145) (xy 223.185634 -71.164629) (xy 223.266515 -71.198225) (xy 223.343703 -71.239609)
			(xy 223.416449 -71.28838) (xy 223.48405 -71.344065) (xy 223.545849 -71.406125) (xy 223.601249 -71.473959)
			(xy 223.625918 -71.510144) (xy 223.63303 -71.520558) (xy 223.655382 -71.53275) (xy 223.765618 -71.53275)
			(xy 223.78797 -71.520558) (xy 223.795082 -71.510144) (xy 223.819739 -71.473951) (xy 223.875146 -71.406123)
			(xy 223.93695 -71.344068) (xy 224.004553 -71.288386) (xy 224.0773 -71.239618) (xy 224.154488 -71.198234)
			(xy 224.235369 -71.164636) (xy 224.319161 -71.139149) (xy 224.405051 -71.122019) (xy 224.492209 -71.113412)
			(xy 224.536 -71.112888) (xy 224.578321 -71.113409) (xy 224.662577 -71.12148) (xy 224.745686 -71.13752)
			(xy 224.826894 -71.161384) (xy 224.905468 -71.192856) (xy 224.980695 -71.231651) (xy 225.016568 -71.254112)
			(xy 225.024962 -71.258975) (xy 225.044 -71.262628) (xy 225.063038 -71.258975) (xy 225.071432 -71.254112)
			(xy 225.107317 -71.231673) (xy 225.182548 -71.192891) (xy 225.261121 -71.161425) (xy 225.342326 -71.137559)
			(xy 225.425429 -71.121508) (xy 225.509681 -71.113418) (xy 225.552 -71.112888) (xy 225.595791 -71.113422)
			(xy 225.68295 -71.12202) (xy 225.768841 -71.139145) (xy 225.852634 -71.164629) (xy 225.933515 -71.198225)
			(xy 226.010703 -71.239609) (xy 226.083449 -71.28838) (xy 226.15105 -71.344065) (xy 226.212849 -71.406125)
			(xy 226.268249 -71.473959) (xy 226.292918 -71.510144) (xy 226.30003 -71.520558) (xy 226.322382 -71.53275)
			(xy 226.432618 -71.53275) (xy 226.45497 -71.520558) (xy 226.462082 -71.510144) (xy 226.486739 -71.473951)
			(xy 226.542146 -71.406123) (xy 226.60395 -71.344068) (xy 226.671553 -71.288386) (xy 226.7443 -71.239618)
			(xy 226.821488 -71.198234) (xy 226.902369 -71.164636) (xy 226.986161 -71.139149) (xy 227.072051 -71.122019)
			(xy 227.159209 -71.113412) (xy 227.203 -71.112888) (xy 227.245363 -71.113292) (xy 227.329705 -71.121346)
			(xy 227.4129 -71.13738) (xy 227.494194 -71.16125) (xy 227.572851 -71.19274) (xy 227.648158 -71.231563)
			(xy 227.719434 -71.27737) (xy 227.786033 -71.329744) (xy 227.847352 -71.388211) (xy 227.902836 -71.452243)
			(xy 227.951982 -71.521259) (xy 227.994345 -71.594633) (xy 228.029541 -71.671703) (xy 228.057252 -71.751769)
			(xy 228.077227 -71.834106) (xy 228.089285 -71.91797) (xy 228.093317 -72.0026) (xy 228.979784 -72.0026)
			(xy 228.983814 -71.91798) (xy 228.995871 -71.834125) (xy 229.015844 -71.751797) (xy 229.043552 -71.67174)
			(xy 229.078744 -71.594679) (xy 229.121102 -71.521313) (xy 229.170243 -71.452305) (xy 229.22572 -71.38828)
			(xy 229.287032 -71.329819) (xy 229.353624 -71.277451) (xy 229.424892 -71.23165) (xy 229.500191 -71.192831)
			(xy 229.578839 -71.161345) (xy 229.660124 -71.137477) (xy 229.743309 -71.121445) (xy 229.827642 -71.113392)
			(xy 229.87 -71.112888) (xy 229.912321 -71.113409) (xy 229.996577 -71.12148) (xy 230.079686 -71.13752)
			(xy 230.160894 -71.161384) (xy 230.239468 -71.192856) (xy 230.314695 -71.231651) (xy 230.350568 -71.254112)
			(xy 230.358962 -71.258975) (xy 230.378 -71.262628) (xy 230.397038 -71.258975) (xy 230.405432 -71.254112)
			(xy 230.441317 -71.231673) (xy 230.516548 -71.192891) (xy 230.595121 -71.161425) (xy 230.676326 -71.137559)
			(xy 230.759429 -71.121508) (xy 230.843681 -71.113418) (xy 230.886 -71.112888) (xy 230.929791 -71.113422)
			(xy 231.01695 -71.12202) (xy 231.102841 -71.139145) (xy 231.186634 -71.164629) (xy 231.267515 -71.198225)
			(xy 231.344703 -71.239609) (xy 231.417449 -71.28838) (xy 231.48505 -71.344065) (xy 231.546849 -71.406125)
			(xy 231.602249 -71.473959) (xy 231.626918 -71.510144) (xy 231.63403 -71.520558) (xy 231.656382 -71.53275)
			(xy 231.766618 -71.53275) (xy 231.78897 -71.520558) (xy 231.796082 -71.510144) (xy 231.820739 -71.473951)
			(xy 231.876146 -71.406123) (xy 231.93795 -71.344068) (xy 232.005553 -71.288386) (xy 232.0783 -71.239618)
			(xy 232.155488 -71.198234) (xy 232.236369 -71.164636) (xy 232.320161 -71.139149) (xy 232.406051 -71.122019)
			(xy 232.493209 -71.113412) (xy 232.537 -71.112888) (xy 232.579363 -71.113292) (xy 232.663705 -71.121346)
			(xy 232.7469 -71.13738) (xy 232.828194 -71.16125) (xy 232.906851 -71.19274) (xy 232.982158 -71.231563)
			(xy 233.053434 -71.27737) (xy 233.120033 -71.329744) (xy 233.181352 -71.388211) (xy 233.236836 -71.452243)
			(xy 233.285982 -71.521259) (xy 233.328345 -71.594633) (xy 233.363541 -71.671703) (xy 233.391252 -71.751769)
			(xy 233.411227 -71.834106) (xy 233.423285 -71.91797) (xy 233.427317 -72.0026) (xy 233.425296 -72.045011)
			(xy 234.314742 -72.045011) (xy 234.314742 -71.960289) (xy 234.322795 -71.875952) (xy 234.338829 -71.792762)
			(xy 234.362697 -71.711472) (xy 234.394185 -71.63282) (xy 234.433007 -71.557517) (xy 234.47881 -71.486245)
			(xy 234.531181 -71.419649) (xy 234.589646 -71.358334) (xy 234.653674 -71.302853) (xy 234.722686 -71.25371)
			(xy 234.796056 -71.21135) (xy 234.873121 -71.176155) (xy 234.953183 -71.148446) (xy 235.035516 -71.128472)
			(xy 235.119375 -71.116415) (xy 235.204 -71.112384) (xy 235.288625 -71.116415) (xy 235.372484 -71.128472)
			(xy 235.454817 -71.148446) (xy 235.534879 -71.176155) (xy 235.611944 -71.21135) (xy 235.685314 -71.25371)
			(xy 235.754326 -71.302853) (xy 235.818354 -71.358334) (xy 235.876819 -71.419649) (xy 235.92919 -71.486245)
			(xy 235.974993 -71.557517) (xy 236.013815 -71.63282) (xy 236.045303 -71.711472) (xy 236.069171 -71.792762)
			(xy 236.085205 -71.875952) (xy 236.093258 -71.960289) (xy 236.093762 -72.00265) (xy 236.093258 -72.045011)
			(xy 236.085376 -72.127561) (xy 237.870742 -72.127561) (xy 237.870742 -72.042839) (xy 237.878795 -71.958502)
			(xy 237.894829 -71.875312) (xy 237.918697 -71.794022) (xy 237.950185 -71.71537) (xy 237.989007 -71.640067)
			(xy 238.03481 -71.568795) (xy 238.087181 -71.502199) (xy 238.145646 -71.440884) (xy 238.209674 -71.385403)
			(xy 238.278686 -71.33626) (xy 238.352056 -71.2939) (xy 238.429121 -71.258705) (xy 238.509183 -71.230996)
			(xy 238.591516 -71.211022) (xy 238.675375 -71.198965) (xy 238.76 -71.194934) (xy 238.844625 -71.198965)
			(xy 238.928484 -71.211022) (xy 239.010817 -71.230996) (xy 239.090879 -71.258705) (xy 239.167944 -71.2939)
			(xy 239.241314 -71.33626) (xy 239.310326 -71.385403) (xy 239.374354 -71.440884) (xy 239.432819 -71.502199)
			(xy 239.48519 -71.568795) (xy 239.530993 -71.640067) (xy 239.569815 -71.71537) (xy 239.601303 -71.794022)
			(xy 239.625171 -71.875312) (xy 239.641205 -71.958502) (xy 239.649258 -72.042839) (xy 239.649762 -72.0852)
			(xy 239.649258 -72.127561) (xy 239.641205 -72.211898) (xy 239.625171 -72.295088) (xy 239.601303 -72.376378)
			(xy 239.569815 -72.45503) (xy 239.530993 -72.530333) (xy 239.48519 -72.601605) (xy 239.432819 -72.668201)
			(xy 239.374354 -72.729516) (xy 239.310326 -72.784997) (xy 239.241314 -72.83414) (xy 239.167944 -72.8765)
			(xy 239.090879 -72.911695) (xy 239.010817 -72.939404) (xy 238.928484 -72.959378) (xy 238.844625 -72.971435)
			(xy 238.76 -72.975467) (xy 238.675375 -72.971435) (xy 238.591516 -72.959378) (xy 238.509183 -72.939404)
			(xy 238.429121 -72.911695) (xy 238.352056 -72.8765) (xy 238.278686 -72.83414) (xy 238.209674 -72.784997)
			(xy 238.145646 -72.729516) (xy 238.087181 -72.668201) (xy 238.03481 -72.601605) (xy 237.989007 -72.530333)
			(xy 237.950185 -72.45503) (xy 237.918697 -72.376378) (xy 237.894829 -72.295088) (xy 237.878795 -72.211898)
			(xy 237.870742 -72.127561) (xy 236.085376 -72.127561) (xy 236.085205 -72.129348) (xy 236.069171 -72.212538)
			(xy 236.045303 -72.293828) (xy 236.013815 -72.37248) (xy 235.974993 -72.447783) (xy 235.92919 -72.519055)
			(xy 235.876819 -72.585651) (xy 235.818354 -72.646966) (xy 235.754326 -72.702447) (xy 235.685314 -72.75159)
			(xy 235.611944 -72.79395) (xy 235.534879 -72.829145) (xy 235.454817 -72.856854) (xy 235.372484 -72.876828)
			(xy 235.288625 -72.888885) (xy 235.204 -72.892917) (xy 235.119375 -72.888885) (xy 235.035516 -72.876828)
			(xy 234.953183 -72.856854) (xy 234.873121 -72.829145) (xy 234.796056 -72.79395) (xy 234.722686 -72.75159)
			(xy 234.653674 -72.702447) (xy 234.589646 -72.646966) (xy 234.531181 -72.585651) (xy 234.47881 -72.519055)
			(xy 234.433007 -72.447783) (xy 234.394185 -72.37248) (xy 234.362697 -72.293828) (xy 234.338829 -72.212538)
			(xy 234.322795 -72.129348) (xy 234.314742 -72.045011) (xy 233.425296 -72.045011) (xy 233.423285 -72.08723)
			(xy 233.411227 -72.171094) (xy 233.391252 -72.253431) (xy 233.363541 -72.333497) (xy 233.328345 -72.410567)
			(xy 233.285982 -72.483941) (xy 233.236836 -72.552957) (xy 233.181352 -72.616989) (xy 233.120033 -72.675456)
			(xy 233.053434 -72.72783) (xy 232.982158 -72.773637) (xy 232.906851 -72.81246) (xy 232.828194 -72.84395)
			(xy 232.7469 -72.86782) (xy 232.663705 -72.883854) (xy 232.579363 -72.891908) (xy 232.537 -72.892412)
			(xy 232.493209 -72.891878) (xy 232.40605 -72.88328) (xy 232.320159 -72.866155) (xy 232.236366 -72.840671)
			(xy 232.155485 -72.807075) (xy 232.078297 -72.765691) (xy 232.005551 -72.71692) (xy 231.93795 -72.661235)
			(xy 231.876151 -72.599175) (xy 231.820751 -72.531341) (xy 231.796082 -72.495156) (xy 231.78897 -72.484742)
			(xy 231.766618 -72.47255) (xy 231.656382 -72.47255) (xy 231.63403 -72.484742) (xy 231.626918 -72.495156)
			(xy 231.602261 -72.531349) (xy 231.546854 -72.599177) (xy 231.48505 -72.661232) (xy 231.417447 -72.716914)
			(xy 231.3447 -72.765682) (xy 231.267512 -72.807066) (xy 231.186631 -72.840664) (xy 231.102839 -72.866151)
			(xy 231.016949 -72.883281) (xy 230.929791 -72.891888) (xy 230.886 -72.892412) (xy 230.843679 -72.891891)
			(xy 230.759423 -72.88382) (xy 230.676314 -72.86778) (xy 230.595106 -72.843916) (xy 230.516532 -72.812444)
			(xy 230.441305 -72.773649) (xy 230.405432 -72.751188) (xy 230.397038 -72.746325) (xy 230.378 -72.742672)
			(xy 230.358962 -72.746325) (xy 230.350568 -72.751188) (xy 230.314683 -72.773627) (xy 230.239452 -72.812409)
			(xy 230.160879 -72.843875) (xy 230.079674 -72.867741) (xy 229.996571 -72.883792) (xy 229.912319 -72.891882)
			(xy 229.87 -72.892412) (xy 229.827642 -72.891808) (xy 229.743309 -72.883755) (xy 229.660124 -72.867723)
			(xy 229.578839 -72.843855) (xy 229.500191 -72.812369) (xy 229.424892 -72.77355) (xy 229.353624 -72.727749)
			(xy 229.287032 -72.675381) (xy 229.22572 -72.61692) (xy 229.170243 -72.552895) (xy 229.121102 -72.483887)
			(xy 229.078744 -72.410521) (xy 229.043552 -72.33346) (xy 229.015844 -72.253403) (xy 228.995871 -72.171075)
			(xy 228.983814 -72.08722) (xy 228.979784 -72.0026) (xy 228.093317 -72.0026) (xy 228.089285 -72.08723)
			(xy 228.077227 -72.171094) (xy 228.057252 -72.253431) (xy 228.029541 -72.333497) (xy 227.994345 -72.410567)
			(xy 227.951982 -72.483941) (xy 227.902836 -72.552957) (xy 227.847352 -72.616989) (xy 227.786033 -72.675456)
			(xy 227.719434 -72.72783) (xy 227.648158 -72.773637) (xy 227.572851 -72.81246) (xy 227.494194 -72.84395)
			(xy 227.4129 -72.86782) (xy 227.329705 -72.883854) (xy 227.245363 -72.891908) (xy 227.203 -72.892412)
			(xy 227.159209 -72.891878) (xy 227.07205 -72.88328) (xy 226.986159 -72.866155) (xy 226.902366 -72.840671)
			(xy 226.821485 -72.807075) (xy 226.744297 -72.765691) (xy 226.671551 -72.71692) (xy 226.60395 -72.661235)
			(xy 226.542151 -72.599175) (xy 226.486751 -72.531341) (xy 226.462082 -72.495156) (xy 226.45497 -72.484742)
			(xy 226.432618 -72.47255) (xy 226.322382 -72.47255) (xy 226.30003 -72.484742) (xy 226.292918 -72.495156)
			(xy 226.268261 -72.531349) (xy 226.212854 -72.599177) (xy 226.15105 -72.661232) (xy 226.083447 -72.716914)
			(xy 226.0107 -72.765682) (xy 225.933512 -72.807066) (xy 225.852631 -72.840664) (xy 225.768839 -72.866151)
			(xy 225.682949 -72.883281) (xy 225.595791 -72.891888) (xy 225.552 -72.892412) (xy 225.509679 -72.891891)
			(xy 225.425423 -72.88382) (xy 225.342314 -72.86778) (xy 225.261106 -72.843916) (xy 225.182532 -72.812444)
			(xy 225.107305 -72.773649) (xy 225.071432 -72.751188) (xy 225.063038 -72.746325) (xy 225.044 -72.742672)
			(xy 225.024962 -72.746325) (xy 225.016568 -72.751188) (xy 224.980683 -72.773627) (xy 224.905452 -72.812409)
			(xy 224.826879 -72.843875) (xy 224.745674 -72.867741) (xy 224.662571 -72.883792) (xy 224.578319 -72.891882)
			(xy 224.536 -72.892412) (xy 224.492209 -72.891878) (xy 224.40505 -72.88328) (xy 224.319159 -72.866155)
			(xy 224.235366 -72.840671) (xy 224.154485 -72.807075) (xy 224.077297 -72.765691) (xy 224.004551 -72.71692)
			(xy 223.93695 -72.661235) (xy 223.875151 -72.599175) (xy 223.819751 -72.531341) (xy 223.795082 -72.495156)
			(xy 223.78797 -72.484742) (xy 223.765618 -72.47255) (xy 223.655382 -72.47255) (xy 223.63303 -72.484742)
			(xy 223.625918 -72.495156) (xy 223.601261 -72.531349) (xy 223.545854 -72.599177) (xy 223.48405 -72.661232)
			(xy 223.416447 -72.716914) (xy 223.3437 -72.765682) (xy 223.266512 -72.807066) (xy 223.185631 -72.840664)
			(xy 223.101839 -72.866151) (xy 223.015949 -72.883281) (xy 222.928791 -72.891888) (xy 222.885 -72.892412)
			(xy 222.842642 -72.891808) (xy 222.758309 -72.883755) (xy 222.675124 -72.867723) (xy 222.593839 -72.843855)
			(xy 222.515191 -72.812369) (xy 222.439892 -72.77355) (xy 222.368624 -72.727749) (xy 222.302032 -72.675381)
			(xy 222.24072 -72.61692) (xy 222.185243 -72.552895) (xy 222.136102 -72.483887) (xy 222.093744 -72.410521)
			(xy 222.058552 -72.33346) (xy 222.030844 -72.253403) (xy 222.010871 -72.171075) (xy 221.998814 -72.08722)
			(xy 221.994784 -72.0026) (xy 221.410326 -72.0026) (xy 220.486986 -72.92594) (xy 220.480136 -72.933336)
			(xy 220.472403 -72.951936) (xy 220.472 -72.962008) (xy 220.472 -73.107042) (xy 220.490796 -73.133204)
			(xy 220.50629 -73.138538) (xy 220.546294 -73.152765) (xy 220.623632 -73.187815) (xy 220.697279 -73.230075)
			(xy 220.766563 -73.279162) (xy 220.830853 -73.334628) (xy 220.889566 -73.395968) (xy 220.942166 -73.462624)
			(xy 220.988175 -73.533989) (xy 221.027173 -73.609414) (xy 221.058806 -73.688212) (xy 221.082786 -73.769665)
			(xy 221.098894 -73.853034) (xy 221.106984 -73.937558) (xy 221.106983 -74.022468) (xy 221.09889 -74.106992)
			(xy 221.082779 -74.19036) (xy 221.058797 -74.271813) (xy 221.027162 -74.35061) (xy 220.988162 -74.426034)
			(xy 220.942151 -74.497397) (xy 220.889549 -74.564052) (xy 220.830835 -74.62539) (xy 220.766542 -74.680854)
			(xy 220.740489 -74.699311) (xy 223.392742 -74.699311) (xy 223.392742 -74.614589) (xy 223.400795 -74.530252)
			(xy 223.416829 -74.447062) (xy 223.440697 -74.365772) (xy 223.472185 -74.28712) (xy 223.511007 -74.211817)
			(xy 223.55681 -74.140545) (xy 223.609181 -74.073949) (xy 223.667646 -74.012634) (xy 223.731674 -73.957153)
			(xy 223.800686 -73.90801) (xy 223.874056 -73.86565) (xy 223.951121 -73.830455) (xy 224.031183 -73.802746)
			(xy 224.113516 -73.782772) (xy 224.197375 -73.770715) (xy 224.282 -73.766684) (xy 224.366625 -73.770715)
			(xy 224.450484 -73.782772) (xy 224.532817 -73.802746) (xy 224.612879 -73.830455) (xy 224.689944 -73.86565)
			(xy 224.763314 -73.90801) (xy 224.832326 -73.957153) (xy 224.896354 -74.012634) (xy 224.954819 -74.073949)
			(xy 225.00719 -74.140545) (xy 225.052057 -74.210361) (xy 228.853742 -74.210361) (xy 228.853742 -74.125639)
			(xy 228.861795 -74.041302) (xy 228.877829 -73.958112) (xy 228.901697 -73.876822) (xy 228.933185 -73.79817)
			(xy 228.972007 -73.722867) (xy 229.01781 -73.651595) (xy 229.070181 -73.584999) (xy 229.128646 -73.523684)
			(xy 229.192674 -73.468203) (xy 229.261686 -73.41906) (xy 229.335056 -73.3767) (xy 229.412121 -73.341505)
			(xy 229.492183 -73.313796) (xy 229.574516 -73.293822) (xy 229.658375 -73.281765) (xy 229.743 -73.277734)
			(xy 229.827625 -73.281765) (xy 229.911484 -73.293822) (xy 229.993817 -73.313796) (xy 230.073879 -73.341505)
			(xy 230.150944 -73.3767) (xy 230.224314 -73.41906) (xy 230.293326 -73.468203) (xy 230.357354 -73.523684)
			(xy 230.415819 -73.584999) (xy 230.46819 -73.651595) (xy 230.513993 -73.722867) (xy 230.552815 -73.79817)
			(xy 230.584303 -73.876822) (xy 230.608171 -73.958112) (xy 230.624205 -74.041302) (xy 230.632258 -74.125639)
			(xy 230.632762 -74.168) (xy 230.632258 -74.210361) (xy 231.393742 -74.210361) (xy 231.393742 -74.125639)
			(xy 231.401795 -74.041302) (xy 231.417829 -73.958112) (xy 231.441697 -73.876822) (xy 231.473185 -73.79817)
			(xy 231.512007 -73.722867) (xy 231.55781 -73.651595) (xy 231.610181 -73.584999) (xy 231.668646 -73.523684)
			(xy 231.732674 -73.468203) (xy 231.801686 -73.41906) (xy 231.875056 -73.3767) (xy 231.952121 -73.341505)
			(xy 232.032183 -73.313796) (xy 232.114516 -73.293822) (xy 232.198375 -73.281765) (xy 232.283 -73.277734)
			(xy 232.367625 -73.281765) (xy 232.451484 -73.293822) (xy 232.533817 -73.313796) (xy 232.613879 -73.341505)
			(xy 232.690944 -73.3767) (xy 232.764314 -73.41906) (xy 232.833326 -73.468203) (xy 232.897354 -73.523684)
			(xy 232.955819 -73.584999) (xy 233.00819 -73.651595) (xy 233.053993 -73.722867) (xy 233.092815 -73.79817)
			(xy 233.124303 -73.876822) (xy 233.148171 -73.958112) (xy 233.164205 -74.041302) (xy 233.172258 -74.125639)
			(xy 233.172762 -74.168) (xy 233.172258 -74.210361) (xy 233.164205 -74.294698) (xy 233.148171 -74.377888)
			(xy 233.124303 -74.459178) (xy 233.092815 -74.53783) (xy 233.090201 -74.5429) (xy 236.091992 -74.5429)
			(xy 236.096022 -74.458299) (xy 236.108075 -74.374465) (xy 236.128043 -74.292156) (xy 236.155745 -74.212117)
			(xy 236.190929 -74.135075) (xy 236.233277 -74.061725) (xy 236.282406 -73.992733) (xy 236.337871 -73.928724)
			(xy 236.399168 -73.870276) (xy 236.465744 -73.81792) (xy 236.536996 -73.77213) (xy 236.612277 -73.73332)
			(xy 236.690907 -73.701841) (xy 236.772173 -73.677979) (xy 236.855339 -73.661951) (xy 236.939652 -73.6539)
			(xy 236.982 -73.653396) (xy 237.023248 -73.653844) (xy 237.105389 -73.661474) (xy 237.186471 -73.676677)
			(xy 237.265797 -73.699324) (xy 237.342685 -73.729218) (xy 237.416474 -73.766105) (xy 237.486531 -73.809665)
			(xy 237.552252 -73.859526) (xy 237.613074 -73.915259) (xy 237.668474 -73.976384) (xy 237.717976 -74.042377)
			(xy 237.761154 -74.11267) (xy 237.779814 -74.149458) (xy 237.784384 -74.157761) (xy 237.798386 -74.170514)
			(xy 237.816063 -74.17731) (xy 237.825534 -74.177652) (xy 237.916466 -74.177652) (xy 237.925934 -74.177277)
			(xy 237.94361 -74.170493) (xy 237.957623 -74.157761) (xy 237.962186 -74.149458) (xy 237.981683 -74.111087)
			(xy 238.02705 -74.037938) (xy 238.07927 -73.969513) (xy 238.137854 -73.906451) (xy 238.202254 -73.849341)
			(xy 238.271869 -73.798718) (xy 238.346047 -73.755055) (xy 238.424096 -73.718761) (xy 238.505285 -73.690173)
			(xy 238.588855 -73.669561) (xy 238.674026 -73.657116) (xy 238.76 -73.652954) (xy 238.845974 -73.657116)
			(xy 238.931145 -73.669561) (xy 239.014715 -73.690173) (xy 239.095904 -73.718761) (xy 239.173953 -73.755055)
			(xy 239.248131 -73.798718) (xy 239.317746 -73.849341) (xy 239.382146 -73.906451) (xy 239.44073 -73.969513)
			(xy 239.49295 -74.037938) (xy 239.538317 -74.111087) (xy 239.557814 -74.149458) (xy 239.562384 -74.157761)
			(xy 239.576386 -74.170514) (xy 239.594063 -74.17731) (xy 239.603534 -74.177652) (xy 239.694466 -74.177652)
			(xy 239.703934 -74.177277) (xy 239.72161 -74.170493) (xy 239.735623 -74.157761) (xy 239.740186 -74.149458)
			(xy 239.758799 -74.112647) (xy 239.801992 -74.042364) (xy 239.851506 -73.976381) (xy 239.906915 -73.915265)
			(xy 239.967744 -73.859541) (xy 240.03347 -73.809687) (xy 240.103529 -73.766132) (xy 240.177319 -73.729249)
			(xy 240.254207 -73.699355) (xy 240.333532 -73.676707) (xy 240.414612 -73.661499) (xy 240.496753 -73.653863)
			(xy 240.538 -73.653396) (xy 240.580349 -73.653892) (xy 240.664663 -73.661943) (xy 240.747829 -73.677972)
			(xy 240.829096 -73.701834) (xy 240.907726 -73.733313) (xy 240.983008 -73.772123) (xy 241.05426 -73.817914)
			(xy 241.120837 -73.87027) (xy 241.182135 -73.928718) (xy 241.2376 -73.992728) (xy 241.28673 -74.061721)
			(xy 241.329078 -74.135071) (xy 241.364263 -74.212114) (xy 241.391965 -74.292153) (xy 241.411933 -74.374463)
			(xy 241.423986 -74.458299) (xy 241.428017 -74.5429) (xy 241.423986 -74.627501) (xy 241.411933 -74.711337)
			(xy 241.391965 -74.793647) (xy 241.364263 -74.873686) (xy 241.329078 -74.950729) (xy 241.28673 -75.024079)
			(xy 241.2376 -75.093072) (xy 241.182135 -75.157082) (xy 241.120837 -75.21553) (xy 241.05426 -75.267886)
			(xy 240.983008 -75.313677) (xy 240.907726 -75.352487) (xy 240.829096 -75.383966) (xy 240.747829 -75.407828)
			(xy 240.664663 -75.423857) (xy 240.580349 -75.431908) (xy 240.538 -75.432412) (xy 240.496753 -75.43196)
			(xy 240.414611 -75.42433) (xy 240.333529 -75.409127) (xy 240.254204 -75.38648) (xy 240.177316 -75.356586)
			(xy 240.103527 -75.3197) (xy 240.033471 -75.27614) (xy 239.967749 -75.226279) (xy 239.906927 -75.170547)
			(xy 239.851527 -75.109423) (xy 239.802025 -75.04343) (xy 239.758847 -74.973138) (xy 239.740186 -74.93635)
			(xy 239.735613 -74.928048) (xy 239.721613 -74.915295) (xy 239.703937 -74.908498) (xy 239.694466 -74.908156)
			(xy 239.603534 -74.908156) (xy 239.594065 -74.908527) (xy 239.576389 -74.915312) (xy 239.562377 -74.928046)
			(xy 239.557814 -74.93635) (xy 239.538997 -74.97349) (xy 239.495344 -75.044397) (xy 239.445257 -75.110913)
			(xy 239.389174 -75.172459) (xy 239.327585 -75.228495) (xy 239.261029 -75.278531) (xy 239.190089 -75.322129)
			(xy 239.115386 -75.358907) (xy 239.037573 -75.388544) (xy 238.957331 -75.410781) (xy 238.875363 -75.425422)
			(xy 238.833914 -75.429364) (xy 238.83366 -75.429364) (xy 238.824216 -75.430661) (xy 238.807191 -75.439197)
			(xy 238.794452 -75.453354) (xy 238.790734 -75.46213) (xy 238.752888 -75.561952) (xy 238.75873 -75.590654)
			(xy 238.769144 -75.601322) (xy 238.798414 -75.632395) (xy 238.851538 -75.699222) (xy 238.898016 -75.770832)
			(xy 238.937418 -75.846565) (xy 238.969383 -75.925725) (xy 238.993617 -76.007583) (xy 239.009895 -76.091387)
			(xy 239.01807 -76.176365) (xy 239.018572 -76.21905) (xy 239.018545 -76.235701) (xy 239.017401 -76.268984)
			(xy 239.016286 -76.285598) (xy 239.015924 -76.294998) (xy 239.021319 -76.313006) (xy 239.032863 -76.327841)
			(xy 239.048994 -76.337494) (xy 239.058196 -76.339446) (xy 239.102205 -76.347638) (xy 239.188423 -76.371745)
			(xy 239.271785 -76.404386) (xy 239.351448 -76.445232) (xy 239.426608 -76.493869) (xy 239.496506 -76.549805)
			(xy 239.528858 -76.580746) (xy 239.535185 -76.586522) (xy 239.550667 -76.593832) (xy 239.567696 -76.595609)
			(xy 239.576102 -76.593954) (xy 239.672876 -76.57084) (xy 239.691926 -76.553568) (xy 239.696244 -76.541122)
			(xy 239.710414 -76.501058) (xy 239.74542 -76.423614) (xy 239.787652 -76.349862) (xy 239.836724 -76.280472)
			(xy 239.892189 -76.216079) (xy 239.953541 -76.157268) (xy 240.020223 -76.104575) (xy 240.091625 -76.058481)
			(xy 240.167097 -76.019406) (xy 240.245951 -75.987705) (xy 240.327469 -75.963669) (xy 240.410908 -75.947516)
			(xy 240.495506 -75.939392) (xy 240.538 -75.938888) (xy 240.580363 -75.939292) (xy 240.664705 -75.947346)
			(xy 240.7479 -75.96338) (xy 240.829194 -75.98725) (xy 240.907851 -76.01874) (xy 240.983158 -76.057563)
			(xy 241.054434 -76.10337) (xy 241.121033 -76.155744) (xy 241.182352 -76.214211) (xy 241.237836 -76.278243)
			(xy 241.286982 -76.347259) (xy 241.329345 -76.420633) (xy 241.364541 -76.497703) (xy 241.392252 -76.577769)
			(xy 241.412227 -76.660106) (xy 241.424285 -76.74397) (xy 241.428317 -76.8286) (xy 241.424285 -76.91323)
			(xy 241.412227 -76.997094) (xy 241.392252 -77.079431) (xy 241.364541 -77.159497) (xy 241.329345 -77.236567)
			(xy 241.286982 -77.309941) (xy 241.237836 -77.378957) (xy 241.182352 -77.442989) (xy 241.121033 -77.501456)
			(xy 241.054434 -77.55383) (xy 240.983158 -77.599637) (xy 240.907851 -77.63846) (xy 240.829194 -77.66995)
			(xy 240.7479 -77.69382) (xy 240.664705 -77.709854) (xy 240.580363 -77.717908) (xy 240.538 -77.718412)
			(xy 240.494868 -77.717905) (xy 240.409009 -77.709544) (xy 240.324363 -77.692911) (xy 240.241724 -77.668162)
			(xy 240.16187 -77.635529) (xy 240.08555 -77.595319) (xy 240.013481 -77.547909) (xy 239.94634 -77.493745)
			(xy 239.915192 -77.463904) (xy 239.908845 -77.458153) (xy 239.893372 -77.45084) (xy 239.876352 -77.44905)
			(xy 239.867948 -77.450696) (xy 239.771174 -77.47381) (xy 239.752124 -77.491082) (xy 239.747806 -77.503528)
			(xy 239.734444 -77.541365) (xy 239.701809 -77.614678) (xy 239.6627 -77.684752) (xy 239.617437 -77.751017)
			(xy 239.566386 -77.812934) (xy 239.509963 -77.869998) (xy 239.479582 -77.896212) (xy 239.467136 -77.906626)
			(xy 239.459008 -77.937614) (xy 239.504474 -78.057756) (xy 239.53089 -78.075536) (xy 239.547146 -78.075282)
			(xy 239.565688 -78.075028) (xy 239.606799 -78.075464) (xy 239.688672 -78.083051) (xy 239.769494 -78.098162)
			(xy 239.848577 -78.120667) (xy 239.925246 -78.150374) (xy 239.998846 -78.18703) (xy 240.068749 -78.230323)
			(xy 240.134358 -78.279881) (xy 240.195113 -78.335284) (xy 240.250496 -78.396056) (xy 240.300035 -78.461681)
			(xy 240.343305 -78.531597) (xy 240.379938 -78.605208) (xy 240.409622 -78.681886) (xy 240.432102 -78.760977)
			(xy 240.447187 -78.841804) (xy 240.454749 -78.923678) (xy 240.455196 -78.96479) (xy 240.454705 -79.006312)
			(xy 240.44697 -79.088996) (xy 240.431565 -79.170599) (xy 240.408626 -79.250413) (xy 240.378352 -79.327742)
			(xy 240.341005 -79.401915) (xy 240.296911 -79.472286) (xy 240.272062 -79.505556) (xy 240.265675 -79.51473)
			(xy 240.260852 -79.536535) (xy 240.265705 -79.558334) (xy 240.272062 -79.567532) (xy 240.296877 -79.600781)
			(xy 240.340937 -79.671087) (xy 240.378264 -79.745188) (xy 240.408533 -79.822441) (xy 240.431483 -79.902175)
			(xy 240.446913 -79.983699) (xy 240.45469 -80.066305) (xy 240.455196 -80.10779) (xy 240.454692 -80.150151)
			(xy 240.446639 -80.234488) (xy 240.430605 -80.317678) (xy 240.406737 -80.398968) (xy 240.375249 -80.47762)
			(xy 240.336427 -80.552923) (xy 240.290624 -80.624195) (xy 240.238253 -80.690791) (xy 240.179788 -80.752106)
			(xy 240.11576 -80.807587) (xy 240.046748 -80.85673) (xy 239.973378 -80.89909) (xy 239.896313 -80.934285)
			(xy 239.816251 -80.961994) (xy 239.733918 -80.981968) (xy 239.650059 -80.994025) (xy 239.565434 -80.998057)
			(xy 239.480809 -80.994025) (xy 239.39695 -80.981968) (xy 239.314617 -80.961994) (xy 239.234555 -80.934285)
			(xy 239.15749 -80.89909) (xy 239.08412 -80.85673) (xy 239.015108 -80.807587) (xy 238.95108 -80.752106)
			(xy 238.892615 -80.690791) (xy 238.840244 -80.624195) (xy 238.794441 -80.552923) (xy 238.755619 -80.47762)
			(xy 238.724131 -80.398968) (xy 238.700263 -80.317678) (xy 238.684229 -80.234488) (xy 238.676176 -80.150151)
			(xy 238.675672 -80.10779) (xy 238.676166 -80.066243) (xy 238.683914 -79.983511) (xy 238.699341 -79.901862)
			(xy 238.722313 -79.822007) (xy 238.75263 -79.744642) (xy 238.790027 -79.670439) (xy 238.83418 -79.600047)
			(xy 238.85906 -79.56677) (xy 238.865384 -79.557609) (xy 238.870213 -79.535907) (xy 238.86539 -79.514204)
			(xy 238.85906 -79.505048) (xy 238.834243 -79.471806) (xy 238.790206 -79.401496) (xy 238.752909 -79.32739)
			(xy 238.722674 -79.250133) (xy 238.699766 -79.170397) (xy 238.684382 -79.088873) (xy 238.676657 -79.006271)
			(xy 238.67618 -78.96479) (xy 238.676706 -78.921769) (xy 238.684978 -78.836125) (xy 238.701482 -78.75168)
			(xy 238.726064 -78.669223) (xy 238.758494 -78.589526) (xy 238.798469 -78.513334) (xy 238.845615 -78.441358)
			(xy 238.899493 -78.374272) (xy 238.959596 -78.312702) (xy 238.992156 -78.284578) (xy 239.004602 -78.274164)
			(xy 239.01273 -78.243176) (xy 238.967264 -78.123034) (xy 238.940848 -78.105254) (xy 238.9251 -78.105508)
			(xy 238.924084 -78.105508) (xy 238.90605 -78.105508) (xy 238.864945 -78.10494) (xy 238.783086 -78.09736)
			(xy 238.702276 -78.082262) (xy 238.623202 -78.059773) (xy 238.546541 -78.030085) (xy 238.472945 -77.993451)
			(xy 238.403043 -77.950184) (xy 238.33743 -77.900654) (xy 238.276667 -77.845281) (xy 238.22127 -77.784539)
			(xy 238.171714 -77.718946) (xy 238.128419 -77.649061) (xy 238.091757 -77.575479) (xy 238.062039 -77.49883)
			(xy 238.039518 -77.419765) (xy 238.024388 -77.33896) (xy 238.016776 -77.257104) (xy 238.016288 -77.216)
			(xy 238.016374 -77.199346) (xy 238.017644 -77.166064) (xy 238.018828 -77.149452) (xy 238.019223 -77.140052)
			(xy 238.013814 -77.122044) (xy 238.002259 -77.107209) (xy 237.986122 -77.097557) (xy 237.976918 -77.095604)
			(xy 237.936121 -77.088041) (xy 237.856044 -77.066285) (xy 237.77834 -77.037168) (xy 237.703686 -77.000941)
			(xy 237.63273 -76.95792) (xy 237.566088 -76.908478) (xy 237.504339 -76.853045) (xy 237.448021 -76.792104)
			(xy 237.397623 -76.726182) (xy 237.353582 -76.655854) (xy 237.316281 -76.581731) (xy 237.286045 -76.504456)
			(xy 237.263137 -76.424701) (xy 237.247754 -76.343159) (xy 237.240032 -76.26054) (xy 237.239556 -76.21905)
			(xy 237.239989 -76.177689) (xy 237.247665 -76.095323) (xy 237.262955 -76.014026) (xy 237.285728 -75.9345)
			(xy 237.315787 -75.857432) (xy 237.352871 -75.783487) (xy 237.396661 -75.713306) (xy 237.446778 -75.647493)
			(xy 237.502789 -75.586618) (xy 237.56421 -75.531207) (xy 237.630511 -75.481737) (xy 237.701118 -75.438638)
			(xy 237.775423 -75.40228) (xy 237.852782 -75.372979) (xy 237.932528 -75.350987) (xy 238.013971 -75.336495)
			(xy 238.05515 -75.33259) (xy 238.055404 -75.33259) (xy 238.064861 -75.331363) (xy 238.081889 -75.322797)
			(xy 238.094621 -75.308612) (xy 238.09833 -75.299824) (xy 238.136176 -75.200002) (xy 238.130334 -75.1713)
			(xy 238.11992 -75.160632) (xy 238.088457 -75.127217) (xy 238.031855 -75.05496) (xy 237.982997 -74.977257)
			(xy 237.962186 -74.93635) (xy 237.957613 -74.928048) (xy 237.943613 -74.915295) (xy 237.925937 -74.908498)
			(xy 237.916466 -74.908156) (xy 237.825534 -74.908156) (xy 237.816065 -74.908527) (xy 237.798389 -74.915312)
			(xy 237.784377 -74.928046) (xy 237.779814 -74.93635) (xy 237.761159 -74.973139) (xy 237.717973 -75.043425)
			(xy 237.668465 -75.10941) (xy 237.613061 -75.170528) (xy 237.552237 -75.226255) (xy 237.486514 -75.276112)
			(xy 237.416459 -75.31967) (xy 237.342672 -75.356555) (xy 237.265786 -75.38645) (xy 237.186464 -75.4091)
			(xy 237.105385 -75.424308) (xy 237.023246 -75.431945) (xy 236.982 -75.432412) (xy 236.939652 -75.4319)
			(xy 236.855339 -75.423849) (xy 236.772173 -75.407821) (xy 236.690907 -75.383959) (xy 236.612277 -75.35248)
			(xy 236.536996 -75.31367) (xy 236.465744 -75.26788) (xy 236.399168 -75.215524) (xy 236.337871 -75.157076)
			(xy 236.282406 -75.093067) (xy 236.233277 -75.024075) (xy 236.190929 -74.950725) (xy 236.155745 -74.873683)
			(xy 236.128043 -74.793644) (xy 236.108075 -74.711335) (xy 236.096022 -74.627501) (xy 236.091992 -74.5429)
			(xy 233.090201 -74.5429) (xy 233.053993 -74.613133) (xy 233.00819 -74.684405) (xy 232.955819 -74.751001)
			(xy 232.897354 -74.812316) (xy 232.833326 -74.867797) (xy 232.764314 -74.91694) (xy 232.690944 -74.9593)
			(xy 232.613879 -74.994495) (xy 232.533817 -75.022204) (xy 232.451484 -75.042178) (xy 232.367625 -75.054235)
			(xy 232.283 -75.058267) (xy 232.198375 -75.054235) (xy 232.114516 -75.042178) (xy 232.032183 -75.022204)
			(xy 231.952121 -74.994495) (xy 231.875056 -74.9593) (xy 231.801686 -74.91694) (xy 231.732674 -74.867797)
			(xy 231.668646 -74.812316) (xy 231.610181 -74.751001) (xy 231.55781 -74.684405) (xy 231.512007 -74.613133)
			(xy 231.473185 -74.53783) (xy 231.441697 -74.459178) (xy 231.417829 -74.377888) (xy 231.401795 -74.294698)
			(xy 231.393742 -74.210361) (xy 230.632258 -74.210361) (xy 230.624205 -74.294698) (xy 230.608171 -74.377888)
			(xy 230.584303 -74.459178) (xy 230.552815 -74.53783) (xy 230.513993 -74.613133) (xy 230.46819 -74.684405)
			(xy 230.415819 -74.751001) (xy 230.357354 -74.812316) (xy 230.293326 -74.867797) (xy 230.224314 -74.91694)
			(xy 230.150944 -74.9593) (xy 230.073879 -74.994495) (xy 229.993817 -75.022204) (xy 229.911484 -75.042178)
			(xy 229.827625 -75.054235) (xy 229.743 -75.058267) (xy 229.658375 -75.054235) (xy 229.574516 -75.042178)
			(xy 229.492183 -75.022204) (xy 229.412121 -74.994495) (xy 229.335056 -74.9593) (xy 229.261686 -74.91694)
			(xy 229.192674 -74.867797) (xy 229.128646 -74.812316) (xy 229.070181 -74.751001) (xy 229.01781 -74.684405)
			(xy 228.972007 -74.613133) (xy 228.933185 -74.53783) (xy 228.901697 -74.459178) (xy 228.877829 -74.377888)
			(xy 228.861795 -74.294698) (xy 228.853742 -74.210361) (xy 225.052057 -74.210361) (xy 225.052993 -74.211817)
			(xy 225.091815 -74.28712) (xy 225.123303 -74.365772) (xy 225.147171 -74.447062) (xy 225.163205 -74.530252)
			(xy 225.171258 -74.614589) (xy 225.171762 -74.65695) (xy 225.171258 -74.699311) (xy 225.163205 -74.783648)
			(xy 225.147171 -74.866838) (xy 225.123303 -74.948128) (xy 225.091815 -75.02678) (xy 225.052993 -75.102083)
			(xy 225.00719 -75.173355) (xy 224.954819 -75.239951) (xy 224.896354 -75.301266) (xy 224.832326 -75.356747)
			(xy 224.763314 -75.40589) (xy 224.689944 -75.44825) (xy 224.612879 -75.483445) (xy 224.532817 -75.511154)
			(xy 224.450484 -75.531128) (xy 224.366625 -75.543185) (xy 224.282 -75.547217) (xy 224.197375 -75.543185)
			(xy 224.113516 -75.531128) (xy 224.031183 -75.511154) (xy 223.951121 -75.483445) (xy 223.874056 -75.44825)
			(xy 223.800686 -75.40589) (xy 223.731674 -75.356747) (xy 223.667646 -75.301266) (xy 223.609181 -75.239951)
			(xy 223.55681 -75.173355) (xy 223.511007 -75.102083) (xy 223.472185 -75.02678) (xy 223.440697 -74.948128)
			(xy 223.416829 -74.866838) (xy 223.400795 -74.783648) (xy 223.392742 -74.699311) (xy 220.740489 -74.699311)
			(xy 220.697257 -74.729938) (xy 220.623609 -74.772197) (xy 220.546269 -74.807245) (xy 220.50629 -74.821542)
			(xy 220.490796 -74.826876) (xy 220.472 -74.853038) (xy 220.472 -75.922321) (xy 226.024944 -75.922321)
			(xy 226.024944 -75.837599) (xy 226.032997 -75.753262) (xy 226.049031 -75.670072) (xy 226.072899 -75.588782)
			(xy 226.104387 -75.51013) (xy 226.143209 -75.434827) (xy 226.189012 -75.363555) (xy 226.241383 -75.296959)
			(xy 226.299848 -75.235644) (xy 226.363876 -75.180163) (xy 226.432888 -75.13102) (xy 226.506258 -75.08866)
			(xy 226.583323 -75.053465) (xy 226.663385 -75.025756) (xy 226.745718 -75.005782) (xy 226.829577 -74.993725)
			(xy 226.914202 -74.989694) (xy 226.998827 -74.993725) (xy 227.082686 -75.005782) (xy 227.165019 -75.025756)
			(xy 227.245081 -75.053465) (xy 227.322146 -75.08866) (xy 227.395516 -75.13102) (xy 227.464528 -75.180163)
			(xy 227.528556 -75.235644) (xy 227.587021 -75.296959) (xy 227.639392 -75.363555) (xy 227.685195 -75.434827)
			(xy 227.724017 -75.51013) (xy 227.755505 -75.588782) (xy 227.779373 -75.670072) (xy 227.795407 -75.753262)
			(xy 227.80346 -75.837599) (xy 227.803964 -75.87996) (xy 227.80346 -75.922321) (xy 227.795407 -76.006658)
			(xy 227.779373 -76.089848) (xy 227.755505 -76.171138) (xy 227.724017 -76.24979) (xy 227.685195 -76.325093)
			(xy 227.639392 -76.396365) (xy 227.587021 -76.462961) (xy 227.528556 -76.524276) (xy 227.464528 -76.579757)
			(xy 227.395516 -76.6289) (xy 227.322146 -76.67126) (xy 227.245081 -76.706455) (xy 227.165019 -76.734164)
			(xy 227.082686 -76.754138) (xy 226.998827 -76.766195) (xy 226.914202 -76.770227) (xy 226.829577 -76.766195)
			(xy 226.745718 -76.754138) (xy 226.663385 -76.734164) (xy 226.583323 -76.706455) (xy 226.506258 -76.67126)
			(xy 226.432888 -76.6289) (xy 226.363876 -76.579757) (xy 226.299848 -76.524276) (xy 226.241383 -76.462961)
			(xy 226.189012 -76.396365) (xy 226.143209 -76.325093) (xy 226.104387 -76.24979) (xy 226.072899 -76.171138)
			(xy 226.049031 -76.089848) (xy 226.032997 -76.006658) (xy 226.024944 -75.922321) (xy 220.472 -75.922321)
			(xy 220.472 -76.44511) (xy 220.472708 -76.45784) (xy 220.484845 -76.480224) (xy 220.495114 -76.487782)
			(xy 220.577664 -76.541122) (xy 220.603572 -76.543154) (xy 220.615256 -76.53782) (xy 220.658367 -76.519117)
			(xy 220.747669 -76.489845) (xy 220.839558 -76.47014) (xy 220.933011 -76.460222) (xy 220.98 -76.459588)
			(xy 221.020054 -76.460025) (xy 221.099837 -76.467222) (xy 221.17865 -76.481568) (xy 221.255852 -76.502945)
			(xy 221.330818 -76.531181) (xy 221.40294 -76.566047) (xy 221.471634 -76.607259) (xy 221.536341 -76.654484)
			(xy 221.56674 -76.680568) (xy 221.573897 -76.686343) (xy 221.591081 -76.692858) (xy 221.600268 -76.693268)
			(xy 221.629732 -76.693268) (xy 221.638925 -76.69288) (xy 221.656121 -76.686372) (xy 221.66326 -76.680568)
			(xy 221.69366 -76.654489) (xy 221.758384 -76.607295) (xy 221.827085 -76.566106) (xy 221.899209 -76.531255)
			(xy 221.974172 -76.503025) (xy 222.051368 -76.481643) (xy 222.130173 -76.467283) (xy 222.209949 -76.46006)
			(xy 222.25 -76.459588) (xy 222.290054 -76.460025) (xy 222.369837 -76.467222) (xy 222.44865 -76.481568)
			(xy 222.525852 -76.502945) (xy 222.600818 -76.531181) (xy 222.67294 -76.566047) (xy 222.741634 -76.607259)
			(xy 222.806341 -76.654484) (xy 222.83674 -76.680568) (xy 222.843897 -76.686343) (xy 222.861081 -76.692858)
			(xy 222.870268 -76.693268) (xy 222.899732 -76.693268) (xy 222.908925 -76.69288) (xy 222.926121 -76.686372)
			(xy 222.93326 -76.680568) (xy 222.96366 -76.654489) (xy 223.028384 -76.607295) (xy 223.097085 -76.566106)
			(xy 223.169209 -76.531255) (xy 223.244172 -76.503025) (xy 223.321368 -76.481643) (xy 223.400173 -76.467283)
			(xy 223.479949 -76.46006) (xy 223.52 -76.459588) (xy 223.562358 -76.460092) (xy 223.646691 -76.468145)
			(xy 223.729876 -76.484177) (xy 223.811161 -76.508045) (xy 223.889809 -76.539531) (xy 223.965108 -76.57835)
			(xy 224.036376 -76.624151) (xy 224.102968 -76.676519) (xy 224.16428 -76.73498) (xy 224.219757 -76.799005)
			(xy 224.268898 -76.868013) (xy 224.311256 -76.941379) (xy 224.346448 -77.01844) (xy 224.374156 -77.098497)
			(xy 224.394129 -77.180825) (xy 224.406186 -77.26468) (xy 224.410217 -77.3493) (xy 224.406186 -77.43392)
			(xy 224.394129 -77.517775) (xy 224.374156 -77.600103) (xy 224.346448 -77.68016) (xy 224.311256 -77.757221)
			(xy 224.268898 -77.830587) (xy 224.224196 -77.893361) (xy 229.219756 -77.893361) (xy 229.219756 -77.808639)
			(xy 229.227809 -77.724302) (xy 229.243843 -77.641112) (xy 229.267711 -77.559822) (xy 229.299199 -77.48117)
			(xy 229.338021 -77.405867) (xy 229.383824 -77.334595) (xy 229.436195 -77.267999) (xy 229.49466 -77.206684)
			(xy 229.558688 -77.151203) (xy 229.6277 -77.10206) (xy 229.70107 -77.0597) (xy 229.778135 -77.024505)
			(xy 229.858197 -76.996796) (xy 229.94053 -76.976822) (xy 230.024389 -76.964765) (xy 230.109014 -76.960734)
			(xy 230.193639 -76.964765) (xy 230.277498 -76.976822) (xy 230.359831 -76.996796) (xy 230.439893 -77.024505)
			(xy 230.516958 -77.0597) (xy 230.590328 -77.10206) (xy 230.65934 -77.151203) (xy 230.723368 -77.206684)
			(xy 230.781833 -77.267999) (xy 230.834204 -77.334595) (xy 230.880007 -77.405867) (xy 230.918829 -77.48117)
			(xy 230.950317 -77.559822) (xy 230.974185 -77.641112) (xy 230.990219 -77.724302) (xy 230.998272 -77.808639)
			(xy 230.998776 -77.851) (xy 230.998272 -77.893361) (xy 230.990219 -77.977698) (xy 230.974185 -78.060888)
			(xy 230.950317 -78.142178) (xy 230.918829 -78.22083) (xy 230.880007 -78.296133) (xy 230.834204 -78.367405)
			(xy 230.781833 -78.434001) (xy 230.723368 -78.495316) (xy 230.65934 -78.550797) (xy 230.590328 -78.59994)
			(xy 230.516958 -78.6423) (xy 230.439893 -78.677495) (xy 230.359831 -78.705204) (xy 230.277498 -78.725178)
			(xy 230.193639 -78.737235) (xy 230.109014 -78.741267) (xy 230.024389 -78.737235) (xy 229.94053 -78.725178)
			(xy 229.858197 -78.705204) (xy 229.778135 -78.677495) (xy 229.70107 -78.6423) (xy 229.6277 -78.59994)
			(xy 229.558688 -78.550797) (xy 229.49466 -78.495316) (xy 229.436195 -78.434001) (xy 229.383824 -78.367405)
			(xy 229.338021 -78.296133) (xy 229.299199 -78.22083) (xy 229.267711 -78.142178) (xy 229.243843 -78.060888)
			(xy 229.227809 -77.977698) (xy 229.219756 -77.893361) (xy 224.224196 -77.893361) (xy 224.219757 -77.899595)
			(xy 224.16428 -77.96362) (xy 224.102968 -78.022081) (xy 224.036376 -78.074449) (xy 223.965108 -78.12025)
			(xy 223.889809 -78.159069) (xy 223.811161 -78.190555) (xy 223.729876 -78.214423) (xy 223.646691 -78.230455)
			(xy 223.562358 -78.238508) (xy 223.52 -78.239112) (xy 223.479946 -78.238675) (xy 223.400163 -78.231478)
			(xy 223.32135 -78.217132) (xy 223.244148 -78.195755) (xy 223.169182 -78.167519) (xy 223.09706 -78.132653)
			(xy 223.028366 -78.091441) (xy 222.963659 -78.044216) (xy 222.93326 -78.018132) (xy 222.926103 -78.012357)
			(xy 222.908919 -78.005842) (xy 222.899732 -78.005432) (xy 222.870268 -78.005432) (xy 222.861075 -78.00582)
			(xy 222.843879 -78.012328) (xy 222.83674 -78.018132) (xy 222.80634 -78.044211) (xy 222.741616 -78.091405)
			(xy 222.672915 -78.132594) (xy 222.600791 -78.167445) (xy 222.525828 -78.195675) (xy 222.448632 -78.217057)
			(xy 222.369827 -78.231417) (xy 222.290051 -78.23864) (xy 222.25 -78.239112) (xy 222.209946 -78.238675)
			(xy 222.130163 -78.231478) (xy 222.05135 -78.217132) (xy 221.974148 -78.195755) (xy 221.899182 -78.167519)
			(xy 221.82706 -78.132653) (xy 221.758366 -78.091441) (xy 221.693659 -78.044216) (xy 221.66326 -78.018132)
			(xy 221.656103 -78.012357) (xy 221.638919 -78.005842) (xy 221.629732 -78.005432) (xy 221.600268 -78.005432)
			(xy 221.591075 -78.00582) (xy 221.573879 -78.012328) (xy 221.56674 -78.018132) (xy 221.53634 -78.044211)
			(xy 221.471616 -78.091405) (xy 221.402915 -78.132594) (xy 221.330791 -78.167445) (xy 221.255828 -78.195675)
			(xy 221.178632 -78.217057) (xy 221.099827 -78.231417) (xy 221.020051 -78.23864) (xy 220.98 -78.239112)
			(xy 220.933009 -78.238506) (xy 220.839551 -78.228603) (xy 220.74766 -78.208895) (xy 220.658359 -78.179604)
			(xy 220.615256 -78.16088) (xy 220.603572 -78.155546) (xy 220.577664 -78.157578) (xy 220.495114 -78.210918)
			(xy 220.488182 -78.21578) (xy 220.477765 -78.229116) (xy 220.472287 -78.245128) (xy 220.472 -78.25359)
			(xy 220.472 -78.543912) (xy 220.472709 -78.556642) (xy 220.484846 -78.579025) (xy 220.495114 -78.586584)
			(xy 220.577664 -78.639924) (xy 220.603572 -78.641956) (xy 220.615256 -78.636622) (xy 220.658251 -78.617985)
			(xy 220.747308 -78.588814) (xy 220.838939 -78.56917) (xy 220.932128 -78.559271) (xy 220.978984 -78.558644)
			(xy 220.98 -78.558644) (xy 221.022351 -78.559148) (xy 221.106669 -78.567199) (xy 221.18984 -78.583229)
			(xy 221.27111 -78.607092) (xy 221.349744 -78.638572) (xy 221.42503 -78.677385) (xy 221.496286 -78.723178)
			(xy 221.562866 -78.775537) (xy 221.624167 -78.833988) (xy 221.679635 -78.898001) (xy 221.728767 -78.966997)
			(xy 221.771117 -79.040351) (xy 221.806304 -79.117398) (xy 221.834007 -79.197441) (xy 221.853976 -79.279755)
			(xy 221.86603 -79.363594) (xy 221.870061 -79.4482) (xy 221.867234 -79.507531) (xy 222.630742 -79.507531)
			(xy 222.630742 -79.422809) (xy 222.638795 -79.338472) (xy 222.654829 -79.255282) (xy 222.678697 -79.173992)
			(xy 222.710185 -79.09534) (xy 222.749007 -79.020037) (xy 222.79481 -78.948765) (xy 222.847181 -78.882169)
			(xy 222.905646 -78.820854) (xy 222.969674 -78.765373) (xy 223.038686 -78.71623) (xy 223.112056 -78.67387)
			(xy 223.189121 -78.638675) (xy 223.269183 -78.610966) (xy 223.351516 -78.590992) (xy 223.435375 -78.578935)
			(xy 223.52 -78.574904) (xy 223.604625 -78.578935) (xy 223.688484 -78.590992) (xy 223.770817 -78.610966)
			(xy 223.850879 -78.638675) (xy 223.927944 -78.67387) (xy 224.001314 -78.71623) (xy 224.070326 -78.765373)
			(xy 224.134354 -78.820854) (xy 224.192819 -78.882169) (xy 224.24519 -78.948765) (xy 224.290993 -79.020037)
			(xy 224.329815 -79.09534) (xy 224.361303 -79.173992) (xy 224.385171 -79.255282) (xy 224.401205 -79.338472)
			(xy 224.409258 -79.422809) (xy 224.409762 -79.46517) (xy 224.409258 -79.507531) (xy 224.401205 -79.591868)
			(xy 224.385171 -79.675058) (xy 224.361303 -79.756348) (xy 224.329815 -79.835) (xy 224.290993 -79.910303)
			(xy 224.24519 -79.981575) (xy 224.192819 -80.048171) (xy 224.134354 -80.109486) (xy 224.114327 -80.12684)
			(xy 235.457492 -80.12684) (xy 235.458084 -80.083505) (xy 235.466508 -79.997245) (xy 235.483279 -79.912213)
			(xy 235.508239 -79.829215) (xy 235.541152 -79.749037) (xy 235.581705 -79.67244) (xy 235.629513 -79.600148)
			(xy 235.684125 -79.532848) (xy 235.745022 -79.471178) (xy 235.811627 -79.415721) (xy 235.883309 -79.367003)
			(xy 235.959388 -79.325486) (xy 236.039144 -79.291564) (xy 236.12182 -79.265558) (xy 236.16412 -79.256128)
			(xy 236.175804 -79.253588) (xy 236.194092 -79.239364) (xy 236.234478 -79.156306) (xy 236.239114 -79.145607)
			(xy 236.239095 -79.122311) (xy 236.234478 -79.111602) (xy 236.216775 -79.074785) (xy 236.187432 -78.998536)
			(xy 236.1652 -78.91992) (xy 236.150264 -78.839597) (xy 236.142751 -78.758244) (xy 236.142276 -78.717394)
			(xy 236.142276 -78.71714) (xy 236.14278 -78.674792) (xy 236.150831 -78.590478) (xy 236.16686 -78.507312)
			(xy 236.190721 -78.426045) (xy 236.2222 -78.347415) (xy 236.261011 -78.272134) (xy 236.306801 -78.200882)
			(xy 236.359157 -78.134306) (xy 236.417605 -78.073008) (xy 236.481615 -78.017543) (xy 236.550607 -77.968414)
			(xy 236.623957 -77.926065) (xy 236.701 -77.890881) (xy 236.781039 -77.863179) (xy 236.863348 -77.843211)
			(xy 236.947183 -77.831158) (xy 237.031784 -77.827128) (xy 237.116385 -77.831158) (xy 237.20022 -77.843211)
			(xy 237.282529 -77.863179) (xy 237.362568 -77.890881) (xy 237.439611 -77.926065) (xy 237.512961 -77.968414)
			(xy 237.581953 -78.017543) (xy 237.645963 -78.073008) (xy 237.704411 -78.134306) (xy 237.756767 -78.200882)
			(xy 237.802557 -78.272134) (xy 237.841368 -78.347415) (xy 237.872847 -78.426045) (xy 237.896708 -78.507312)
			(xy 237.912737 -78.590478) (xy 237.920788 -78.674792) (xy 237.921292 -78.71714) (xy 237.920787 -78.760477)
			(xy 237.912356 -78.84674) (xy 237.895576 -78.931774) (xy 237.870609 -79.014774) (xy 237.837689 -79.094953)
			(xy 237.797129 -79.171551) (xy 237.749313 -79.243843) (xy 237.694695 -79.311142) (xy 237.633791 -79.372812)
			(xy 237.56718 -79.428268) (xy 237.495493 -79.476984) (xy 237.419408 -79.518499) (xy 237.339647 -79.552419)
			(xy 237.256966 -79.578424) (xy 237.214664 -79.587852) (xy 237.20298 -79.590392) (xy 237.184692 -79.604616)
			(xy 237.144306 -79.687674) (xy 237.139684 -79.698377) (xy 237.139695 -79.721669) (xy 237.144306 -79.732378)
			(xy 237.162008 -79.769196) (xy 237.19135 -79.845444) (xy 237.213582 -79.924061) (xy 237.228518 -80.004383)
			(xy 237.236032 -80.085736) (xy 237.236508 -80.126586) (xy 237.236508 -80.12684) (xy 237.236004 -80.169188)
			(xy 237.227953 -80.253502) (xy 237.211924 -80.336668) (xy 237.188063 -80.417935) (xy 237.156584 -80.496565)
			(xy 237.117773 -80.571846) (xy 237.071983 -80.643098) (xy 237.019627 -80.709674) (xy 236.961179 -80.770972)
			(xy 236.897169 -80.826437) (xy 236.828177 -80.875566) (xy 236.754827 -80.917915) (xy 236.677784 -80.953099)
			(xy 236.597745 -80.980801) (xy 236.515436 -81.000769) (xy 236.431601 -81.012822) (xy 236.347 -81.016853)
			(xy 236.262399 -81.012822) (xy 236.178564 -81.000769) (xy 236.096255 -80.980801) (xy 236.016216 -80.953099)
			(xy 235.939173 -80.917915) (xy 235.865823 -80.875566) (xy 235.796831 -80.826437) (xy 235.732821 -80.770972)
			(xy 235.674373 -80.709674) (xy 235.622017 -80.643098) (xy 235.576227 -80.571846) (xy 235.537416 -80.496565)
			(xy 235.505937 -80.417935) (xy 235.482076 -80.336668) (xy 235.466047 -80.253502) (xy 235.457996 -80.169188)
			(xy 235.457492 -80.12684) (xy 224.114327 -80.12684) (xy 224.070326 -80.164967) (xy 224.001314 -80.21411)
			(xy 223.927944 -80.25647) (xy 223.850879 -80.291665) (xy 223.770817 -80.319374) (xy 223.688484 -80.339348)
			(xy 223.604625 -80.351405) (xy 223.52 -80.355437) (xy 223.435375 -80.351405) (xy 223.351516 -80.339348)
			(xy 223.269183 -80.319374) (xy 223.189121 -80.291665) (xy 223.112056 -80.25647) (xy 223.038686 -80.21411)
			(xy 222.969674 -80.164967) (xy 222.905646 -80.109486) (xy 222.847181 -80.048171) (xy 222.79481 -79.981575)
			(xy 222.749007 -79.910303) (xy 222.710185 -79.835) (xy 222.678697 -79.756348) (xy 222.654829 -79.675058)
			(xy 222.638795 -79.591868) (xy 222.630742 -79.507531) (xy 221.867234 -79.507531) (xy 221.86603 -79.532806)
			(xy 221.853976 -79.616645) (xy 221.834007 -79.698959) (xy 221.806304 -79.779002) (xy 221.771117 -79.856049)
			(xy 221.728767 -79.929403) (xy 221.679635 -79.998399) (xy 221.624167 -80.062412) (xy 221.562866 -80.120863)
			(xy 221.496286 -80.173222) (xy 221.42503 -80.219015) (xy 221.349744 -80.257828) (xy 221.27111 -80.289308)
			(xy 221.18984 -80.313171) (xy 221.106669 -80.329201) (xy 221.022351 -80.337252) (xy 220.98 -80.33766)
			(xy 220.978984 -80.33766) (xy 220.932128 -80.337031) (xy 220.83894 -80.327127) (xy 220.747309 -80.307484)
			(xy 220.65825 -80.278319) (xy 220.615256 -80.259682) (xy 220.603572 -80.254348) (xy 220.577664 -80.25638)
			(xy 220.495114 -80.30972) (xy 220.488182 -80.314582) (xy 220.477766 -80.327919) (xy 220.472288 -80.34393)
			(xy 220.472 -80.352392) (xy 220.472 -81.415325) (xy 229.219756 -81.415325) (xy 229.219756 -81.330603)
			(xy 229.227809 -81.246266) (xy 229.243843 -81.163076) (xy 229.267711 -81.081786) (xy 229.299199 -81.003134)
			(xy 229.338021 -80.927831) (xy 229.383824 -80.856559) (xy 229.436195 -80.789963) (xy 229.49466 -80.728648)
			(xy 229.558688 -80.673167) (xy 229.6277 -80.624024) (xy 229.70107 -80.581664) (xy 229.778135 -80.546469)
			(xy 229.858197 -80.51876) (xy 229.94053 -80.498786) (xy 230.024389 -80.486729) (xy 230.109014 -80.482698)
			(xy 230.193639 -80.486729) (xy 230.277498 -80.498786) (xy 230.359831 -80.51876) (xy 230.439893 -80.546469)
			(xy 230.516958 -80.581664) (xy 230.590328 -80.624024) (xy 230.65934 -80.673167) (xy 230.723368 -80.728648)
			(xy 230.781833 -80.789963) (xy 230.834204 -80.856559) (xy 230.880007 -80.927831) (xy 230.918829 -81.003134)
			(xy 230.950317 -81.081786) (xy 230.974185 -81.163076) (xy 230.990219 -81.246266) (xy 230.998272 -81.330603)
			(xy 230.998776 -81.372964) (xy 230.998272 -81.415325) (xy 230.990219 -81.499662) (xy 230.974185 -81.582852)
			(xy 230.950317 -81.664142) (xy 230.918829 -81.742794) (xy 230.880007 -81.818097) (xy 230.834204 -81.889369)
			(xy 230.781833 -81.955965) (xy 230.723368 -82.01728) (xy 230.65934 -82.072761) (xy 230.590328 -82.121904)
			(xy 230.516958 -82.164264) (xy 230.439893 -82.199459) (xy 230.359831 -82.227168) (xy 230.277498 -82.247142)
			(xy 230.193639 -82.259199) (xy 230.109014 -82.263231) (xy 230.024389 -82.259199) (xy 229.94053 -82.247142)
			(xy 229.858197 -82.227168) (xy 229.778135 -82.199459) (xy 229.70107 -82.164264) (xy 229.6277 -82.121904)
			(xy 229.558688 -82.072761) (xy 229.49466 -82.01728) (xy 229.436195 -81.955965) (xy 229.383824 -81.889369)
			(xy 229.338021 -81.818097) (xy 229.299199 -81.742794) (xy 229.267711 -81.664142) (xy 229.243843 -81.582852)
			(xy 229.227809 -81.499662) (xy 229.219756 -81.415325) (xy 220.472 -81.415325) (xy 220.472 -83.3056)
			(xy 228.598784 -83.3056) (xy 228.602814 -83.22098) (xy 228.614871 -83.137125) (xy 228.634844 -83.054797)
			(xy 228.662552 -82.97474) (xy 228.697744 -82.897679) (xy 228.740102 -82.824313) (xy 228.789243 -82.755305)
			(xy 228.84472 -82.69128) (xy 228.906032 -82.632819) (xy 228.972624 -82.580451) (xy 229.043892 -82.53465)
			(xy 229.119191 -82.495831) (xy 229.197839 -82.464345) (xy 229.279124 -82.440477) (xy 229.362309 -82.424445)
			(xy 229.446642 -82.416392) (xy 229.489 -82.415888) (xy 229.530512 -82.41638) (xy 229.613172 -82.424148)
			(xy 229.694748 -82.439588) (xy 229.774529 -82.462566) (xy 229.851821 -82.492881) (xy 229.92595 -82.53027)
			(xy 229.99627 -82.574407) (xy 230.029512 -82.599276) (xy 230.038711 -82.605619) (xy 230.0605 -82.61045)
			(xy 230.082289 -82.605619) (xy 230.091488 -82.599276) (xy 230.124746 -82.574432) (xy 230.195072 -82.53031)
			(xy 230.269201 -82.492931) (xy 230.34649 -82.462618) (xy 230.426266 -82.439635) (xy 230.507836 -82.424183)
			(xy 230.59049 -82.416395) (xy 230.632 -82.415888) (xy 230.673512 -82.41638) (xy 230.756172 -82.424148)
			(xy 230.837748 -82.439588) (xy 230.917529 -82.462566) (xy 230.994821 -82.492881) (xy 231.06895 -82.53027)
			(xy 231.13927 -82.574407) (xy 231.172512 -82.599276) (xy 231.181711 -82.605619) (xy 231.2035 -82.61045)
			(xy 231.225289 -82.605619) (xy 231.234488 -82.599276) (xy 231.270142 -82.57265) (xy 231.345838 -82.525859)
			(xy 231.425826 -82.486856) (xy 231.509307 -82.45603) (xy 231.552242 -82.444336) (xy 231.563084 -82.440862)
			(xy 231.580486 -82.426226) (xy 231.58577 -82.416142) (xy 231.618282 -82.344006) (xy 231.622573 -82.333314)
			(xy 231.622029 -82.310302) (xy 231.617266 -82.29981) (xy 231.598716 -82.262296) (xy 231.56794 -82.184465)
			(xy 231.544602 -82.10409) (xy 231.528909 -82.021879) (xy 231.520999 -81.938559) (xy 231.520492 -81.896712)
			(xy 231.520492 -81.89595) (xy 231.520996 -81.853602) (xy 231.529047 -81.769288) (xy 231.545076 -81.686122)
			(xy 231.568937 -81.604855) (xy 231.600416 -81.526225) (xy 231.639227 -81.450944) (xy 231.685017 -81.379692)
			(xy 231.737373 -81.313116) (xy 231.795821 -81.251818) (xy 231.859831 -81.196353) (xy 231.928823 -81.147224)
			(xy 232.002173 -81.104875) (xy 232.079216 -81.069691) (xy 232.159255 -81.041989) (xy 232.241564 -81.022021)
			(xy 232.325399 -81.009968) (xy 232.41 -81.005938) (xy 232.494601 -81.009968) (xy 232.578436 -81.022021)
			(xy 232.660745 -81.041989) (xy 232.740784 -81.069691) (xy 232.817827 -81.104875) (xy 232.891177 -81.147224)
			(xy 232.960169 -81.196353) (xy 233.024179 -81.251818) (xy 233.082627 -81.313116) (xy 233.134983 -81.379692)
			(xy 233.180773 -81.450944) (xy 233.219584 -81.526225) (xy 233.251063 -81.604855) (xy 233.274924 -81.686122)
			(xy 233.290953 -81.769288) (xy 233.299004 -81.853602) (xy 233.299508 -81.89595) (xy 233.298994 -81.937821)
			(xy 233.291121 -82.021191) (xy 233.27545 -82.103453) (xy 233.252119 -82.183878) (xy 233.221334 -82.261756)
			(xy 233.183369 -82.336396) (xy 233.138559 -82.40714) (xy 233.087299 -82.47336) (xy 233.030045 -82.534471)
			(xy 232.967303 -82.589932) (xy 232.899626 -82.639253) (xy 232.827616 -82.681996) (xy 232.751907 -82.717785)
			(xy 232.673171 -82.746302) (xy 232.632758 -82.757264) (xy 232.621916 -82.760738) (xy 232.604514 -82.775374)
			(xy 232.59923 -82.785458) (xy 232.566718 -82.857594) (xy 232.562427 -82.868286) (xy 232.562971 -82.891298)
			(xy 232.567734 -82.90179) (xy 232.586315 -82.939374) (xy 232.617134 -83.017352) (xy 232.640486 -83.097881)
			(xy 232.656166 -83.180249) (xy 232.664033 -83.263726) (xy 232.664508 -83.30565) (xy 232.664022 -83.347993)
			(xy 232.655995 -83.432297) (xy 232.639998 -83.515458) (xy 232.616178 -83.596725) (xy 232.584748 -83.675362)
			(xy 232.545992 -83.750659) (xy 232.500262 -83.821936) (xy 232.447971 -83.888549) (xy 232.419144 -83.919568)
			(xy 232.411956 -83.927948) (xy 232.404859 -83.948828) (xy 232.407134 -83.970764) (xy 232.412286 -83.980528)
			(xy 232.432279 -84.014995) (xy 232.46675 -84.086842) (xy 232.49466 -84.161483) (xy 232.515787 -84.238319)
			(xy 232.529962 -84.316736) (xy 232.537072 -84.396106) (xy 232.537508 -84.43595) (xy 232.537014 -84.480384)
			(xy 232.528235 -84.568816) (xy 232.519982 -84.61248) (xy 232.517442 -84.624418) (xy 232.524046 -84.647532)
			(xy 232.587546 -84.717128) (xy 232.596183 -84.72564) (xy 232.618873 -84.73411) (xy 232.63098 -84.733384)
			(xy 232.655662 -84.730773) (xy 232.705221 -84.72798) (xy 232.73004 -84.727796) (xy 232.77196 -84.728317)
			(xy 232.855429 -84.736211) (xy 232.937784 -84.751923) (xy 233.018296 -84.775316) (xy 233.096248 -84.806182)
			(xy 233.170951 -84.844245) (xy 233.24174 -84.88917) (xy 233.307987 -84.940557) (xy 233.369105 -84.997949)
			(xy 233.424551 -85.060838) (xy 233.473833 -85.128666) (xy 233.516514 -85.20083) (xy 233.552214 -85.27669)
			(xy 233.580618 -85.355573) (xy 233.601472 -85.436779) (xy 233.614592 -85.519587) (xy 233.619862 -85.603263)
			(xy 233.617234 -85.687062) (xy 233.606732 -85.770243) (xy 233.58845 -85.852066) (xy 233.562549 -85.931806)
			(xy 233.529259 -86.008755) (xy 233.488876 -86.082229) (xy 233.441757 -86.151577) (xy 233.388323 -86.216184)
			(xy 233.329046 -86.275476) (xy 233.264452 -86.328927) (xy 233.195115 -86.376062) (xy 233.12165 -86.416463)
			(xy 233.04471 -86.449771) (xy 232.964977 -86.475692) (xy 232.883158 -86.493995) (xy 232.79998 -86.504517)
			(xy 232.716181 -86.507165) (xy 232.632504 -86.501916) (xy 232.549693 -86.488816) (xy 232.468482 -86.467982)
			(xy 232.389592 -86.439598) (xy 232.313723 -86.403916) (xy 232.241548 -86.361253) (xy 232.173708 -86.311988)
			(xy 232.110806 -86.256557) (xy 232.053398 -86.195453) (xy 232.001995 -86.129218) (xy 231.957053 -86.05844)
			(xy 231.918971 -85.983747) (xy 231.888087 -85.905802) (xy 231.864674 -85.825296) (xy 231.848941 -85.742945)
			(xy 231.841027 -85.659478) (xy 231.840532 -85.617558) (xy 231.841027 -85.573124) (xy 231.849805 -85.484692)
			(xy 231.858058 -85.441028) (xy 231.860598 -85.42909) (xy 231.853994 -85.405976) (xy 231.790494 -85.33638)
			(xy 231.781839 -85.32789) (xy 231.759163 -85.319407) (xy 231.74706 -85.320124) (xy 231.722378 -85.322731)
			(xy 231.672819 -85.325527) (xy 231.648 -85.325712) (xy 231.606889 -85.325248) (xy 231.525019 -85.31766)
			(xy 231.444199 -85.302549) (xy 231.365118 -85.280044) (xy 231.288451 -85.250338) (xy 231.214853 -85.213682)
			(xy 231.144951 -85.170392) (xy 231.079343 -85.120835) (xy 231.018588 -85.065435) (xy 230.963205 -85.004665)
			(xy 230.913667 -84.939043) (xy 230.870396 -84.869129) (xy 230.833761 -84.79552) (xy 230.804076 -84.718845)
			(xy 230.781594 -84.639758) (xy 230.766506 -84.558933) (xy 230.758941 -84.477061) (xy 230.758492 -84.43595)
			(xy 230.758696 -84.404476) (xy 230.763021 -84.341679) (xy 230.767128 -84.310474) (xy 230.768906 -84.299298)
			(xy 230.762302 -84.277962) (xy 230.702612 -84.211414) (xy 230.694763 -84.203557) (xy 230.674346 -84.194874)
			(xy 230.663242 -84.19465) (xy 230.662734 -84.19465) (xy 230.632254 -84.195412) (xy 230.631746 -84.195412)
			(xy 230.590252 -84.194909) (xy 230.50763 -84.187124) (xy 230.426093 -84.171674) (xy 230.34635 -84.148693)
			(xy 230.269096 -84.118382) (xy 230.195003 -84.081003) (xy 230.124715 -84.036883) (xy 230.091488 -84.012024)
			(xy 230.082289 -84.005681) (xy 230.0605 -84.00085) (xy 230.038711 -84.005681) (xy 230.029512 -84.012024)
			(xy 229.996254 -84.036868) (xy 229.925928 -84.08099) (xy 229.851799 -84.118369) (xy 229.77451 -84.148682)
			(xy 229.694734 -84.171665) (xy 229.613164 -84.187117) (xy 229.53051 -84.194905) (xy 229.489 -84.195412)
			(xy 229.446642 -84.194808) (xy 229.362309 -84.186755) (xy 229.279124 -84.170723) (xy 229.197839 -84.146855)
			(xy 229.119191 -84.115369) (xy 229.043892 -84.07655) (xy 228.972624 -84.030749) (xy 228.906032 -83.978381)
			(xy 228.84472 -83.91992) (xy 228.789243 -83.855895) (xy 228.740102 -83.786887) (xy 228.697744 -83.713521)
			(xy 228.662552 -83.63646) (xy 228.634844 -83.556403) (xy 228.614871 -83.474075) (xy 228.602814 -83.39022)
			(xy 228.598784 -83.3056) (xy 220.472 -83.3056) (xy 220.472 -88.249703) (xy 221.360742 -88.249703)
			(xy 221.360742 -88.164981) (xy 221.368795 -88.080644) (xy 221.384829 -87.997454) (xy 221.408697 -87.916164)
			(xy 221.440185 -87.837512) (xy 221.479007 -87.762209) (xy 221.52481 -87.690937) (xy 221.577181 -87.624341)
			(xy 221.635646 -87.563026) (xy 221.699674 -87.507545) (xy 221.768686 -87.458402) (xy 221.842056 -87.416042)
			(xy 221.919121 -87.380847) (xy 221.999183 -87.353138) (xy 222.081516 -87.333164) (xy 222.165375 -87.321107)
			(xy 222.25 -87.317076) (xy 222.334625 -87.321107) (xy 222.418484 -87.333164) (xy 222.500817 -87.353138)
			(xy 222.580879 -87.380847) (xy 222.657944 -87.416042) (xy 222.731314 -87.458402) (xy 222.800326 -87.507545)
			(xy 222.864354 -87.563026) (xy 222.922819 -87.624341) (xy 222.97519 -87.690937) (xy 223.020993 -87.762209)
			(xy 223.040146 -87.799361) (xy 233.740702 -87.799361) (xy 233.740702 -87.714639) (xy 233.748755 -87.630302)
			(xy 233.764789 -87.547112) (xy 233.788657 -87.465822) (xy 233.820145 -87.38717) (xy 233.858967 -87.311867)
			(xy 233.90477 -87.240595) (xy 233.957141 -87.173999) (xy 234.015606 -87.112684) (xy 234.079634 -87.057203)
			(xy 234.148646 -87.00806) (xy 234.222016 -86.9657) (xy 234.299081 -86.930505) (xy 234.379143 -86.902796)
			(xy 234.461476 -86.882822) (xy 234.545335 -86.870765) (xy 234.62996 -86.866734) (xy 234.714585 -86.870765)
			(xy 234.798444 -86.882822) (xy 234.880777 -86.902796) (xy 234.960839 -86.930505) (xy 235.037904 -86.9657)
			(xy 235.111274 -87.00806) (xy 235.180286 -87.057203) (xy 235.244314 -87.112684) (xy 235.302779 -87.173999)
			(xy 235.35515 -87.240595) (xy 235.400953 -87.311867) (xy 235.439775 -87.38717) (xy 235.471263 -87.465822)
			(xy 235.495131 -87.547112) (xy 235.511165 -87.630302) (xy 235.511373 -87.632483) (xy 236.18342 -87.632483)
			(xy 236.18342 -87.547761) (xy 236.191473 -87.463424) (xy 236.207507 -87.380234) (xy 236.231375 -87.298944)
			(xy 236.262863 -87.220292) (xy 236.301685 -87.144989) (xy 236.347488 -87.073717) (xy 236.399859 -87.007121)
			(xy 236.458324 -86.945806) (xy 236.522352 -86.890325) (xy 236.591364 -86.841182) (xy 236.664734 -86.798822)
			(xy 236.741799 -86.763627) (xy 236.821861 -86.735918) (xy 236.904194 -86.715944) (xy 236.988053 -86.703887)
			(xy 237.072678 -86.699856) (xy 237.157303 -86.703887) (xy 237.241162 -86.715944) (xy 237.323495 -86.735918)
			(xy 237.403557 -86.763627) (xy 237.480622 -86.798822) (xy 237.553992 -86.841182) (xy 237.623004 -86.890325)
			(xy 237.687032 -86.945806) (xy 237.745497 -87.007121) (xy 237.797868 -87.073717) (xy 237.843671 -87.144989)
			(xy 237.882493 -87.220292) (xy 237.913981 -87.298944) (xy 237.937849 -87.380234) (xy 237.953883 -87.463424)
			(xy 237.961076 -87.538757) (xy 238.133632 -87.538757) (xy 238.133632 -87.454035) (xy 238.141685 -87.369698)
			(xy 238.157719 -87.286508) (xy 238.181587 -87.205218) (xy 238.213075 -87.126566) (xy 238.251897 -87.051263)
			(xy 238.2977 -86.979991) (xy 238.350071 -86.913395) (xy 238.408536 -86.85208) (xy 238.472564 -86.796599)
			(xy 238.541576 -86.747456) (xy 238.614946 -86.705096) (xy 238.692011 -86.669901) (xy 238.772073 -86.642192)
			(xy 238.854406 -86.622218) (xy 238.938265 -86.610161) (xy 239.02289 -86.60613) (xy 239.107515 -86.610161)
			(xy 239.191374 -86.622218) (xy 239.273707 -86.642192) (xy 239.353769 -86.669901) (xy 239.430834 -86.705096)
			(xy 239.504204 -86.747456) (xy 239.573216 -86.796599) (xy 239.637244 -86.85208) (xy 239.695709 -86.913395)
			(xy 239.74808 -86.979991) (xy 239.793883 -87.051263) (xy 239.832705 -87.126566) (xy 239.864193 -87.205218)
			(xy 239.888061 -87.286508) (xy 239.904095 -87.369698) (xy 239.912148 -87.454035) (xy 239.912652 -87.496396)
			(xy 239.912148 -87.538757) (xy 239.904095 -87.623094) (xy 239.888061 -87.706284) (xy 239.864193 -87.787574)
			(xy 239.832705 -87.866226) (xy 239.793883 -87.941529) (xy 239.74808 -88.012801) (xy 239.695709 -88.079397)
			(xy 239.637244 -88.140712) (xy 239.573216 -88.196193) (xy 239.504204 -88.245336) (xy 239.430834 -88.287696)
			(xy 239.353769 -88.322891) (xy 239.273707 -88.3506) (xy 239.191374 -88.370574) (xy 239.107515 -88.382631)
			(xy 239.02289 -88.386663) (xy 238.938265 -88.382631) (xy 238.854406 -88.370574) (xy 238.772073 -88.3506)
			(xy 238.692011 -88.322891) (xy 238.614946 -88.287696) (xy 238.541576 -88.245336) (xy 238.472564 -88.196193)
			(xy 238.408536 -88.140712) (xy 238.350071 -88.079397) (xy 238.2977 -88.012801) (xy 238.251897 -87.941529)
			(xy 238.213075 -87.866226) (xy 238.181587 -87.787574) (xy 238.157719 -87.706284) (xy 238.141685 -87.623094)
			(xy 238.133632 -87.538757) (xy 237.961076 -87.538757) (xy 237.961936 -87.547761) (xy 237.96244 -87.590122)
			(xy 237.961936 -87.632483) (xy 237.953883 -87.71682) (xy 237.937849 -87.80001) (xy 237.913981 -87.8813)
			(xy 237.882493 -87.959952) (xy 237.843671 -88.035255) (xy 237.797868 -88.106527) (xy 237.745497 -88.173123)
			(xy 237.687032 -88.234438) (xy 237.623004 -88.289919) (xy 237.553992 -88.339062) (xy 237.480622 -88.381422)
			(xy 237.403557 -88.416617) (xy 237.323495 -88.444326) (xy 237.241162 -88.4643) (xy 237.157303 -88.476357)
			(xy 237.072678 -88.480389) (xy 236.988053 -88.476357) (xy 236.904194 -88.4643) (xy 236.821861 -88.444326)
			(xy 236.741799 -88.416617) (xy 236.664734 -88.381422) (xy 236.591364 -88.339062) (xy 236.522352 -88.289919)
			(xy 236.458324 -88.234438) (xy 236.399859 -88.173123) (xy 236.347488 -88.106527) (xy 236.301685 -88.035255)
			(xy 236.262863 -87.959952) (xy 236.231375 -87.8813) (xy 236.207507 -87.80001) (xy 236.191473 -87.71682)
			(xy 236.18342 -87.632483) (xy 235.511373 -87.632483) (xy 235.519218 -87.714639) (xy 235.519722 -87.757)
			(xy 235.519218 -87.799361) (xy 235.511165 -87.883698) (xy 235.495131 -87.966888) (xy 235.471263 -88.048178)
			(xy 235.439775 -88.12683) (xy 235.400953 -88.202133) (xy 235.35515 -88.273405) (xy 235.302779 -88.340001)
			(xy 235.244314 -88.401316) (xy 235.180286 -88.456797) (xy 235.111274 -88.50594) (xy 235.037904 -88.5483)
			(xy 234.960839 -88.583495) (xy 234.880777 -88.611204) (xy 234.798444 -88.631178) (xy 234.714585 -88.643235)
			(xy 234.62996 -88.647267) (xy 234.545335 -88.643235) (xy 234.461476 -88.631178) (xy 234.379143 -88.611204)
			(xy 234.299081 -88.583495) (xy 234.222016 -88.5483) (xy 234.148646 -88.50594) (xy 234.079634 -88.456797)
			(xy 234.015606 -88.401316) (xy 233.957141 -88.340001) (xy 233.90477 -88.273405) (xy 233.858967 -88.202133)
			(xy 233.820145 -88.12683) (xy 233.788657 -88.048178) (xy 233.764789 -87.966888) (xy 233.748755 -87.883698)
			(xy 233.740702 -87.799361) (xy 223.040146 -87.799361) (xy 223.059815 -87.837512) (xy 223.091303 -87.916164)
			(xy 223.115171 -87.997454) (xy 223.131205 -88.080644) (xy 223.139258 -88.164981) (xy 223.139762 -88.207342)
			(xy 223.139258 -88.249703) (xy 223.131205 -88.33404) (xy 223.115171 -88.41723) (xy 223.091303 -88.49852)
			(xy 223.059815 -88.577172) (xy 223.020993 -88.652475) (xy 222.97519 -88.723747) (xy 222.922819 -88.790343)
			(xy 222.864354 -88.851658) (xy 222.800326 -88.907139) (xy 222.731314 -88.956282) (xy 222.657944 -88.998642)
			(xy 222.580879 -89.033837) (xy 222.500817 -89.061546) (xy 222.418484 -89.08152) (xy 222.334625 -89.093577)
			(xy 222.25 -89.097609) (xy 222.165375 -89.093577) (xy 222.081516 -89.08152) (xy 221.999183 -89.061546)
			(xy 221.919121 -89.033837) (xy 221.842056 -88.998642) (xy 221.768686 -88.956282) (xy 221.699674 -88.907139)
			(xy 221.635646 -88.851658) (xy 221.577181 -88.790343) (xy 221.52481 -88.723747) (xy 221.479007 -88.652475)
			(xy 221.440185 -88.577172) (xy 221.408697 -88.49852) (xy 221.384829 -88.41723) (xy 221.368795 -88.33404)
			(xy 221.360742 -88.249703) (xy 220.472 -88.249703) (xy 220.472 -90.587576) (xy 220.472536 -90.598597)
			(xy 220.481749 -90.618619) (xy 220.48978 -90.626184) (xy 220.55709 -90.683588) (xy 220.578172 -90.689684)
			(xy 220.589094 -90.687906) (xy 220.623106 -90.682991) (xy 220.691636 -90.677777) (xy 220.726 -90.677492)
			(xy 220.768085 -90.677959) (xy 220.851884 -90.685861) (xy 220.934562 -90.70164) (xy 221.01538 -90.725157)
			(xy 221.054676 -90.74023) (xy 221.063566 -90.743786) (xy 221.083378 -90.743786) (xy 221.157546 -90.713814)
			(xy 221.166375 -90.709773) (xy 221.180358 -90.696324) (xy 221.184724 -90.687652) (xy 221.202634 -90.649033)
			(xy 221.244802 -90.575077) (xy 221.293844 -90.505489) (xy 221.34931 -90.440904) (xy 221.410693 -90.381914)
			(xy 221.477432 -90.329059) (xy 221.548915 -90.282822) (xy 221.624488 -90.243627) (xy 221.703461 -90.211831)
			(xy 221.785111 -90.187726) (xy 221.86869 -90.171533) (xy 221.953433 -90.163399) (xy 221.996 -90.162888)
			(xy 222.038319 -90.163418) (xy 222.122571 -90.171508) (xy 222.205674 -90.187559) (xy 222.286879 -90.211425)
			(xy 222.365452 -90.242891) (xy 222.440683 -90.281673) (xy 222.476568 -90.304112) (xy 222.484962 -90.308975)
			(xy 222.504 -90.312628) (xy 222.523038 -90.308975) (xy 222.531432 -90.304112) (xy 222.567305 -90.281651)
			(xy 222.642532 -90.242856) (xy 222.721106 -90.211384) (xy 222.802314 -90.18752) (xy 222.885423 -90.17148)
			(xy 222.969679 -90.163409) (xy 223.012 -90.162888) (xy 223.052325 -90.16334) (xy 223.132644 -90.170639)
			(xy 223.211973 -90.185176) (xy 223.289661 -90.206833) (xy 223.36507 -90.235431) (xy 223.437582 -90.270737)
			(xy 223.506601 -90.312459) (xy 223.571561 -90.360257) (xy 223.602042 -90.386662) (xy 223.609127 -90.392457)
			(xy 223.626177 -90.399083) (xy 223.635316 -90.399616) (xy 223.665034 -90.399616) (xy 223.67427 -90.399316)
			(xy 223.6916 -90.392942) (xy 223.698816 -90.38717) (xy 223.730347 -90.360399) (xy 223.797558 -90.31218)
			(xy 223.86896 -90.270414) (xy 223.943932 -90.235462) (xy 224.021829 -90.207629) (xy 224.061782 -90.196924)
			(xy 224.072958 -90.19413) (xy 224.090992 -90.179144) (xy 224.128076 -90.09634) (xy 224.132321 -90.085555)
			(xy 224.131672 -90.062408) (xy 224.126806 -90.05189) (xy 224.107774 -90.014006) (xy 224.076182 -89.935326)
			(xy 224.052219 -89.853996) (xy 224.036105 -89.770755) (xy 224.027983 -89.686359) (xy 224.027492 -89.643966)
			(xy 224.027492 -89.64295) (xy 224.027996 -89.600602) (xy 224.036047 -89.516288) (xy 224.052076 -89.433122)
			(xy 224.075937 -89.351855) (xy 224.107416 -89.273225) (xy 224.146227 -89.197944) (xy 224.192017 -89.126692)
			(xy 224.244373 -89.060116) (xy 224.302821 -88.998818) (xy 224.366831 -88.943353) (xy 224.435823 -88.894224)
			(xy 224.509173 -88.851875) (xy 224.586216 -88.816691) (xy 224.666255 -88.788989) (xy 224.748564 -88.769021)
			(xy 224.832399 -88.756968) (xy 224.917 -88.752938) (xy 225.001601 -88.756968) (xy 225.085436 -88.769021)
			(xy 225.167745 -88.788989) (xy 225.247784 -88.816691) (xy 225.324827 -88.851875) (xy 225.398177 -88.894224)
			(xy 225.467169 -88.943353) (xy 225.531179 -88.998818) (xy 225.589627 -89.060116) (xy 225.641983 -89.126692)
			(xy 225.687773 -89.197944) (xy 225.726584 -89.273225) (xy 225.758063 -89.351855) (xy 225.781924 -89.433122)
			(xy 225.797953 -89.516288) (xy 225.799904 -89.536721) (xy 227.980744 -89.536721) (xy 227.980744 -89.451999)
			(xy 227.988797 -89.367662) (xy 228.004831 -89.284472) (xy 228.028699 -89.203182) (xy 228.060187 -89.12453)
			(xy 228.099009 -89.049227) (xy 228.144812 -88.977955) (xy 228.197183 -88.911359) (xy 228.255648 -88.850044)
			(xy 228.319676 -88.794563) (xy 228.388688 -88.74542) (xy 228.462058 -88.70306) (xy 228.539123 -88.667865)
			(xy 228.619185 -88.640156) (xy 228.701518 -88.620182) (xy 228.785377 -88.608125) (xy 228.870002 -88.604094)
			(xy 228.954627 -88.608125) (xy 229.038486 -88.620182) (xy 229.120819 -88.640156) (xy 229.200881 -88.667865)
			(xy 229.277946 -88.70306) (xy 229.351316 -88.74542) (xy 229.420328 -88.794563) (xy 229.484356 -88.850044)
			(xy 229.542821 -88.911359) (xy 229.595192 -88.977955) (xy 229.640995 -89.049227) (xy 229.679817 -89.12453)
			(xy 229.711305 -89.203182) (xy 229.735173 -89.284472) (xy 229.751207 -89.367662) (xy 229.75926 -89.451999)
			(xy 229.759764 -89.49436) (xy 229.75926 -89.536721) (xy 229.751207 -89.621058) (xy 229.735173 -89.704248)
			(xy 229.711305 -89.785538) (xy 229.679817 -89.86419) (xy 229.640995 -89.939493) (xy 229.595192 -90.010765)
			(xy 229.542821 -90.077361) (xy 229.484356 -90.138676) (xy 229.420328 -90.194157) (xy 229.351316 -90.2433)
			(xy 229.277946 -90.28566) (xy 229.200881 -90.320855) (xy 229.120819 -90.348564) (xy 229.038486 -90.368538)
			(xy 228.954627 -90.380595) (xy 228.870002 -90.384627) (xy 228.785377 -90.380595) (xy 228.701518 -90.368538)
			(xy 228.619185 -90.348564) (xy 228.539123 -90.320855) (xy 228.462058 -90.28566) (xy 228.388688 -90.2433)
			(xy 228.319676 -90.194157) (xy 228.255648 -90.138676) (xy 228.197183 -90.077361) (xy 228.144812 -90.010765)
			(xy 228.099009 -89.939493) (xy 228.060187 -89.86419) (xy 228.028699 -89.785538) (xy 228.004831 -89.704248)
			(xy 227.988797 -89.621058) (xy 227.980744 -89.536721) (xy 225.799904 -89.536721) (xy 225.806004 -89.600602)
			(xy 225.806508 -89.64295) (xy 225.806021 -89.684918) (xy 225.798112 -89.76848) (xy 225.782371 -89.850927)
			(xy 225.758936 -89.931525) (xy 225.728016 -90.009558) (xy 225.689886 -90.084333) (xy 225.644884 -90.155186)
			(xy 225.593411 -90.221486) (xy 225.535923 -90.282645) (xy 225.472932 -90.338119) (xy 225.404998 -90.387415)
			(xy 225.332723 -90.430095) (xy 225.256751 -90.46578) (xy 225.177756 -90.494153) (xy 225.137218 -90.505026)
			(xy 225.126042 -90.50782) (xy 225.108008 -90.522806) (xy 225.070924 -90.60561) (xy 225.066691 -90.616394)
			(xy 225.06736 -90.63953) (xy 225.072194 -90.65006) (xy 225.091224 -90.687944) (xy 225.122812 -90.766626)
			(xy 225.146769 -90.847955) (xy 225.16288 -90.931196) (xy 225.170996 -91.015592) (xy 225.171508 -91.057984)
			(xy 225.171508 -91.059) (xy 225.171033 -91.100102) (xy 225.163448 -91.181957) (xy 225.148343 -91.262762)
			(xy 225.125847 -91.341829) (xy 225.096151 -91.418483) (xy 225.059509 -91.49207) (xy 225.016234 -91.561962)
			(xy 224.966694 -91.627563) (xy 224.911313 -91.688313) (xy 224.850563 -91.743694) (xy 224.784962 -91.793234)
			(xy 224.71507 -91.836509) (xy 224.641483 -91.873151) (xy 224.564829 -91.902847) (xy 224.485762 -91.925343)
			(xy 224.404957 -91.940448) (xy 224.323102 -91.948033) (xy 224.282 -91.948508) (xy 224.281492 -91.948508)
			(xy 224.241206 -91.94804) (xy 224.160968 -91.940722) (xy 224.081718 -91.926183) (xy 224.004108 -91.904541)
			(xy 223.92877 -91.875975) (xy 223.856322 -91.840717) (xy 223.787357 -91.799056) (xy 223.722439 -91.751334)
			(xy 223.691958 -91.724988) (xy 223.684875 -91.719188) (xy 223.667824 -91.712556) (xy 223.658684 -91.712034)
			(xy 223.628966 -91.712034) (xy 223.61973 -91.712335) (xy 223.602404 -91.718714) (xy 223.595184 -91.72448)
			(xy 223.564879 -91.750222) (xy 223.50043 -91.796802) (xy 223.43208 -91.837444) (xy 223.360375 -91.871821)
			(xy 223.285888 -91.899661) (xy 223.209212 -91.920739) (xy 223.130962 -91.934889) (xy 223.05176 -91.941997)
			(xy 223.012 -91.942412) (xy 222.969681 -91.941882) (xy 222.885429 -91.933792) (xy 222.802326 -91.917741)
			(xy 222.721121 -91.893875) (xy 222.642548 -91.862409) (xy 222.567317 -91.823627) (xy 222.531432 -91.801188)
			(xy 222.523038 -91.796325) (xy 222.504 -91.792672) (xy 222.484962 -91.796325) (xy 222.476568 -91.801188)
			(xy 222.440695 -91.823649) (xy 222.365468 -91.862444) (xy 222.286894 -91.893916) (xy 222.205686 -91.91778)
			(xy 222.122577 -91.93382) (xy 222.038321 -91.941891) (xy 221.996 -91.942412) (xy 221.95391 -91.941904)
			(xy 221.870109 -91.933925) (xy 221.787435 -91.918075) (xy 221.706624 -91.894497) (xy 221.667324 -91.87942)
			(xy 221.658434 -91.875864) (xy 221.638622 -91.875864) (xy 221.564454 -91.905836) (xy 221.555629 -91.90988)
			(xy 221.541658 -91.923335) (xy 221.537276 -91.931998) (xy 221.520276 -91.968643) (xy 221.480566 -92.038998)
			(xy 221.434642 -92.105463) (xy 221.382883 -92.167493) (xy 221.325715 -92.224576) (xy 221.29496 -92.250768)
			(xy 221.287086 -92.257372) (xy 221.277942 -92.274898) (xy 221.270576 -92.35694) (xy 221.270039 -92.366939)
			(xy 221.275941 -92.386056) (xy 221.282006 -92.394024) (xy 221.283022 -92.39504) (xy 221.290134 -92.403676)
			(xy 221.310454 -92.413328) (xy 221.411546 -92.413328) (xy 221.431866 -92.403676) (xy 221.438978 -92.39504)
			(xy 221.467105 -92.362046) (xy 221.528783 -92.301107) (xy 221.596098 -92.246458) (xy 221.668412 -92.198619)
			(xy 221.745038 -92.158044) (xy 221.825248 -92.125118) (xy 221.908282 -92.100154) (xy 221.993351 -92.083388)
			(xy 222.079647 -92.07498) (xy 222.123 -92.074492) (xy 222.169396 -92.075077) (xy 222.261686 -92.08471)
			(xy 222.352471 -92.103903) (xy 222.440764 -92.132447) (xy 222.483426 -92.150692) (xy 222.493368 -92.154498)
			(xy 222.514632 -92.154498) (xy 222.524574 -92.150692) (xy 222.567239 -92.132454) (xy 222.655532 -92.103916)
			(xy 222.746316 -92.08472) (xy 222.838604 -92.075075) (xy 222.885 -92.074492) (xy 222.928785 -92.075002)
			(xy 223.015933 -92.083579) (xy 223.101817 -92.100681) (xy 223.185603 -92.126142) (xy 223.266482 -92.159714)
			(xy 223.343669 -92.201073) (xy 223.416417 -92.249819) (xy 223.484021 -92.305479) (xy 223.545828 -92.367514)
			(xy 223.601238 -92.435324) (xy 223.625918 -92.471494) (xy 223.63303 -92.481908) (xy 223.655382 -92.4941)
			(xy 223.765618 -92.4941) (xy 223.78797 -92.481908) (xy 223.795082 -92.471494) (xy 223.819762 -92.435324)
			(xy 223.87518 -92.367522) (xy 223.936991 -92.305492) (xy 224.004597 -92.249835) (xy 224.077345 -92.20109)
			(xy 224.15453 -92.159728) (xy 224.235406 -92.12615) (xy 224.319189 -92.10068) (xy 224.405069 -92.083566)
			(xy 224.492215 -92.074972) (xy 224.536 -92.074492) (xy 224.582396 -92.075077) (xy 224.674686 -92.08471)
			(xy 224.765471 -92.103903) (xy 224.853764 -92.132447) (xy 224.896426 -92.150692) (xy 224.906368 -92.154498)
			(xy 224.927632 -92.154498) (xy 224.937574 -92.150692) (xy 224.980239 -92.132454) (xy 225.068532 -92.103916)
			(xy 225.159316 -92.08472) (xy 225.251604 -92.075075) (xy 225.298 -92.074492) (xy 225.341785 -92.075002)
			(xy 225.428933 -92.083579) (xy 225.514817 -92.100681) (xy 225.598603 -92.126142) (xy 225.679482 -92.159714)
			(xy 225.756669 -92.201073) (xy 225.829417 -92.249819) (xy 225.897021 -92.305479) (xy 225.958828 -92.367514)
			(xy 226.014238 -92.435324) (xy 226.038918 -92.471494) (xy 226.04603 -92.481908) (xy 226.068382 -92.4941)
			(xy 226.178618 -92.4941) (xy 226.20097 -92.481908) (xy 226.208082 -92.471494) (xy 226.232762 -92.435324)
			(xy 226.28818 -92.367522) (xy 226.349991 -92.305492) (xy 226.417597 -92.249835) (xy 226.490345 -92.20109)
			(xy 226.56753 -92.159728) (xy 226.648406 -92.12615) (xy 226.732189 -92.10068) (xy 226.818069 -92.083566)
			(xy 226.905215 -92.074972) (xy 226.949 -92.074492) (xy 226.995396 -92.075077) (xy 227.087686 -92.08471)
			(xy 227.178471 -92.103903) (xy 227.266764 -92.132447) (xy 227.309426 -92.150692) (xy 227.319368 -92.154498)
			(xy 227.340632 -92.154498) (xy 227.350574 -92.150692) (xy 227.393239 -92.132454) (xy 227.481532 -92.103916)
			(xy 227.572316 -92.08472) (xy 227.664604 -92.075075) (xy 227.711 -92.074492) (xy 227.754785 -92.075002)
			(xy 227.841933 -92.083579) (xy 227.927817 -92.100681) (xy 228.011603 -92.126142) (xy 228.092482 -92.159714)
			(xy 228.169669 -92.201073) (xy 228.242417 -92.249819) (xy 228.310021 -92.305479) (xy 228.371828 -92.367514)
			(xy 228.427238 -92.435324) (xy 228.451918 -92.471494) (xy 228.45903 -92.481908) (xy 228.481382 -92.4941)
			(xy 228.591618 -92.4941) (xy 228.61397 -92.481908) (xy 228.621082 -92.471494) (xy 228.645762 -92.435324)
			(xy 228.70118 -92.367522) (xy 228.762991 -92.305492) (xy 228.830597 -92.249835) (xy 228.903345 -92.20109)
			(xy 228.98053 -92.159728) (xy 229.061406 -92.12615) (xy 229.145189 -92.10068) (xy 229.231069 -92.083566)
			(xy 229.318215 -92.074972) (xy 229.362 -92.074492) (xy 229.408396 -92.075077) (xy 229.500686 -92.08471)
			(xy 229.591471 -92.103903) (xy 229.679764 -92.132447) (xy 229.722426 -92.150692) (xy 229.732368 -92.154498)
			(xy 229.753632 -92.154498) (xy 229.763574 -92.150692) (xy 229.806239 -92.132454) (xy 229.894532 -92.103916)
			(xy 229.985316 -92.08472) (xy 230.077604 -92.075075) (xy 230.124 -92.074492) (xy 230.161541 -92.074862)
			(xy 230.23636 -92.081149) (xy 230.310382 -92.093721) (xy 230.383081 -92.112487) (xy 230.41864 -92.12453)
			(xy 230.43261 -92.12961) (xy 230.460804 -92.12326) (xy 230.536242 -92.048838) (xy 230.542639 -92.041848)
			(xy 230.550323 -92.024545) (xy 230.551252 -92.005636) (xy 230.548688 -91.996514) (xy 230.548688 -91.99626)
			(xy 230.534027 -91.950543) (xy 230.513464 -91.85676) (xy 230.503112 -91.761309) (xy 230.50246 -91.713304)
			(xy 230.50246 -91.71305) (xy 230.502964 -91.670702) (xy 230.511015 -91.586388) (xy 230.527044 -91.503222)
			(xy 230.550905 -91.421955) (xy 230.582384 -91.343325) (xy 230.621195 -91.268044) (xy 230.666985 -91.196792)
			(xy 230.719341 -91.130216) (xy 230.777789 -91.068918) (xy 230.841799 -91.013453) (xy 230.910791 -90.964324)
			(xy 230.984141 -90.921975) (xy 231.061184 -90.886791) (xy 231.141223 -90.859089) (xy 231.223532 -90.839121)
			(xy 231.307367 -90.827068) (xy 231.391968 -90.823038) (xy 231.476569 -90.827068) (xy 231.560404 -90.839121)
			(xy 231.642713 -90.859089) (xy 231.722752 -90.886791) (xy 231.799795 -90.921975) (xy 231.873145 -90.964324)
			(xy 231.942137 -91.013453) (xy 232.006147 -91.068918) (xy 232.064595 -91.130216) (xy 232.116951 -91.196792)
			(xy 232.162741 -91.268044) (xy 232.201552 -91.343325) (xy 232.233031 -91.421955) (xy 232.256892 -91.503222)
			(xy 232.272921 -91.586388) (xy 232.280972 -91.670702) (xy 232.281476 -91.71305) (xy 232.281476 -91.713812)
			(xy 232.280955 -91.755959) (xy 232.272932 -91.83987) (xy 232.257016 -91.922648) (xy 232.245662 -91.96324)
			(xy 232.245662 -91.963494) (xy 232.243578 -91.971937) (xy 232.244574 -91.989287) (xy 232.25128 -92.005319)
			(xy 232.256838 -92.012008) (xy 232.324656 -92.085922) (xy 232.350056 -92.09405) (xy 232.36301 -92.09151)
			(xy 232.406059 -92.083494) (xy 232.493214 -92.074964) (xy 232.537 -92.074492) (xy 232.580785 -92.075002)
			(xy 232.667933 -92.083579) (xy 232.753817 -92.100681) (xy 232.837603 -92.126142) (xy 232.918482 -92.159714)
			(xy 232.995669 -92.201073) (xy 233.068417 -92.249819) (xy 233.136021 -92.305479) (xy 233.197828 -92.367514)
			(xy 233.253238 -92.435324) (xy 233.277918 -92.471494) (xy 233.28503 -92.481908) (xy 233.307382 -92.4941)
			(xy 233.417618 -92.4941) (xy 233.43997 -92.481908) (xy 233.447082 -92.471494) (xy 233.471762 -92.435324)
			(xy 233.52718 -92.367522) (xy 233.588991 -92.305492) (xy 233.656597 -92.249835) (xy 233.729345 -92.20109)
			(xy 233.80653 -92.159728) (xy 233.887406 -92.12615) (xy 233.971189 -92.10068) (xy 234.057069 -92.083566)
			(xy 234.144215 -92.074972) (xy 234.188 -92.074492) (xy 234.234396 -92.075077) (xy 234.326686 -92.08471)
			(xy 234.417471 -92.103903) (xy 234.505764 -92.132447) (xy 234.548426 -92.150692) (xy 234.558368 -92.154498)
			(xy 234.579632 -92.154498) (xy 234.589574 -92.150692) (xy 234.597448 -92.147136) (xy 234.606358 -92.142812)
			(xy 234.620222 -92.128696) (xy 234.624372 -92.119704) (xy 234.636056 -92.091256) (xy 234.639274 -92.081921)
			(xy 234.639141 -92.062194) (xy 234.635802 -92.052902) (xy 234.619674 -92.012432) (xy 234.594468 -91.929034)
			(xy 234.577528 -91.843573) (xy 234.569017 -91.756866) (xy 234.568492 -91.713304) (xy 234.568492 -91.71305)
			(xy 234.56893 -91.673951) (xy 234.575817 -91.596056) (xy 234.589508 -91.519066) (xy 234.609898 -91.443572)
			(xy 234.636829 -91.370157) (xy 234.653074 -91.33459) (xy 234.65731 -91.324203) (xy 234.65731 -91.301797)
			(xy 234.653074 -91.29141) (xy 234.636811 -91.255849) (xy 234.609859 -91.182439) (xy 234.589461 -91.106944)
			(xy 234.575772 -91.02995) (xy 234.568898 -90.952051) (xy 234.568492 -90.91295) (xy 234.568492 -90.906854)
			(xy 234.568062 -90.896228) (xy 234.559664 -90.876717) (xy 234.544077 -90.862286) (xy 234.534202 -90.85834)
			(xy 234.443016 -90.827098) (xy 234.432811 -90.824173) (xy 234.411681 -90.825955) (xy 234.393042 -90.836068)
			(xy 234.38612 -90.844116) (xy 234.38612 -90.84437) (xy 234.360946 -90.87648) (xy 234.305607 -90.936444)
			(xy 234.245011 -90.99109) (xy 234.179665 -91.039959) (xy 234.11012 -91.082639) (xy 234.03696 -91.118773)
			(xy 233.960798 -91.148058) (xy 233.882275 -91.170246) (xy 233.802051 -91.185151) (xy 233.720799 -91.192649)
			(xy 233.68 -91.193112) (xy 233.637111 -91.192597) (xy 233.551732 -91.184336) (xy 233.467546 -91.167891)
			(xy 233.385334 -91.143414) (xy 233.305862 -91.111134) (xy 233.229868 -91.07135) (xy 233.158059 -91.024432)
			(xy 233.124248 -90.99804) (xy 233.116909 -90.992662) (xy 233.09963 -90.987006) (xy 233.081464 -90.987747)
			(xy 233.07294 -90.990928) (xy 233.032237 -91.007327) (xy 232.948306 -91.032965) (xy 232.862261 -91.050222)
			(xy 232.774935 -91.05893) (xy 232.731056 -91.059508) (xy 232.73004 -91.059508) (xy 232.68769 -91.059022)
			(xy 232.603372 -91.050974) (xy 232.520201 -91.034948) (xy 232.43893 -91.011088) (xy 232.360295 -90.97961)
			(xy 232.285009 -90.9408) (xy 232.213753 -90.895009) (xy 232.147172 -90.842653) (xy 232.08587 -90.784204)
			(xy 232.030401 -90.720192) (xy 231.981269 -90.651198) (xy 231.938917 -90.577845) (xy 231.90373 -90.500799)
			(xy 231.876026 -90.420757) (xy 231.856057 -90.338444) (xy 231.844002 -90.254605) (xy 231.839972 -90.17)
			(xy 231.844002 -90.085395) (xy 231.856057 -90.001556) (xy 231.876026 -89.919243) (xy 231.90373 -89.839201)
			(xy 231.938917 -89.762155) (xy 231.981269 -89.688802) (xy 232.030401 -89.619808) (xy 232.08587 -89.555796)
			(xy 232.147172 -89.497347) (xy 232.213753 -89.444991) (xy 232.285009 -89.3992) (xy 232.360295 -89.36039)
			(xy 232.43893 -89.328912) (xy 232.520201 -89.305052) (xy 232.603372 -89.289026) (xy 232.68769 -89.280978)
			(xy 232.73004 -89.280492) (xy 232.730548 -89.280492) (xy 232.773394 -89.281016) (xy 232.858685 -89.289284)
			(xy 232.942786 -89.305718) (xy 233.024916 -89.330166) (xy 233.104313 -89.362402) (xy 233.18024 -89.402126)
			(xy 233.251994 -89.44897) (xy 233.285792 -89.47531) (xy 233.29313 -89.480685) (xy 233.310407 -89.486334)
			(xy 233.328568 -89.48558) (xy 233.3371 -89.482422) (xy 233.377914 -89.465939) (xy 233.462087 -89.440173)
			(xy 233.548392 -89.422845) (xy 233.635986 -89.414123) (xy 233.68 -89.413588) (xy 233.721111 -89.414048)
			(xy 233.802981 -89.421636) (xy 233.883802 -89.436747) (xy 233.962884 -89.459252) (xy 234.039551 -89.488959)
			(xy 234.113149 -89.525614) (xy 234.183051 -89.568905) (xy 234.24866 -89.618462) (xy 234.309415 -89.673862)
			(xy 234.364798 -89.734633) (xy 234.410974 -89.795801) (xy 236.142526 -89.795801) (xy 236.142526 -89.711079)
			(xy 236.150579 -89.626742) (xy 236.166613 -89.543552) (xy 236.190481 -89.462262) (xy 236.221969 -89.38361)
			(xy 236.260791 -89.308307) (xy 236.306594 -89.237035) (xy 236.358965 -89.170439) (xy 236.41743 -89.109124)
			(xy 236.481458 -89.053643) (xy 236.55047 -89.0045) (xy 236.62384 -88.96214) (xy 236.700905 -88.926945)
			(xy 236.780967 -88.899236) (xy 236.8633 -88.879262) (xy 236.947159 -88.867205) (xy 237.031784 -88.863174)
			(xy 237.116409 -88.867205) (xy 237.200268 -88.879262) (xy 237.282601 -88.899236) (xy 237.362663 -88.926945)
			(xy 237.439728 -88.96214) (xy 237.513098 -89.0045) (xy 237.58211 -89.053643) (xy 237.646138 -89.109124)
			(xy 237.704603 -89.170439) (xy 237.756974 -89.237035) (xy 237.802777 -89.308307) (xy 237.841599 -89.38361)
			(xy 237.873087 -89.462262) (xy 237.896955 -89.543552) (xy 237.897841 -89.548151) (xy 238.857532 -89.548151)
			(xy 238.857532 -89.463429) (xy 238.865585 -89.379092) (xy 238.881619 -89.295902) (xy 238.905487 -89.214612)
			(xy 238.936975 -89.13596) (xy 238.975797 -89.060657) (xy 239.0216 -88.989385) (xy 239.073971 -88.922789)
			(xy 239.132436 -88.861474) (xy 239.196464 -88.805993) (xy 239.265476 -88.75685) (xy 239.338846 -88.71449)
			(xy 239.415911 -88.679295) (xy 239.495973 -88.651586) (xy 239.578306 -88.631612) (xy 239.662165 -88.619555)
			(xy 239.74679 -88.615524) (xy 239.831415 -88.619555) (xy 239.915274 -88.631612) (xy 239.997607 -88.651586)
			(xy 240.077669 -88.679295) (xy 240.154734 -88.71449) (xy 240.228104 -88.75685) (xy 240.297116 -88.805993)
			(xy 240.361144 -88.861474) (xy 240.419609 -88.922789) (xy 240.47198 -88.989385) (xy 240.517783 -89.060657)
			(xy 240.556605 -89.13596) (xy 240.588093 -89.214612) (xy 240.611961 -89.295902) (xy 240.627995 -89.379092)
			(xy 240.636048 -89.463429) (xy 240.636552 -89.50579) (xy 240.636048 -89.548151) (xy 240.627995 -89.632488)
			(xy 240.611961 -89.715678) (xy 240.588093 -89.796968) (xy 240.556605 -89.87562) (xy 240.517783 -89.950923)
			(xy 240.47198 -90.022195) (xy 240.419609 -90.088791) (xy 240.361144 -90.150106) (xy 240.297116 -90.205587)
			(xy 240.228104 -90.25473) (xy 240.154734 -90.29709) (xy 240.077669 -90.332285) (xy 239.997607 -90.359994)
			(xy 239.915274 -90.379968) (xy 239.831415 -90.392025) (xy 239.74679 -90.396057) (xy 239.662165 -90.392025)
			(xy 239.578306 -90.379968) (xy 239.495973 -90.359994) (xy 239.415911 -90.332285) (xy 239.338846 -90.29709)
			(xy 239.265476 -90.25473) (xy 239.196464 -90.205587) (xy 239.132436 -90.150106) (xy 239.073971 -90.088791)
			(xy 239.0216 -90.022195) (xy 238.975797 -89.950923) (xy 238.936975 -89.87562) (xy 238.905487 -89.796968)
			(xy 238.881619 -89.715678) (xy 238.865585 -89.632488) (xy 238.857532 -89.548151) (xy 237.897841 -89.548151)
			(xy 237.912989 -89.626742) (xy 237.921042 -89.711079) (xy 237.921546 -89.75344) (xy 237.921042 -89.795801)
			(xy 237.912989 -89.880138) (xy 237.896955 -89.963328) (xy 237.873087 -90.044618) (xy 237.841599 -90.12327)
			(xy 237.802777 -90.198573) (xy 237.756974 -90.269845) (xy 237.704603 -90.336441) (xy 237.646138 -90.397756)
			(xy 237.58211 -90.453237) (xy 237.513098 -90.50238) (xy 237.439728 -90.54474) (xy 237.362663 -90.579935)
			(xy 237.282601 -90.607644) (xy 237.200268 -90.627618) (xy 237.116409 -90.639675) (xy 237.031784 -90.643707)
			(xy 236.947159 -90.639675) (xy 236.8633 -90.627618) (xy 236.780967 -90.607644) (xy 236.700905 -90.579935)
			(xy 236.62384 -90.54474) (xy 236.55047 -90.50238) (xy 236.481458 -90.453237) (xy 236.41743 -90.397756)
			(xy 236.358965 -90.336441) (xy 236.306594 -90.269845) (xy 236.260791 -90.198573) (xy 236.221969 -90.12327)
			(xy 236.190481 -90.044618) (xy 236.166613 -89.963328) (xy 236.150579 -89.880138) (xy 236.142526 -89.795801)
			(xy 234.410974 -89.795801) (xy 234.414336 -89.800255) (xy 234.457608 -89.870169) (xy 234.494242 -89.943778)
			(xy 234.523928 -90.020454) (xy 234.54641 -90.099541) (xy 234.561498 -90.180367) (xy 234.569063 -90.262239)
			(xy 234.569508 -90.30335) (xy 234.569508 -90.309446) (xy 234.569938 -90.320072) (xy 234.578336 -90.339583)
			(xy 234.593923 -90.354014) (xy 234.603798 -90.35796) (xy 234.694984 -90.389202) (xy 234.705189 -90.392127)
			(xy 234.726319 -90.390345) (xy 234.744958 -90.380232) (xy 234.75188 -90.372184) (xy 234.75188 -90.37193)
			(xy 234.777054 -90.33982) (xy 234.832393 -90.279856) (xy 234.892989 -90.22521) (xy 234.958335 -90.176341)
			(xy 235.02788 -90.133661) (xy 235.10104 -90.097527) (xy 235.177202 -90.068242) (xy 235.255725 -90.046054)
			(xy 235.335949 -90.031149) (xy 235.417201 -90.023651) (xy 235.458 -90.023188) (xy 235.499095 -90.023662)
			(xy 235.580935 -90.031244) (xy 235.661726 -90.046344) (xy 235.74078 -90.068832) (xy 235.817422 -90.098518)
			(xy 235.890999 -90.135147) (xy 235.960883 -90.178407) (xy 236.026478 -90.22793) (xy 236.087225 -90.283293)
			(xy 236.142605 -90.344024) (xy 236.192147 -90.409604) (xy 236.235428 -90.479476) (xy 236.272078 -90.553042)
			(xy 236.301785 -90.629675) (xy 236.324297 -90.708723) (xy 236.33942 -90.78951) (xy 236.347026 -90.871347)
			(xy 236.347508 -90.912442) (xy 236.347508 -90.91295) (xy 236.34707 -90.952049) (xy 236.340183 -91.029944)
			(xy 236.326492 -91.106934) (xy 236.306102 -91.182428) (xy 236.279171 -91.255843) (xy 236.262926 -91.29141)
			(xy 236.25869 -91.301797) (xy 236.25869 -91.324203) (xy 236.262926 -91.33459) (xy 236.279189 -91.370151)
			(xy 236.306141 -91.443561) (xy 236.326539 -91.519056) (xy 236.340228 -91.59605) (xy 236.347102 -91.673949)
			(xy 236.347508 -91.71305) (xy 236.347508 -91.713304) (xy 236.346999 -91.755493) (xy 236.338989 -91.839492)
			(xy 236.323068 -91.922356) (xy 236.311694 -91.962986) (xy 236.307884 -91.97594) (xy 236.31398 -92.001594)
			(xy 236.381798 -92.075762) (xy 236.387896 -92.081893) (xy 236.403155 -92.090002) (xy 236.420243 -92.092572)
			(xy 236.428788 -92.091256) (xy 236.429042 -92.091256) (xy 236.471596 -92.083394) (xy 236.557729 -92.074993)
			(xy 236.601 -92.074492) (xy 236.658404 -92.07627) (xy 236.658658 -92.07627) (xy 236.670759 -92.076324)
			(xy 236.692903 -92.066651) (xy 236.701076 -92.057728) (xy 236.761274 -91.983814) (xy 236.766354 -91.959938)
			(xy 236.763052 -91.948) (xy 236.753041 -91.90978) (xy 236.73904 -91.832018) (xy 236.732003 -91.753318)
			(xy 236.731556 -91.713812) (xy 236.731556 -91.71305) (xy 236.73206 -91.670702) (xy 236.740111 -91.586388)
			(xy 236.75614 -91.503222) (xy 236.780001 -91.421955) (xy 236.81148 -91.343325) (xy 236.850291 -91.268044)
			(xy 236.896081 -91.196792) (xy 236.948437 -91.130216) (xy 237.006885 -91.068918) (xy 237.070895 -91.013453)
			(xy 237.139887 -90.964324) (xy 237.213237 -90.921975) (xy 237.29028 -90.886791) (xy 237.370319 -90.859089)
			(xy 237.452628 -90.839121) (xy 237.536463 -90.827068) (xy 237.621064 -90.823038) (xy 237.705665 -90.827068)
			(xy 237.7895 -90.839121) (xy 237.871809 -90.859089) (xy 237.951848 -90.886791) (xy 238.028891 -90.921975)
			(xy 238.102241 -90.964324) (xy 238.171233 -91.013453) (xy 238.235243 -91.068918) (xy 238.293691 -91.130216)
			(xy 238.346047 -91.196792) (xy 238.391837 -91.268044) (xy 238.430648 -91.343325) (xy 238.462127 -91.421955)
			(xy 238.485988 -91.503222) (xy 238.502017 -91.586388) (xy 238.510068 -91.670702) (xy 238.510572 -91.71305)
			(xy 238.510572 -91.714066) (xy 238.510011 -91.758047) (xy 238.501279 -91.845576) (xy 238.483954 -91.931816)
			(xy 238.458207 -92.015927) (xy 238.441738 -92.056712) (xy 238.43817 -92.066604) (xy 238.438506 -92.087609)
			(xy 238.44721 -92.106728) (xy 238.454692 -92.114116) (xy 238.525812 -92.178378) (xy 238.534 -92.185051)
			(xy 238.55403 -92.191684) (xy 238.575035 -92.189696) (xy 238.584486 -92.184982) (xy 238.624023 -92.163841)
			(xy 238.70651 -92.128698) (xy 238.792112 -92.102024) (xy 238.879962 -92.08409) (xy 238.969169 -92.075077)
			(xy 239.014 -92.074492) (xy 239.060396 -92.075077) (xy 239.152686 -92.08471) (xy 239.243471 -92.103903)
			(xy 239.331764 -92.132447) (xy 239.374426 -92.150692) (xy 239.384368 -92.154498) (xy 239.405632 -92.154498)
			(xy 239.415574 -92.150692) (xy 239.458239 -92.132454) (xy 239.546532 -92.103916) (xy 239.637316 -92.08472)
			(xy 239.729604 -92.075075) (xy 239.776 -92.074492) (xy 239.819785 -92.075002) (xy 239.906933 -92.083579)
			(xy 239.992817 -92.100681) (xy 240.076603 -92.126142) (xy 240.157482 -92.159714) (xy 240.234669 -92.201073)
			(xy 240.307417 -92.249819) (xy 240.375021 -92.305479) (xy 240.436828 -92.367514) (xy 240.492238 -92.435324)
			(xy 240.516918 -92.471494) (xy 240.52403 -92.481908) (xy 240.546382 -92.4941) (xy 240.656618 -92.4941)
			(xy 240.67897 -92.481908) (xy 240.686082 -92.471494) (xy 240.710762 -92.435324) (xy 240.76618 -92.367522)
			(xy 240.827991 -92.305492) (xy 240.895597 -92.249835) (xy 240.968345 -92.20109) (xy 241.04553 -92.159728)
			(xy 241.126406 -92.12615) (xy 241.210189 -92.10068) (xy 241.296069 -92.083566) (xy 241.383215 -92.074972)
			(xy 241.427 -92.074492) (xy 241.473396 -92.075077) (xy 241.565686 -92.08471) (xy 241.656471 -92.103903)
			(xy 241.744764 -92.132447) (xy 241.787426 -92.150692) (xy 241.797368 -92.154498) (xy 241.818632 -92.154498)
			(xy 241.828574 -92.150692) (xy 241.871179 -92.132477) (xy 241.959348 -92.103965) (xy 242.050002 -92.084769)
			(xy 242.14216 -92.075098) (xy 242.188492 -92.074492) (xy 242.189 -92.074492) (xy 242.231348 -92.074996)
			(xy 242.315662 -92.083047) (xy 242.398828 -92.099076) (xy 242.480095 -92.122937) (xy 242.558725 -92.154416)
			(xy 242.634006 -92.193227) (xy 242.705258 -92.239017) (xy 242.771834 -92.291373) (xy 242.833132 -92.349821)
			(xy 242.888597 -92.413831) (xy 242.937726 -92.482823) (xy 242.980075 -92.556173) (xy 243.015259 -92.633216)
			(xy 243.042961 -92.713255) (xy 243.062929 -92.795564) (xy 243.074982 -92.879399) (xy 243.079013 -92.964)
			(xy 243.074982 -93.048601) (xy 243.062929 -93.132436) (xy 243.042961 -93.214745) (xy 243.015259 -93.294784)
			(xy 242.980075 -93.371827) (xy 242.937726 -93.445177) (xy 242.888597 -93.514169) (xy 242.833132 -93.578179)
			(xy 242.771834 -93.636627) (xy 242.705258 -93.688983) (xy 242.634006 -93.734773) (xy 242.558725 -93.773584)
			(xy 242.480095 -93.805063) (xy 242.398828 -93.828924) (xy 242.315662 -93.844953) (xy 242.231348 -93.853004)
			(xy 242.189 -93.853508) (xy 242.188492 -93.853508) (xy 242.14216 -93.8529) (xy 242.05 -93.84324)
			(xy 241.959344 -93.824048) (xy 241.871177 -93.79553) (xy 241.828574 -93.777308) (xy 241.818632 -93.773502)
			(xy 241.797368 -93.773502) (xy 241.787426 -93.777308) (xy 241.744761 -93.795546) (xy 241.656468 -93.824084)
			(xy 241.565684 -93.84328) (xy 241.473396 -93.852925) (xy 241.427 -93.853508) (xy 241.383215 -93.852998)
			(xy 241.296067 -93.844421) (xy 241.210183 -93.827319) (xy 241.126397 -93.801858) (xy 241.045518 -93.768286)
			(xy 240.968331 -93.726927) (xy 240.895583 -93.678181) (xy 240.827979 -93.622521) (xy 240.766172 -93.560486)
			(xy 240.710762 -93.492676) (xy 240.686082 -93.456506) (xy 240.67897 -93.446092) (xy 240.656618 -93.4339)
			(xy 240.546382 -93.4339) (xy 240.52403 -93.446092) (xy 240.516918 -93.456506) (xy 240.492238 -93.492676)
			(xy 240.43682 -93.560478) (xy 240.375009 -93.622508) (xy 240.307403 -93.678165) (xy 240.234655 -93.72691)
			(xy 240.15747 -93.768272) (xy 240.076594 -93.80185) (xy 239.992811 -93.82732) (xy 239.906931 -93.844434)
			(xy 239.819785 -93.853028) (xy 239.776 -93.853508) (xy 239.729604 -93.852923) (xy 239.637314 -93.84329)
			(xy 239.546529 -93.824097) (xy 239.458236 -93.795553) (xy 239.415574 -93.777308) (xy 239.405632 -93.773502)
			(xy 239.384368 -93.773502) (xy 239.374426 -93.777308) (xy 239.331761 -93.795546) (xy 239.243468 -93.824084)
			(xy 239.152684 -93.84328) (xy 239.060396 -93.852925) (xy 239.014 -93.853508) (xy 238.970215 -93.852998)
			(xy 238.883067 -93.844421) (xy 238.797183 -93.827319) (xy 238.713397 -93.801858) (xy 238.632518 -93.768286)
			(xy 238.555331 -93.726927) (xy 238.482583 -93.678181) (xy 238.414979 -93.622521) (xy 238.353172 -93.560486)
			(xy 238.297762 -93.492676) (xy 238.273082 -93.456506) (xy 238.26597 -93.446092) (xy 238.243618 -93.4339)
			(xy 238.133382 -93.4339) (xy 238.11103 -93.446092) (xy 238.103918 -93.456506) (xy 238.079238 -93.492676)
			(xy 238.02382 -93.560478) (xy 237.962009 -93.622508) (xy 237.894403 -93.678165) (xy 237.821655 -93.72691)
			(xy 237.74447 -93.768272) (xy 237.663594 -93.80185) (xy 237.579811 -93.82732) (xy 237.493931 -93.844434)
			(xy 237.406785 -93.853028) (xy 237.363 -93.853508) (xy 237.316604 -93.852923) (xy 237.224314 -93.84329)
			(xy 237.133529 -93.824097) (xy 237.045236 -93.795553) (xy 237.002574 -93.777308) (xy 236.992632 -93.773502)
			(xy 236.971368 -93.773502) (xy 236.961426 -93.777308) (xy 236.918761 -93.795546) (xy 236.830468 -93.824084)
			(xy 236.739684 -93.84328) (xy 236.647396 -93.852925) (xy 236.601 -93.853508) (xy 236.557215 -93.852998)
			(xy 236.470067 -93.844421) (xy 236.384183 -93.827319) (xy 236.300397 -93.801858) (xy 236.219518 -93.768286)
			(xy 236.142331 -93.726927) (xy 236.069583 -93.678181) (xy 236.001979 -93.622521) (xy 235.940172 -93.560486)
			(xy 235.884762 -93.492676) (xy 235.860082 -93.456506) (xy 235.85297 -93.446092) (xy 235.830618 -93.4339)
			(xy 235.720382 -93.4339) (xy 235.69803 -93.446092) (xy 235.690918 -93.456506) (xy 235.666238 -93.492676)
			(xy 235.61082 -93.560478) (xy 235.549009 -93.622508) (xy 235.481403 -93.678165) (xy 235.408655 -93.72691)
			(xy 235.33147 -93.768272) (xy 235.250594 -93.80185) (xy 235.166811 -93.82732) (xy 235.080931 -93.844434)
			(xy 234.993785 -93.853028) (xy 234.95 -93.853508) (xy 234.903604 -93.852923) (xy 234.811314 -93.84329)
			(xy 234.720529 -93.824097) (xy 234.632236 -93.795553) (xy 234.589574 -93.777308) (xy 234.579632 -93.773502)
			(xy 234.558368 -93.773502) (xy 234.548426 -93.777308) (xy 234.505761 -93.795546) (xy 234.417468 -93.824084)
			(xy 234.326684 -93.84328) (xy 234.234396 -93.852925) (xy 234.188 -93.853508) (xy 234.144215 -93.852998)
			(xy 234.057067 -93.844421) (xy 233.971183 -93.827319) (xy 233.887397 -93.801858) (xy 233.806518 -93.768286)
			(xy 233.729331 -93.726927) (xy 233.656583 -93.678181) (xy 233.588979 -93.622521) (xy 233.527172 -93.560486)
			(xy 233.471762 -93.492676) (xy 233.447082 -93.456506) (xy 233.43997 -93.446092) (xy 233.417618 -93.4339)
			(xy 233.307382 -93.4339) (xy 233.28503 -93.446092) (xy 233.277918 -93.456506) (xy 233.253238 -93.492676)
			(xy 233.19782 -93.560478) (xy 233.136009 -93.622508) (xy 233.068403 -93.678165) (xy 232.995655 -93.72691)
			(xy 232.91847 -93.768272) (xy 232.837594 -93.80185) (xy 232.753811 -93.82732) (xy 232.667931 -93.844434)
			(xy 232.580785 -93.853028) (xy 232.537 -93.853508) (xy 232.490604 -93.852923) (xy 232.398314 -93.84329)
			(xy 232.307529 -93.824097) (xy 232.219236 -93.795553) (xy 232.176574 -93.777308) (xy 232.166632 -93.773502)
			(xy 232.145368 -93.773502) (xy 232.135426 -93.777308) (xy 232.092761 -93.795546) (xy 232.004468 -93.824084)
			(xy 231.913684 -93.84328) (xy 231.821396 -93.852925) (xy 231.775 -93.853508) (xy 231.731215 -93.852998)
			(xy 231.644067 -93.844421) (xy 231.558183 -93.827319) (xy 231.474397 -93.801858) (xy 231.393518 -93.768286)
			(xy 231.316331 -93.726927) (xy 231.243583 -93.678181) (xy 231.175979 -93.622521) (xy 231.114172 -93.560486)
			(xy 231.058762 -93.492676) (xy 231.034082 -93.456506) (xy 231.02697 -93.446092) (xy 231.004618 -93.4339)
			(xy 230.894382 -93.4339) (xy 230.87203 -93.446092) (xy 230.864918 -93.456506) (xy 230.840238 -93.492676)
			(xy 230.78482 -93.560478) (xy 230.723009 -93.622508) (xy 230.655403 -93.678165) (xy 230.582655 -93.72691)
			(xy 230.50547 -93.768272) (xy 230.424594 -93.80185) (xy 230.340811 -93.82732) (xy 230.254931 -93.844434)
			(xy 230.167785 -93.853028) (xy 230.124 -93.853508) (xy 230.077604 -93.852923) (xy 229.985314 -93.84329)
			(xy 229.894529 -93.824097) (xy 229.806236 -93.795553) (xy 229.763574 -93.777308) (xy 229.753632 -93.773502)
			(xy 229.732368 -93.773502) (xy 229.722426 -93.777308) (xy 229.679761 -93.795546) (xy 229.591468 -93.824084)
			(xy 229.500684 -93.84328) (xy 229.408396 -93.852925) (xy 229.362 -93.853508) (xy 229.318215 -93.852998)
			(xy 229.231067 -93.844421) (xy 229.145183 -93.827319) (xy 229.061397 -93.801858) (xy 228.980518 -93.768286)
			(xy 228.903331 -93.726927) (xy 228.830583 -93.678181) (xy 228.762979 -93.622521) (xy 228.701172 -93.560486)
			(xy 228.645762 -93.492676) (xy 228.621082 -93.456506) (xy 228.61397 -93.446092) (xy 228.591618 -93.4339)
			(xy 228.481382 -93.4339) (xy 228.45903 -93.446092) (xy 228.451918 -93.456506) (xy 228.427238 -93.492676)
			(xy 228.37182 -93.560478) (xy 228.310009 -93.622508) (xy 228.242403 -93.678165) (xy 228.169655 -93.72691)
			(xy 228.09247 -93.768272) (xy 228.011594 -93.80185) (xy 227.927811 -93.82732) (xy 227.841931 -93.844434)
			(xy 227.754785 -93.853028) (xy 227.711 -93.853508) (xy 227.664604 -93.852923) (xy 227.572314 -93.84329)
			(xy 227.481529 -93.824097) (xy 227.393236 -93.795553) (xy 227.350574 -93.777308) (xy 227.340632 -93.773502)
			(xy 227.319368 -93.773502) (xy 227.309426 -93.777308) (xy 227.266761 -93.795546) (xy 227.178468 -93.824084)
			(xy 227.087684 -93.84328) (xy 226.995396 -93.852925) (xy 226.949 -93.853508) (xy 226.905215 -93.852998)
			(xy 226.818067 -93.844421) (xy 226.732183 -93.827319) (xy 226.648397 -93.801858) (xy 226.567518 -93.768286)
			(xy 226.490331 -93.726927) (xy 226.417583 -93.678181) (xy 226.349979 -93.622521) (xy 226.288172 -93.560486)
			(xy 226.232762 -93.492676) (xy 226.208082 -93.456506) (xy 226.20097 -93.446092) (xy 226.178618 -93.4339)
			(xy 226.068382 -93.4339) (xy 226.04603 -93.446092) (xy 226.038918 -93.456506) (xy 226.014238 -93.492676)
			(xy 225.95882 -93.560478) (xy 225.897009 -93.622508) (xy 225.829403 -93.678165) (xy 225.756655 -93.72691)
			(xy 225.67947 -93.768272) (xy 225.598594 -93.80185) (xy 225.514811 -93.82732) (xy 225.428931 -93.844434)
			(xy 225.341785 -93.853028) (xy 225.298 -93.853508) (xy 225.251604 -93.852923) (xy 225.159314 -93.84329)
			(xy 225.068529 -93.824097) (xy 224.980236 -93.795553) (xy 224.937574 -93.777308) (xy 224.927632 -93.773502)
			(xy 224.906368 -93.773502) (xy 224.896426 -93.777308) (xy 224.853761 -93.795546) (xy 224.765468 -93.824084)
			(xy 224.674684 -93.84328) (xy 224.582396 -93.852925) (xy 224.536 -93.853508) (xy 224.492215 -93.852998)
			(xy 224.405067 -93.844421) (xy 224.319183 -93.827319) (xy 224.235397 -93.801858) (xy 224.154518 -93.768286)
			(xy 224.077331 -93.726927) (xy 224.004583 -93.678181) (xy 223.936979 -93.622521) (xy 223.875172 -93.560486)
			(xy 223.819762 -93.492676) (xy 223.795082 -93.456506) (xy 223.78797 -93.446092) (xy 223.765618 -93.4339)
			(xy 223.655382 -93.4339) (xy 223.63303 -93.446092) (xy 223.625918 -93.456506) (xy 223.601238 -93.492676)
			(xy 223.54582 -93.560478) (xy 223.484009 -93.622508) (xy 223.416403 -93.678165) (xy 223.343655 -93.72691)
			(xy 223.26647 -93.768272) (xy 223.185594 -93.80185) (xy 223.101811 -93.82732) (xy 223.015931 -93.844434)
			(xy 222.928785 -93.853028) (xy 222.885 -93.853508) (xy 222.838604 -93.852923) (xy 222.746314 -93.84329)
			(xy 222.655529 -93.824097) (xy 222.567236 -93.795553) (xy 222.524574 -93.777308) (xy 222.514632 -93.773502)
			(xy 222.493368 -93.773502) (xy 222.483426 -93.777308) (xy 222.440761 -93.795546) (xy 222.352468 -93.824084)
			(xy 222.261684 -93.84328) (xy 222.169396 -93.852925) (xy 222.123 -93.853508) (xy 222.079649 -93.852998)
			(xy 221.993356 -93.844582) (xy 221.908292 -93.827812) (xy 221.825262 -93.802845) (xy 221.745055 -93.769919)
			(xy 221.668433 -93.729346) (xy 221.59612 -93.681511) (xy 221.528805 -93.626868) (xy 221.467124 -93.565936)
			(xy 221.438978 -93.53296) (xy 221.431866 -93.524324) (xy 221.411546 -93.514672) (xy 221.310454 -93.514672)
			(xy 221.290134 -93.524324) (xy 221.283022 -93.53296) (xy 221.254895 -93.565954) (xy 221.193217 -93.626893)
			(xy 221.125902 -93.681542) (xy 221.053588 -93.729381) (xy 220.976962 -93.769956) (xy 220.896752 -93.802882)
			(xy 220.813718 -93.827846) (xy 220.728649 -93.844612) (xy 220.642353 -93.85302) (xy 220.599 -93.853508)
			(xy 220.552604 -93.852923) (xy 220.460314 -93.84329) (xy 220.369529 -93.824097) (xy 220.281236 -93.795553)
			(xy 220.238574 -93.777308) (xy 220.228632 -93.773502) (xy 220.207368 -93.773502) (xy 220.197426 -93.777308)
			(xy 220.154761 -93.795546) (xy 220.066468 -93.824084) (xy 219.975684 -93.84328) (xy 219.883396 -93.852925)
			(xy 219.837 -93.853508) (xy 219.793649 -93.852998) (xy 219.707356 -93.844582) (xy 219.622292 -93.827812)
			(xy 219.539262 -93.802845) (xy 219.459055 -93.769919) (xy 219.382433 -93.729346) (xy 219.31012 -93.681511)
			(xy 219.242805 -93.626868) (xy 219.181124 -93.565936) (xy 219.152978 -93.53296) (xy 219.145866 -93.524324)
			(xy 219.125546 -93.514672) (xy 219.024454 -93.514672) (xy 219.004134 -93.524324) (xy 218.997022 -93.53296)
			(xy 218.968895 -93.565954) (xy 218.907217 -93.626893) (xy 218.839902 -93.681542) (xy 218.767588 -93.729381)
			(xy 218.690962 -93.769956) (xy 218.610752 -93.802882) (xy 218.527718 -93.827846) (xy 218.442649 -93.844612)
			(xy 218.356353 -93.85302) (xy 218.313 -93.853508) (xy 218.266604 -93.852923) (xy 218.174314 -93.84329)
			(xy 218.083529 -93.824097) (xy 217.995236 -93.795553) (xy 217.952574 -93.777308) (xy 217.942632 -93.773502)
			(xy 217.921368 -93.773502) (xy 217.911426 -93.777308) (xy 217.868761 -93.795546) (xy 217.780468 -93.824084)
			(xy 217.689684 -93.84328) (xy 217.597396 -93.852925) (xy 217.551 -93.853508) (xy 217.507649 -93.852998)
			(xy 217.421356 -93.844582) (xy 217.336292 -93.827812) (xy 217.253262 -93.802845) (xy 217.173055 -93.769919)
			(xy 217.096433 -93.729346) (xy 217.02412 -93.681511) (xy 216.956805 -93.626868) (xy 216.895124 -93.565936)
			(xy 216.866978 -93.53296) (xy 216.859866 -93.524324) (xy 216.839546 -93.514672) (xy 216.738454 -93.514672)
			(xy 216.718134 -93.524324) (xy 216.711022 -93.53296) (xy 216.682895 -93.565954) (xy 216.621217 -93.626893)
			(xy 216.553902 -93.681542) (xy 216.481588 -93.729381) (xy 216.404962 -93.769956) (xy 216.324752 -93.802882)
			(xy 216.241718 -93.827846) (xy 216.156649 -93.844612) (xy 216.070353 -93.85302) (xy 216.027 -93.853508)
			(xy 215.980604 -93.852923) (xy 215.888314 -93.84329) (xy 215.797529 -93.824097) (xy 215.709236 -93.795553)
			(xy 215.666574 -93.777308) (xy 215.656632 -93.773502) (xy 215.635368 -93.773502) (xy 215.625426 -93.777308)
			(xy 215.582821 -93.795523) (xy 215.494652 -93.824035) (xy 215.403998 -93.843231) (xy 215.31184 -93.852902)
			(xy 215.265508 -93.853508) (xy 215.265 -93.853508) (xy 215.223898 -93.853033) (xy 215.142043 -93.845448)
			(xy 215.061238 -93.830343) (xy 214.982171 -93.807847) (xy 214.905517 -93.778151) (xy 214.83193 -93.741509)
			(xy 214.762038 -93.698234) (xy 214.696437 -93.648694) (xy 214.635687 -93.593313) (xy 214.580306 -93.532563)
			(xy 214.530766 -93.466962) (xy 214.487491 -93.39707) (xy 214.450849 -93.323483) (xy 214.421153 -93.246829)
			(xy 214.398657 -93.167762) (xy 214.383552 -93.086957) (xy 214.375967 -93.005102) (xy 214.375492 -92.964)
			(xy 214.375967 -92.922672) (xy 214.383643 -92.840374) (xy 214.398918 -92.759143) (xy 214.421662 -92.679678)
			(xy 214.451679 -92.602666) (xy 214.488709 -92.528769) (xy 214.532433 -92.458626) (xy 214.582474 -92.39284)
			(xy 214.638402 -92.33198) (xy 214.699733 -92.276569) (xy 214.76594 -92.227085) (xy 214.83645 -92.183956)
			(xy 214.910657 -92.147552) (xy 214.98792 -92.118188) (xy 215.067574 -92.096116) (xy 215.148932 -92.081528)
			(xy 215.19007 -92.07754) (xy 215.203278 -92.076524) (xy 215.225122 -92.061792) (xy 215.276176 -91.960954)
			(xy 215.27516 -91.934792) (xy 215.268302 -91.923362) (xy 215.257377 -91.905314) (xy 215.237049 -91.868341)
			(xy 215.227662 -91.849448) (xy 215.223171 -91.841117) (xy 215.209268 -91.828297) (xy 215.191652 -91.821415)
			(xy 215.182196 -91.821) (xy 210.945476 -91.821) (xy 210.934977 -91.821519) (xy 210.915729 -91.829915)
			(xy 210.901438 -91.845301) (xy 210.89747 -91.855036) (xy 210.883032 -91.894706) (xy 210.847671 -91.97137)
			(xy 210.805206 -92.044338) (xy 210.756018 -92.112955) (xy 210.700551 -92.176603) (xy 210.639303 -92.23471)
			(xy 210.572825 -92.286753) (xy 210.501716 -92.332263) (xy 210.426615 -92.370831) (xy 210.348197 -92.40211)
			(xy 210.267169 -92.425819) (xy 210.184259 -92.441745) (xy 210.100213 -92.449744) (xy 210.015787 -92.449744)
			(xy 209.931741 -92.441745) (xy 209.848831 -92.425819) (xy 209.767803 -92.40211) (xy 209.689385 -92.370831)
			(xy 209.614284 -92.332263) (xy 209.543175 -92.286753) (xy 209.476697 -92.23471) (xy 209.415449 -92.176603)
			(xy 209.359982 -92.112955) (xy 209.310794 -92.044338) (xy 209.268329 -91.97137) (xy 209.232968 -91.894706)
			(xy 209.21853 -91.855036) (xy 209.214587 -91.84528) (xy 209.200303 -91.82986) (xy 209.181034 -91.821461)
			(xy 209.170524 -91.821) (xy 207.740504 -91.821) (xy 207.730344 -91.82144) (xy 207.711602 -91.829288)
			(xy 207.704182 -91.83624) (xy 207.646016 -91.89593) (xy 207.63865 -91.914726) (xy 207.638904 -91.92514)
			(xy 207.639412 -91.947746) (xy 207.639412 -91.948254) (xy 207.638896 -91.990607) (xy 207.630822 -92.074927)
			(xy 207.61477 -92.158098) (xy 207.590887 -92.239367) (xy 207.559388 -92.317998) (xy 207.520559 -92.39328)
			(xy 207.47475 -92.464531) (xy 207.422378 -92.531105) (xy 207.363915 -92.592401) (xy 207.299892 -92.647863)
			(xy 207.230887 -92.69699) (xy 207.157525 -92.739336) (xy 207.080471 -92.774518) (xy 207.000423 -92.802218)
			(xy 206.918104 -92.822184) (xy 206.83426 -92.834237) (xy 206.74965 -92.838267) (xy 206.66504 -92.834237)
			(xy 206.581196 -92.822184) (xy 206.498877 -92.802218) (xy 206.418829 -92.774518) (xy 206.341775 -92.739336)
			(xy 206.268413 -92.69699) (xy 206.199408 -92.647863) (xy 206.135385 -92.592401) (xy 206.076922 -92.531105)
			(xy 206.02455 -92.464531) (xy 205.978741 -92.39328) (xy 205.939912 -92.317998) (xy 205.908413 -92.239367)
			(xy 205.88453 -92.158098) (xy 205.868478 -92.074927) (xy 205.860404 -91.990607) (xy 205.859888 -91.948254)
			(xy 205.859888 -91.947746) (xy 205.860396 -91.925394) (xy 205.860396 -91.924886) (xy 205.86065 -91.914726)
			(xy 205.853284 -91.89593) (xy 205.795118 -91.83624) (xy 205.787695 -91.829286) (xy 205.768958 -91.821416)
			(xy 205.758796 -91.821) (xy 204.946504 -91.821) (xy 204.936344 -91.82144) (xy 204.917602 -91.829288)
			(xy 204.910182 -91.83624) (xy 204.852016 -91.89593) (xy 204.84465 -91.914726) (xy 204.844904 -91.92514)
			(xy 204.845412 -91.947746) (xy 204.845412 -91.948254) (xy 204.844896 -91.990607) (xy 204.836822 -92.074927)
			(xy 204.82077 -92.158098) (xy 204.796887 -92.239367) (xy 204.765388 -92.317998) (xy 204.726559 -92.39328)
			(xy 204.68075 -92.464531) (xy 204.628378 -92.531105) (xy 204.569915 -92.592401) (xy 204.505892 -92.647863)
			(xy 204.436887 -92.69699) (xy 204.363525 -92.739336) (xy 204.286471 -92.774518) (xy 204.206423 -92.802218)
			(xy 204.124104 -92.822184) (xy 204.04026 -92.834237) (xy 203.95565 -92.838267) (xy 203.87104 -92.834237)
			(xy 203.787196 -92.822184) (xy 203.704877 -92.802218) (xy 203.624829 -92.774518) (xy 203.547775 -92.739336)
			(xy 203.474413 -92.69699) (xy 203.405408 -92.647863) (xy 203.341385 -92.592401) (xy 203.282922 -92.531105)
			(xy 203.23055 -92.464531) (xy 203.184741 -92.39328) (xy 203.145912 -92.317998) (xy 203.114413 -92.239367)
			(xy 203.09053 -92.158098) (xy 203.074478 -92.074927) (xy 203.066404 -91.990607) (xy 203.065888 -91.948254)
			(xy 203.065888 -91.947746) (xy 203.066396 -91.925394) (xy 203.066396 -91.924886) (xy 203.06665 -91.914726)
			(xy 203.059284 -91.89593) (xy 203.001118 -91.83624) (xy 202.993695 -91.829286) (xy 202.974958 -91.821416)
			(xy 202.964796 -91.821) (xy 201.197972 -91.821) (xy 201.196448 -91.821) (xy 201.168 -91.821508) (xy 201.139552 -91.821)
			(xy 199.471026 -91.821) (xy 199.459701 -91.821614) (xy 199.439267 -91.831384) (xy 199.431656 -91.839796)
			(xy 199.381872 -91.901264) (xy 199.375307 -91.910416) (xy 199.370043 -91.932288) (xy 199.371712 -91.943428)
			(xy 199.380481 -91.988254) (xy 199.389899 -92.079112) (xy 199.390508 -92.124784) (xy 199.390508 -92.1258)
			(xy 199.390004 -92.168148) (xy 199.381953 -92.252462) (xy 199.365924 -92.335628) (xy 199.342063 -92.416895)
			(xy 199.310584 -92.495525) (xy 199.271773 -92.570806) (xy 199.225983 -92.642058) (xy 199.173627 -92.708634)
			(xy 199.115179 -92.769932) (xy 199.051169 -92.825397) (xy 198.982177 -92.874526) (xy 198.908827 -92.916875)
			(xy 198.831784 -92.952059) (xy 198.751745 -92.979761) (xy 198.669436 -92.999729) (xy 198.585601 -93.011782)
			(xy 198.501 -93.015813) (xy 198.416399 -93.011782) (xy 198.332564 -92.999729) (xy 198.250255 -92.979761)
			(xy 198.170216 -92.952059) (xy 198.093173 -92.916875) (xy 198.019823 -92.874526) (xy 197.950831 -92.825397)
			(xy 197.886821 -92.769932) (xy 197.828373 -92.708634) (xy 197.776017 -92.642058) (xy 197.730227 -92.570806)
			(xy 197.691416 -92.495525) (xy 197.659937 -92.416895) (xy 197.636076 -92.335628) (xy 197.620047 -92.252462)
			(xy 197.611996 -92.168148) (xy 197.611492 -92.1258) (xy 197.611492 -92.124784) (xy 197.612102 -92.079112)
			(xy 197.621523 -91.988255) (xy 197.630288 -91.943428) (xy 197.632022 -91.932286) (xy 197.626746 -91.910394)
			(xy 197.620128 -91.901264) (xy 197.570344 -91.839796) (xy 197.562722 -91.831409) (xy 197.542289 -91.821674)
			(xy 197.530974 -91.821) (xy 189.534038 -91.821) (xy 189.524402 -91.821422) (xy 189.506487 -91.828529)
			(xy 189.49244 -91.841724) (xy 189.484227 -91.859159) (xy 189.483238 -91.868752) (xy 189.483238 -91.869006)
			(xy 189.480468 -91.91109) (xy 189.467964 -91.994502) (xy 189.447621 -92.076356) (xy 189.419621 -92.155917)
			(xy 189.384215 -92.232471) (xy 189.341723 -92.305329) (xy 189.292524 -92.373838) (xy 189.237061 -92.437382)
			(xy 189.175833 -92.49539) (xy 189.109388 -92.547343) (xy 189.038324 -92.592772) (xy 188.963279 -92.631271)
			(xy 188.884927 -92.662494) (xy 188.80397 -92.686159) (xy 188.721138 -92.702055) (xy 188.637172 -92.710039)
			(xy 188.552828 -92.710039) (xy 188.468862 -92.702055) (xy 188.38603 -92.686159) (xy 188.305073 -92.662494)
			(xy 188.226721 -92.631271) (xy 188.151676 -92.592772) (xy 188.080612 -92.547343) (xy 188.014167 -92.49539)
			(xy 187.952939 -92.437382) (xy 187.897476 -92.373838) (xy 187.848277 -92.305329) (xy 187.805785 -92.232471)
			(xy 187.770379 -92.155917) (xy 187.742379 -92.076356) (xy 187.722036 -91.994502) (xy 187.709532 -91.91109)
			(xy 187.706762 -91.869006) (xy 187.706762 -91.868752) (xy 187.705783 -91.859144) (xy 187.697616 -91.841659)
			(xy 187.683561 -91.828434) (xy 187.665612 -91.821346) (xy 187.655962 -91.821) (xy 180.336444 -91.821)
			(xy 180.328166 -91.821326) (xy 180.31249 -91.826651) (xy 180.30571 -91.831414) (xy 180.272589 -91.855937)
			(xy 180.202585 -91.899434) (xy 180.128856 -91.936266) (xy 180.052034 -91.966116) (xy 179.97278 -91.988729)
			(xy 179.891773 -92.003909) (xy 179.809709 -92.011528) (xy 179.7685 -92.012008) (xy 179.722676 -92.011452)
			(xy 179.631512 -92.002053) (xy 179.541799 -91.983324) (xy 179.45449 -91.955463) (xy 179.37051 -91.918767)
			(xy 179.33035 -91.896692) (xy 179.319566 -91.891372) (xy 179.295577 -91.890293) (xy 179.284376 -91.89466)
			(xy 179.241058 -91.913595) (xy 179.151287 -91.943249) (xy 179.058877 -91.963214) (xy 178.964871 -91.973263)
			(xy 178.9176 -91.973908) (xy 178.87473 -91.973413) (xy 178.789386 -91.965193) (xy 178.70523 -91.948791)
			(xy 178.623045 -91.924359) (xy 178.543596 -91.892126) (xy 178.46762 -91.852389) (xy 178.431444 -91.829382)
			(xy 178.425171 -91.82555) (xy 178.411104 -91.821302) (xy 178.403758 -91.821) (xy 157.099 -91.821)
			(xy 157.06574 -91.820479) (xy 156.99979 -91.811791) (xy 156.935539 -91.794566) (xy 156.874088 -91.769097)
			(xy 156.816489 -91.735821) (xy 156.763729 -91.695308) (xy 156.739844 -91.672156) (xy 148.902674 -83.834986)
			(xy 148.895278 -83.828134) (xy 148.876679 -83.820396) (xy 148.866606 -83.82) (xy 37.213794 -83.82)
			(xy 37.203724 -83.820424) (xy 37.185121 -83.82814) (xy 37.177726 -83.834986) (xy 36.034726 -84.977986)
			(xy 36.02789 -84.985388) (xy 36.020183 -85.003986) (xy 36.01974 -85.014054) (xy 36.01974 -86.542569)
			(xy 43.120052 -86.542569) (xy 43.120052 -86.457847) (xy 43.128105 -86.37351) (xy 43.144139 -86.29032)
			(xy 43.168007 -86.20903) (xy 43.199495 -86.130378) (xy 43.238317 -86.055075) (xy 43.28412 -85.983803)
			(xy 43.336491 -85.917207) (xy 43.394956 -85.855892) (xy 43.458984 -85.800411) (xy 43.527996 -85.751268)
			(xy 43.601366 -85.708908) (xy 43.678431 -85.673713) (xy 43.758493 -85.646004) (xy 43.840826 -85.62603)
			(xy 43.924685 -85.613973) (xy 44.00931 -85.609942) (xy 44.093935 -85.613973) (xy 44.177794 -85.62603)
			(xy 44.260127 -85.646004) (xy 44.340189 -85.673713) (xy 44.417254 -85.708908) (xy 44.490624 -85.751268)
			(xy 44.559636 -85.800411) (xy 44.623664 -85.855892) (xy 44.682129 -85.917207) (xy 44.7345 -85.983803)
			(xy 44.780303 -86.055075) (xy 44.819125 -86.130378) (xy 44.850613 -86.20903) (xy 44.874481 -86.29032)
			(xy 44.890515 -86.37351) (xy 44.898568 -86.457847) (xy 44.898929 -86.488213) (xy 72.953622 -86.488213)
			(xy 72.953622 -86.403491) (xy 72.961675 -86.319154) (xy 72.977709 -86.235964) (xy 73.001577 -86.154674)
			(xy 73.033065 -86.076022) (xy 73.071887 -86.000719) (xy 73.11769 -85.929447) (xy 73.170061 -85.862851)
			(xy 73.228526 -85.801536) (xy 73.292554 -85.746055) (xy 73.361566 -85.696912) (xy 73.434936 -85.654552)
			(xy 73.512001 -85.619357) (xy 73.592063 -85.591648) (xy 73.674396 -85.571674) (xy 73.758255 -85.559617)
			(xy 73.84288 -85.555586) (xy 73.927505 -85.559617) (xy 74.011364 -85.571674) (xy 74.093697 -85.591648)
			(xy 74.173759 -85.619357) (xy 74.250824 -85.654552) (xy 74.324194 -85.696912) (xy 74.393206 -85.746055)
			(xy 74.457234 -85.801536) (xy 74.515699 -85.862851) (xy 74.56807 -85.929447) (xy 74.613873 -86.000719)
			(xy 74.652695 -86.076022) (xy 74.684183 -86.154674) (xy 74.708051 -86.235964) (xy 74.724085 -86.319154)
			(xy 74.732138 -86.403491) (xy 74.732642 -86.445852) (xy 74.732138 -86.488213) (xy 74.726948 -86.542569)
			(xy 78.757776 -86.542569) (xy 78.757776 -86.457847) (xy 78.765829 -86.37351) (xy 78.781863 -86.29032)
			(xy 78.805731 -86.20903) (xy 78.837219 -86.130378) (xy 78.876041 -86.055075) (xy 78.921844 -85.983803)
			(xy 78.974215 -85.917207) (xy 79.03268 -85.855892) (xy 79.096708 -85.800411) (xy 79.16572 -85.751268)
			(xy 79.23909 -85.708908) (xy 79.316155 -85.673713) (xy 79.396217 -85.646004) (xy 79.47855 -85.62603)
			(xy 79.562409 -85.613973) (xy 79.647034 -85.609942) (xy 79.731659 -85.613973) (xy 79.815518 -85.62603)
			(xy 79.897851 -85.646004) (xy 79.977913 -85.673713) (xy 80.054978 -85.708908) (xy 80.128348 -85.751268)
			(xy 80.19736 -85.800411) (xy 80.261388 -85.855892) (xy 80.319853 -85.917207) (xy 80.372224 -85.983803)
			(xy 80.418027 -86.055075) (xy 80.456849 -86.130378) (xy 80.488337 -86.20903) (xy 80.512205 -86.29032)
			(xy 80.528239 -86.37351) (xy 80.536292 -86.457847) (xy 80.536656 -86.488467) (xy 112.713512 -86.488467)
			(xy 112.713512 -86.403745) (xy 112.721565 -86.319408) (xy 112.737599 -86.236218) (xy 112.761467 -86.154928)
			(xy 112.792955 -86.076276) (xy 112.831777 -86.000973) (xy 112.87758 -85.929701) (xy 112.929951 -85.863105)
			(xy 112.988416 -85.80179) (xy 113.052444 -85.746309) (xy 113.121456 -85.697166) (xy 113.194826 -85.654806)
			(xy 113.271891 -85.619611) (xy 113.351953 -85.591902) (xy 113.434286 -85.571928) (xy 113.518145 -85.559871)
			(xy 113.60277 -85.55584) (xy 113.687395 -85.559871) (xy 113.771254 -85.571928) (xy 113.853587 -85.591902)
			(xy 113.933649 -85.619611) (xy 114.010714 -85.654806) (xy 114.084084 -85.697166) (xy 114.153096 -85.746309)
			(xy 114.217124 -85.80179) (xy 114.275589 -85.863105) (xy 114.32796 -85.929701) (xy 114.373763 -86.000973)
			(xy 114.412585 -86.076276) (xy 114.444073 -86.154928) (xy 114.467941 -86.236218) (xy 114.483975 -86.319408)
			(xy 114.492028 -86.403745) (xy 114.492532 -86.446106) (xy 114.492028 -86.488467) (xy 119.276872 -86.488467)
			(xy 119.276872 -86.403745) (xy 119.284925 -86.319408) (xy 119.300959 -86.236218) (xy 119.324827 -86.154928)
			(xy 119.356315 -86.076276) (xy 119.395137 -86.000973) (xy 119.44094 -85.929701) (xy 119.493311 -85.863105)
			(xy 119.551776 -85.80179) (xy 119.615804 -85.746309) (xy 119.684816 -85.697166) (xy 119.758186 -85.654806)
			(xy 119.835251 -85.619611) (xy 119.915313 -85.591902) (xy 119.997646 -85.571928) (xy 120.081505 -85.559871)
			(xy 120.16613 -85.55584) (xy 120.250755 -85.559871) (xy 120.334614 -85.571928) (xy 120.416947 -85.591902)
			(xy 120.497009 -85.619611) (xy 120.574074 -85.654806) (xy 120.647444 -85.697166) (xy 120.716456 -85.746309)
			(xy 120.780484 -85.80179) (xy 120.838949 -85.863105) (xy 120.89132 -85.929701) (xy 120.937123 -86.000973)
			(xy 120.975945 -86.076276) (xy 121.007433 -86.154928) (xy 121.031301 -86.236218) (xy 121.047335 -86.319408)
			(xy 121.055388 -86.403745) (xy 121.055892 -86.446106) (xy 121.055388 -86.488467) (xy 137.556744 -86.488467)
			(xy 137.556744 -86.403745) (xy 137.564797 -86.319408) (xy 137.580831 -86.236218) (xy 137.604699 -86.154928)
			(xy 137.636187 -86.076276) (xy 137.675009 -86.000973) (xy 137.720812 -85.929701) (xy 137.773183 -85.863105)
			(xy 137.831648 -85.80179) (xy 137.895676 -85.746309) (xy 137.964688 -85.697166) (xy 138.038058 -85.654806)
			(xy 138.115123 -85.619611) (xy 138.195185 -85.591902) (xy 138.277518 -85.571928) (xy 138.361377 -85.559871)
			(xy 138.446002 -85.55584) (xy 138.530627 -85.559871) (xy 138.614486 -85.571928) (xy 138.696819 -85.591902)
			(xy 138.776881 -85.619611) (xy 138.853946 -85.654806) (xy 138.927316 -85.697166) (xy 138.996328 -85.746309)
			(xy 139.060356 -85.80179) (xy 139.118821 -85.863105) (xy 139.171192 -85.929701) (xy 139.216995 -86.000973)
			(xy 139.255817 -86.076276) (xy 139.287305 -86.154928) (xy 139.311173 -86.236218) (xy 139.327207 -86.319408)
			(xy 139.33526 -86.403745) (xy 139.335764 -86.446106) (xy 139.33526 -86.488467) (xy 139.327207 -86.572804)
			(xy 139.311173 -86.655994) (xy 139.287305 -86.737284) (xy 139.255817 -86.815936) (xy 139.216995 -86.891239)
			(xy 139.171192 -86.962511) (xy 139.118821 -87.029107) (xy 139.060356 -87.090422) (xy 138.996328 -87.145903)
			(xy 138.927316 -87.195046) (xy 138.853946 -87.237406) (xy 138.776881 -87.272601) (xy 138.696819 -87.30031)
			(xy 138.614486 -87.320284) (xy 138.530627 -87.332341) (xy 138.446002 -87.336373) (xy 138.361377 -87.332341)
			(xy 138.277518 -87.320284) (xy 138.195185 -87.30031) (xy 138.115123 -87.272601) (xy 138.038058 -87.237406)
			(xy 137.964688 -87.195046) (xy 137.895676 -87.145903) (xy 137.831648 -87.090422) (xy 137.773183 -87.029107)
			(xy 137.720812 -86.962511) (xy 137.675009 -86.891239) (xy 137.636187 -86.815936) (xy 137.604699 -86.737284)
			(xy 137.580831 -86.655994) (xy 137.564797 -86.572804) (xy 137.556744 -86.488467) (xy 121.055388 -86.488467)
			(xy 121.047335 -86.572804) (xy 121.031301 -86.655994) (xy 121.007433 -86.737284) (xy 120.975945 -86.815936)
			(xy 120.937123 -86.891239) (xy 120.89132 -86.962511) (xy 120.838949 -87.029107) (xy 120.780484 -87.090422)
			(xy 120.716456 -87.145903) (xy 120.647444 -87.195046) (xy 120.574074 -87.237406) (xy 120.497009 -87.272601)
			(xy 120.416947 -87.30031) (xy 120.334614 -87.320284) (xy 120.250755 -87.332341) (xy 120.16613 -87.336373)
			(xy 120.081505 -87.332341) (xy 119.997646 -87.320284) (xy 119.915313 -87.30031) (xy 119.835251 -87.272601)
			(xy 119.758186 -87.237406) (xy 119.684816 -87.195046) (xy 119.615804 -87.145903) (xy 119.551776 -87.090422)
			(xy 119.493311 -87.029107) (xy 119.44094 -86.962511) (xy 119.395137 -86.891239) (xy 119.356315 -86.815936)
			(xy 119.324827 -86.737284) (xy 119.300959 -86.655994) (xy 119.284925 -86.572804) (xy 119.276872 -86.488467)
			(xy 114.492028 -86.488467) (xy 114.483975 -86.572804) (xy 114.467941 -86.655994) (xy 114.444073 -86.737284)
			(xy 114.412585 -86.815936) (xy 114.373763 -86.891239) (xy 114.32796 -86.962511) (xy 114.275589 -87.029107)
			(xy 114.217124 -87.090422) (xy 114.153096 -87.145903) (xy 114.084084 -87.195046) (xy 114.010714 -87.237406)
			(xy 113.933649 -87.272601) (xy 113.853587 -87.30031) (xy 113.771254 -87.320284) (xy 113.687395 -87.332341)
			(xy 113.60277 -87.336373) (xy 113.518145 -87.332341) (xy 113.434286 -87.320284) (xy 113.351953 -87.30031)
			(xy 113.271891 -87.272601) (xy 113.194826 -87.237406) (xy 113.121456 -87.195046) (xy 113.052444 -87.145903)
			(xy 112.988416 -87.090422) (xy 112.929951 -87.029107) (xy 112.87758 -86.962511) (xy 112.831777 -86.891239)
			(xy 112.792955 -86.815936) (xy 112.761467 -86.737284) (xy 112.737599 -86.655994) (xy 112.721565 -86.572804)
			(xy 112.713512 -86.488467) (xy 80.536656 -86.488467) (xy 80.536796 -86.500208) (xy 80.536292 -86.542569)
			(xy 80.528239 -86.626906) (xy 80.512205 -86.710096) (xy 80.488337 -86.791386) (xy 80.456849 -86.870038)
			(xy 80.418027 -86.945341) (xy 80.372224 -87.016613) (xy 80.319853 -87.083209) (xy 80.261388 -87.144524)
			(xy 80.19736 -87.200005) (xy 80.128348 -87.249148) (xy 80.054978 -87.291508) (xy 79.977913 -87.326703)
			(xy 79.897851 -87.354412) (xy 79.815518 -87.374386) (xy 79.731659 -87.386443) (xy 79.647034 -87.390475)
			(xy 79.562409 -87.386443) (xy 79.47855 -87.374386) (xy 79.396217 -87.354412) (xy 79.316155 -87.326703)
			(xy 79.23909 -87.291508) (xy 79.16572 -87.249148) (xy 79.096708 -87.200005) (xy 79.03268 -87.144524)
			(xy 78.974215 -87.083209) (xy 78.921844 -87.016613) (xy 78.876041 -86.945341) (xy 78.837219 -86.870038)
			(xy 78.805731 -86.791386) (xy 78.781863 -86.710096) (xy 78.765829 -86.626906) (xy 78.757776 -86.542569)
			(xy 74.726948 -86.542569) (xy 74.724085 -86.57255) (xy 74.708051 -86.65574) (xy 74.684183 -86.73703)
			(xy 74.652695 -86.815682) (xy 74.613873 -86.890985) (xy 74.56807 -86.962257) (xy 74.515699 -87.028853)
			(xy 74.457234 -87.090168) (xy 74.393206 -87.145649) (xy 74.324194 -87.194792) (xy 74.250824 -87.237152)
			(xy 74.173759 -87.272347) (xy 74.093697 -87.300056) (xy 74.011364 -87.32003) (xy 73.927505 -87.332087)
			(xy 73.84288 -87.336119) (xy 73.758255 -87.332087) (xy 73.674396 -87.32003) (xy 73.592063 -87.300056)
			(xy 73.512001 -87.272347) (xy 73.434936 -87.237152) (xy 73.361566 -87.194792) (xy 73.292554 -87.145649)
			(xy 73.228526 -87.090168) (xy 73.170061 -87.028853) (xy 73.11769 -86.962257) (xy 73.071887 -86.890985)
			(xy 73.033065 -86.815682) (xy 73.001577 -86.73703) (xy 72.977709 -86.65574) (xy 72.961675 -86.57255)
			(xy 72.953622 -86.488213) (xy 44.898929 -86.488213) (xy 44.899072 -86.500208) (xy 44.898568 -86.542569)
			(xy 44.890515 -86.626906) (xy 44.874481 -86.710096) (xy 44.850613 -86.791386) (xy 44.819125 -86.870038)
			(xy 44.780303 -86.945341) (xy 44.7345 -87.016613) (xy 44.682129 -87.083209) (xy 44.623664 -87.144524)
			(xy 44.559636 -87.200005) (xy 44.490624 -87.249148) (xy 44.417254 -87.291508) (xy 44.340189 -87.326703)
			(xy 44.260127 -87.354412) (xy 44.177794 -87.374386) (xy 44.093935 -87.386443) (xy 44.00931 -87.390475)
			(xy 43.924685 -87.386443) (xy 43.840826 -87.374386) (xy 43.758493 -87.354412) (xy 43.678431 -87.326703)
			(xy 43.601366 -87.291508) (xy 43.527996 -87.249148) (xy 43.458984 -87.200005) (xy 43.394956 -87.144524)
			(xy 43.336491 -87.083209) (xy 43.28412 -87.016613) (xy 43.238317 -86.945341) (xy 43.199495 -86.870038)
			(xy 43.168007 -86.791386) (xy 43.144139 -86.710096) (xy 43.128105 -86.626906) (xy 43.120052 -86.542569)
			(xy 36.01974 -86.542569) (xy 36.01974 -93.133361) (xy 189.121792 -93.133361) (xy 189.121792 -93.048639)
			(xy 189.129845 -92.964302) (xy 189.145879 -92.881112) (xy 189.169747 -92.799822) (xy 189.201235 -92.72117)
			(xy 189.240057 -92.645867) (xy 189.28586 -92.574595) (xy 189.338231 -92.507999) (xy 189.396696 -92.446684)
			(xy 189.460724 -92.391203) (xy 189.529736 -92.34206) (xy 189.603106 -92.2997) (xy 189.680171 -92.264505)
			(xy 189.760233 -92.236796) (xy 189.842566 -92.216822) (xy 189.926425 -92.204765) (xy 190.01105 -92.200734)
			(xy 190.095675 -92.204765) (xy 190.179534 -92.216822) (xy 190.261867 -92.236796) (xy 190.341929 -92.264505)
			(xy 190.418994 -92.2997) (xy 190.492364 -92.34206) (xy 190.561376 -92.391203) (xy 190.625404 -92.446684)
			(xy 190.683869 -92.507999) (xy 190.73624 -92.574595) (xy 190.782043 -92.645867) (xy 190.820865 -92.72117)
			(xy 190.852353 -92.799822) (xy 190.876221 -92.881112) (xy 190.892255 -92.964302) (xy 190.900308 -93.048639)
			(xy 190.900812 -93.091) (xy 190.900308 -93.133361) (xy 190.892255 -93.217698) (xy 190.876221 -93.300888)
			(xy 190.852353 -93.382178) (xy 190.820865 -93.46083) (xy 190.782043 -93.536133) (xy 190.73624 -93.607405)
			(xy 190.683869 -93.674001) (xy 190.625404 -93.735316) (xy 190.561376 -93.790797) (xy 190.492364 -93.83994)
			(xy 190.418994 -93.8823) (xy 190.341929 -93.917495) (xy 190.261867 -93.945204) (xy 190.179534 -93.965178)
			(xy 190.095675 -93.977235) (xy 190.01105 -93.981267) (xy 189.926425 -93.977235) (xy 189.842566 -93.965178)
			(xy 189.760233 -93.945204) (xy 189.680171 -93.917495) (xy 189.603106 -93.8823) (xy 189.529736 -93.83994)
			(xy 189.460724 -93.790797) (xy 189.396696 -93.735316) (xy 189.338231 -93.674001) (xy 189.28586 -93.607405)
			(xy 189.240057 -93.536133) (xy 189.201235 -93.46083) (xy 189.169747 -93.382178) (xy 189.145879 -93.300888)
			(xy 189.129845 -93.217698) (xy 189.121792 -93.133361) (xy 36.01974 -93.133361) (xy 36.01974 -113.078711)
			(xy 55.960768 -113.078711) (xy 55.960768 -112.993989) (xy 55.968821 -112.909652) (xy 55.984855 -112.826462)
			(xy 56.008723 -112.745172) (xy 56.040211 -112.66652) (xy 56.079033 -112.591217) (xy 56.124836 -112.519945)
			(xy 56.177207 -112.453349) (xy 56.235672 -112.392034) (xy 56.2997 -112.336553) (xy 56.368712 -112.28741)
			(xy 56.442082 -112.24505) (xy 56.519147 -112.209855) (xy 56.599209 -112.182146) (xy 56.681542 -112.162172)
			(xy 56.765401 -112.150115) (xy 56.850026 -112.146084) (xy 56.934651 -112.150115) (xy 57.01851 -112.162172)
			(xy 57.100843 -112.182146) (xy 57.180905 -112.209855) (xy 57.25797 -112.24505) (xy 57.33134 -112.28741)
			(xy 57.400352 -112.336553) (xy 57.46438 -112.392034) (xy 57.522845 -112.453349) (xy 57.575216 -112.519945)
			(xy 57.621019 -112.591217) (xy 57.659841 -112.66652) (xy 57.691329 -112.745172) (xy 57.715197 -112.826462)
			(xy 57.731231 -112.909652) (xy 57.739284 -112.993989) (xy 57.739788 -113.03635) (xy 57.739284 -113.078711)
			(xy 95.960688 -113.078711) (xy 95.960688 -112.993989) (xy 95.968741 -112.909652) (xy 95.984775 -112.826462)
			(xy 96.008643 -112.745172) (xy 96.040131 -112.66652) (xy 96.078953 -112.591217) (xy 96.124756 -112.519945)
			(xy 96.177127 -112.453349) (xy 96.235592 -112.392034) (xy 96.29962 -112.336553) (xy 96.368632 -112.28741)
			(xy 96.442002 -112.24505) (xy 96.519067 -112.209855) (xy 96.599129 -112.182146) (xy 96.681462 -112.162172)
			(xy 96.765321 -112.150115) (xy 96.849946 -112.146084) (xy 96.934571 -112.150115) (xy 97.01843 -112.162172)
			(xy 97.100763 -112.182146) (xy 97.180825 -112.209855) (xy 97.25789 -112.24505) (xy 97.33126 -112.28741)
			(xy 97.400272 -112.336553) (xy 97.4643 -112.392034) (xy 97.522765 -112.453349) (xy 97.575136 -112.519945)
			(xy 97.620939 -112.591217) (xy 97.659761 -112.66652) (xy 97.691249 -112.745172) (xy 97.715117 -112.826462)
			(xy 97.726284 -112.884401) (xy 108.335568 -112.884401) (xy 108.335568 -112.799679) (xy 108.343621 -112.715342)
			(xy 108.359655 -112.632152) (xy 108.383523 -112.550862) (xy 108.415011 -112.47221) (xy 108.453833 -112.396907)
			(xy 108.499636 -112.325635) (xy 108.552007 -112.259039) (xy 108.610472 -112.197724) (xy 108.6745 -112.142243)
			(xy 108.743512 -112.0931) (xy 108.816882 -112.05074) (xy 108.893947 -112.015545) (xy 108.974009 -111.987836)
			(xy 109.056342 -111.967862) (xy 109.140201 -111.955805) (xy 109.224826 -111.951774) (xy 109.309451 -111.955805)
			(xy 109.39331 -111.967862) (xy 109.475643 -111.987836) (xy 109.555705 -112.015545) (xy 109.63277 -112.05074)
			(xy 109.70614 -112.0931) (xy 109.775152 -112.142243) (xy 109.83918 -112.197724) (xy 109.897645 -112.259039)
			(xy 109.950016 -112.325635) (xy 109.995819 -112.396907) (xy 110.034641 -112.47221) (xy 110.066129 -112.550862)
			(xy 110.089997 -112.632152) (xy 110.106031 -112.715342) (xy 110.114084 -112.799679) (xy 110.114588 -112.84204)
			(xy 110.114084 -112.884401) (xy 110.106031 -112.968738) (xy 110.089997 -113.051928) (xy 110.082133 -113.078711)
			(xy 135.960862 -113.078711) (xy 135.960862 -112.993989) (xy 135.968915 -112.909652) (xy 135.984949 -112.826462)
			(xy 136.008817 -112.745172) (xy 136.040305 -112.66652) (xy 136.079127 -112.591217) (xy 136.12493 -112.519945)
			(xy 136.177301 -112.453349) (xy 136.235766 -112.392034) (xy 136.299794 -112.336553) (xy 136.368806 -112.28741)
			(xy 136.442176 -112.24505) (xy 136.519241 -112.209855) (xy 136.599303 -112.182146) (xy 136.681636 -112.162172)
			(xy 136.765495 -112.150115) (xy 136.85012 -112.146084) (xy 136.934745 -112.150115) (xy 137.018604 -112.162172)
			(xy 137.100937 -112.182146) (xy 137.180999 -112.209855) (xy 137.258064 -112.24505) (xy 137.331434 -112.28741)
			(xy 137.400446 -112.336553) (xy 137.464474 -112.392034) (xy 137.522939 -112.453349) (xy 137.57531 -112.519945)
			(xy 137.621113 -112.591217) (xy 137.659935 -112.66652) (xy 137.691423 -112.745172) (xy 137.715291 -112.826462)
			(xy 137.731325 -112.909652) (xy 137.739378 -112.993989) (xy 137.739882 -113.03635) (xy 137.739381 -113.078457)
			(xy 138.683742 -113.078457) (xy 138.683742 -112.993735) (xy 138.691795 -112.909398) (xy 138.707829 -112.826208)
			(xy 138.731697 -112.744918) (xy 138.763185 -112.666266) (xy 138.802007 -112.590963) (xy 138.84781 -112.519691)
			(xy 138.900181 -112.453095) (xy 138.958646 -112.39178) (xy 139.022674 -112.336299) (xy 139.091686 -112.287156)
			(xy 139.165056 -112.244796) (xy 139.242121 -112.209601) (xy 139.322183 -112.181892) (xy 139.404516 -112.161918)
			(xy 139.488375 -112.149861) (xy 139.573 -112.14583) (xy 139.657625 -112.149861) (xy 139.741484 -112.161918)
			(xy 139.823817 -112.181892) (xy 139.903879 -112.209601) (xy 139.980944 -112.244796) (xy 140.054314 -112.287156)
			(xy 140.123326 -112.336299) (xy 140.187354 -112.39178) (xy 140.245819 -112.453095) (xy 140.29819 -112.519691)
			(xy 140.343993 -112.590963) (xy 140.382815 -112.666266) (xy 140.414303 -112.744918) (xy 140.438171 -112.826208)
			(xy 140.441222 -112.84204) (xy 148.335492 -112.84204) (xy 148.33599 -112.800937) (xy 148.343572 -112.719083)
			(xy 148.358674 -112.638277) (xy 148.381167 -112.559209) (xy 148.41086 -112.482554) (xy 148.4475 -112.408966)
			(xy 148.490773 -112.339073) (xy 148.540311 -112.273471) (xy 148.595691 -112.212719) (xy 148.65644 -112.157337)
			(xy 148.72204 -112.107796) (xy 148.791931 -112.06452) (xy 148.865518 -112.027877) (xy 148.942171 -111.99818)
			(xy 149.021238 -111.975683) (xy 149.102043 -111.960577) (xy 149.183898 -111.952992) (xy 149.225 -111.952532)
			(xy 149.268098 -111.953004) (xy 149.353887 -111.961357) (xy 149.438467 -111.977965) (xy 149.521045 -112.002674)
			(xy 149.600847 -112.035251) (xy 149.677125 -112.075391) (xy 149.749165 -112.122718) (xy 149.816292 -112.176789)
			(xy 149.877876 -112.237097) (xy 149.933341 -112.303076) (xy 149.982167 -112.374109) (xy 150.023896 -112.44953)
			(xy 150.058137 -112.528632) (xy 150.071836 -112.569498) (xy 150.075523 -112.579517) (xy 150.089733 -112.595429)
			(xy 150.099268 -112.600232) (xy 150.137803 -112.618172) (xy 150.211568 -112.660421) (xy 150.280968 -112.709511)
			(xy 150.345369 -112.764997) (xy 150.404186 -112.826371) (xy 150.456881 -112.893075) (xy 150.502974 -112.964501)
			(xy 150.542046 -113.039997) (xy 150.557499 -113.078457) (xy 175.961036 -113.078457) (xy 175.961036 -112.993735)
			(xy 175.969089 -112.909398) (xy 175.985123 -112.826208) (xy 176.008991 -112.744918) (xy 176.040479 -112.666266)
			(xy 176.079301 -112.590963) (xy 176.125104 -112.519691) (xy 176.177475 -112.453095) (xy 176.23594 -112.39178)
			(xy 176.299968 -112.336299) (xy 176.36898 -112.287156) (xy 176.44235 -112.244796) (xy 176.519415 -112.209601)
			(xy 176.599477 -112.181892) (xy 176.68181 -112.161918) (xy 176.765669 -112.149861) (xy 176.850294 -112.14583)
			(xy 176.934919 -112.149861) (xy 177.018778 -112.161918) (xy 177.101111 -112.181892) (xy 177.181173 -112.209601)
			(xy 177.258238 -112.244796) (xy 177.331608 -112.287156) (xy 177.40062 -112.336299) (xy 177.464648 -112.39178)
			(xy 177.523113 -112.453095) (xy 177.575484 -112.519691) (xy 177.621287 -112.590963) (xy 177.660109 -112.666266)
			(xy 177.691597 -112.744918) (xy 177.715465 -112.826208) (xy 177.731499 -112.909398) (xy 177.739552 -112.993735)
			(xy 177.740056 -113.036096) (xy 177.739552 -113.078457) (xy 177.731499 -113.162794) (xy 177.715465 -113.245984)
			(xy 177.691597 -113.327274) (xy 177.660109 -113.405926) (xy 177.621287 -113.481229) (xy 177.575484 -113.552501)
			(xy 177.523113 -113.619097) (xy 177.464648 -113.680412) (xy 177.40062 -113.735893) (xy 177.331608 -113.785036)
			(xy 177.258238 -113.827396) (xy 177.181173 -113.862591) (xy 177.101111 -113.8903) (xy 177.018778 -113.910274)
			(xy 176.934919 -113.922331) (xy 176.850294 -113.926363) (xy 176.765669 -113.922331) (xy 176.68181 -113.910274)
			(xy 176.599477 -113.8903) (xy 176.519415 -113.862591) (xy 176.44235 -113.827396) (xy 176.36898 -113.785036)
			(xy 176.299968 -113.735893) (xy 176.23594 -113.680412) (xy 176.177475 -113.619097) (xy 176.125104 -113.552501)
			(xy 176.079301 -113.481229) (xy 176.040479 -113.405926) (xy 176.008991 -113.327274) (xy 175.985123 -113.245984)
			(xy 175.969089 -113.162794) (xy 175.961036 -113.078457) (xy 150.557499 -113.078457) (xy 150.573739 -113.118875)
			(xy 150.597765 -113.200416) (xy 150.613906 -113.283877) (xy 150.622013 -113.368496) (xy 150.622508 -113.411)
			(xy 150.622033 -113.452102) (xy 150.614448 -113.533957) (xy 150.599343 -113.614762) (xy 150.576847 -113.693829)
			(xy 150.547151 -113.770483) (xy 150.510509 -113.84407) (xy 150.467234 -113.913962) (xy 150.417694 -113.979563)
			(xy 150.362313 -114.040313) (xy 150.301563 -114.095694) (xy 150.235962 -114.145234) (xy 150.16607 -114.188509)
			(xy 150.092483 -114.225151) (xy 150.015829 -114.254847) (xy 149.936762 -114.277343) (xy 149.855957 -114.292448)
			(xy 149.774102 -114.300033) (xy 149.733 -114.300508) (xy 149.689903 -114.300009) (xy 149.604115 -114.291656)
			(xy 149.519537 -114.275048) (xy 149.436961 -114.250341) (xy 149.35716 -114.217766) (xy 149.280882 -114.177627)
			(xy 149.208843 -114.130303) (xy 149.141716 -114.076235) (xy 149.080132 -114.01593) (xy 149.024666 -113.949953)
			(xy 148.975839 -113.878923) (xy 148.934108 -113.803506) (xy 148.899864 -113.724406) (xy 148.886164 -113.683542)
			(xy 148.8825 -113.673512) (xy 148.868273 -113.657607) (xy 148.858732 -113.652808) (xy 148.820213 -113.634836)
			(xy 148.746449 -113.59259) (xy 148.677049 -113.543502) (xy 148.612648 -113.488019) (xy 148.553831 -113.426648)
			(xy 148.501135 -113.359947) (xy 148.45504 -113.288524) (xy 148.415967 -113.213032) (xy 148.384272 -113.134156)
			(xy 148.360243 -113.052618) (xy 148.3441 -112.96916) (xy 148.335989 -112.884543) (xy 148.335492 -112.84204)
			(xy 140.441222 -112.84204) (xy 140.454205 -112.909398) (xy 140.462258 -112.993735) (xy 140.462762 -113.036096)
			(xy 140.462258 -113.078457) (xy 140.454205 -113.162794) (xy 140.438171 -113.245984) (xy 140.414303 -113.327274)
			(xy 140.382815 -113.405926) (xy 140.343993 -113.481229) (xy 140.29819 -113.552501) (xy 140.245819 -113.619097)
			(xy 140.187354 -113.680412) (xy 140.123326 -113.735893) (xy 140.054314 -113.785036) (xy 139.980944 -113.827396)
			(xy 139.903879 -113.862591) (xy 139.823817 -113.8903) (xy 139.741484 -113.910274) (xy 139.657625 -113.922331)
			(xy 139.573 -113.926363) (xy 139.488375 -113.922331) (xy 139.404516 -113.910274) (xy 139.322183 -113.8903)
			(xy 139.242121 -113.862591) (xy 139.165056 -113.827396) (xy 139.091686 -113.785036) (xy 139.022674 -113.735893)
			(xy 138.958646 -113.680412) (xy 138.900181 -113.619097) (xy 138.84781 -113.552501) (xy 138.802007 -113.481229)
			(xy 138.763185 -113.405926) (xy 138.731697 -113.327274) (xy 138.707829 -113.245984) (xy 138.691795 -113.162794)
			(xy 138.683742 -113.078457) (xy 137.739381 -113.078457) (xy 137.739378 -113.078711) (xy 137.731325 -113.163048)
			(xy 137.715291 -113.246238) (xy 137.691423 -113.327528) (xy 137.659935 -113.40618) (xy 137.621113 -113.481483)
			(xy 137.57531 -113.552755) (xy 137.522939 -113.619351) (xy 137.464474 -113.680666) (xy 137.400446 -113.736147)
			(xy 137.331434 -113.78529) (xy 137.258064 -113.82765) (xy 137.180999 -113.862845) (xy 137.100937 -113.890554)
			(xy 137.018604 -113.910528) (xy 136.934745 -113.922585) (xy 136.85012 -113.926617) (xy 136.765495 -113.922585)
			(xy 136.681636 -113.910528) (xy 136.599303 -113.890554) (xy 136.519241 -113.862845) (xy 136.442176 -113.82765)
			(xy 136.368806 -113.78529) (xy 136.299794 -113.736147) (xy 136.235766 -113.680666) (xy 136.177301 -113.619351)
			(xy 136.12493 -113.552755) (xy 136.079127 -113.481483) (xy 136.040305 -113.40618) (xy 136.008817 -113.327528)
			(xy 135.984949 -113.246238) (xy 135.968915 -113.163048) (xy 135.960862 -113.078711) (xy 110.082133 -113.078711)
			(xy 110.066129 -113.133218) (xy 110.034641 -113.21187) (xy 109.995819 -113.287173) (xy 109.950016 -113.358445)
			(xy 109.897645 -113.425041) (xy 109.83918 -113.486356) (xy 109.775152 -113.541837) (xy 109.70614 -113.59098)
			(xy 109.63277 -113.63334) (xy 109.555705 -113.668535) (xy 109.475643 -113.696244) (xy 109.39331 -113.716218)
			(xy 109.309451 -113.728275) (xy 109.224826 -113.732307) (xy 109.140201 -113.728275) (xy 109.056342 -113.716218)
			(xy 108.974009 -113.696244) (xy 108.893947 -113.668535) (xy 108.816882 -113.63334) (xy 108.743512 -113.59098)
			(xy 108.6745 -113.541837) (xy 108.610472 -113.486356) (xy 108.552007 -113.425041) (xy 108.499636 -113.358445)
			(xy 108.453833 -113.287173) (xy 108.415011 -113.21187) (xy 108.383523 -113.133218) (xy 108.359655 -113.051928)
			(xy 108.343621 -112.968738) (xy 108.335568 -112.884401) (xy 97.726284 -112.884401) (xy 97.731151 -112.909652)
			(xy 97.739204 -112.993989) (xy 97.739708 -113.03635) (xy 97.739204 -113.078711) (xy 97.731151 -113.163048)
			(xy 97.715117 -113.246238) (xy 97.691249 -113.327528) (xy 97.659761 -113.40618) (xy 97.620939 -113.481483)
			(xy 97.575136 -113.552755) (xy 97.522765 -113.619351) (xy 97.4643 -113.680666) (xy 97.400272 -113.736147)
			(xy 97.33126 -113.78529) (xy 97.25789 -113.82765) (xy 97.180825 -113.862845) (xy 97.100763 -113.890554)
			(xy 97.01843 -113.910528) (xy 96.934571 -113.922585) (xy 96.849946 -113.926617) (xy 96.765321 -113.922585)
			(xy 96.681462 -113.910528) (xy 96.599129 -113.890554) (xy 96.519067 -113.862845) (xy 96.442002 -113.82765)
			(xy 96.368632 -113.78529) (xy 96.29962 -113.736147) (xy 96.235592 -113.680666) (xy 96.177127 -113.619351)
			(xy 96.124756 -113.552755) (xy 96.078953 -113.481483) (xy 96.040131 -113.40618) (xy 96.008643 -113.327528)
			(xy 95.984775 -113.246238) (xy 95.968741 -113.163048) (xy 95.960688 -113.078711) (xy 57.739284 -113.078711)
			(xy 57.731231 -113.163048) (xy 57.715197 -113.246238) (xy 57.691329 -113.327528) (xy 57.659841 -113.40618)
			(xy 57.621019 -113.481483) (xy 57.575216 -113.552755) (xy 57.522845 -113.619351) (xy 57.46438 -113.680666)
			(xy 57.400352 -113.736147) (xy 57.33134 -113.78529) (xy 57.25797 -113.82765) (xy 57.180905 -113.862845)
			(xy 57.100843 -113.890554) (xy 57.01851 -113.910528) (xy 56.934651 -113.922585) (xy 56.850026 -113.926617)
			(xy 56.765401 -113.922585) (xy 56.681542 -113.910528) (xy 56.599209 -113.890554) (xy 56.519147 -113.862845)
			(xy 56.442082 -113.82765) (xy 56.368712 -113.78529) (xy 56.2997 -113.736147) (xy 56.235672 -113.680666)
			(xy 56.177207 -113.619351) (xy 56.124836 -113.552755) (xy 56.079033 -113.481483) (xy 56.040211 -113.40618)
			(xy 56.008723 -113.327528) (xy 55.984855 -113.246238) (xy 55.968821 -113.163048) (xy 55.960768 -113.078711)
			(xy 36.01974 -113.078711) (xy 36.01974 -114.856711) (xy 108.843568 -114.856711) (xy 108.843568 -114.771989)
			(xy 108.851621 -114.687652) (xy 108.867655 -114.604462) (xy 108.891523 -114.523172) (xy 108.923011 -114.44452)
			(xy 108.961833 -114.369217) (xy 109.007636 -114.297945) (xy 109.060007 -114.231349) (xy 109.118472 -114.170034)
			(xy 109.1825 -114.114553) (xy 109.251512 -114.06541) (xy 109.324882 -114.02305) (xy 109.401947 -113.987855)
			(xy 109.482009 -113.960146) (xy 109.564342 -113.940172) (xy 109.648201 -113.928115) (xy 109.732826 -113.924084)
			(xy 109.817451 -113.928115) (xy 109.90131 -113.940172) (xy 109.983643 -113.960146) (xy 110.063705 -113.987855)
			(xy 110.14077 -114.02305) (xy 110.21414 -114.06541) (xy 110.283152 -114.114553) (xy 110.34718 -114.170034)
			(xy 110.405645 -114.231349) (xy 110.458016 -114.297945) (xy 110.503819 -114.369217) (xy 110.542641 -114.44452)
			(xy 110.574129 -114.523172) (xy 110.597997 -114.604462) (xy 110.614031 -114.687652) (xy 110.622084 -114.771989)
			(xy 110.622588 -114.81435) (xy 110.622084 -114.856711) (xy 110.614031 -114.941048) (xy 110.597997 -115.024238)
			(xy 110.574129 -115.105528) (xy 110.542641 -115.18418) (xy 110.503819 -115.259483) (xy 110.458016 -115.330755)
			(xy 110.405645 -115.397351) (xy 110.34718 -115.458666) (xy 110.283152 -115.514147) (xy 110.21414 -115.56329)
			(xy 110.14077 -115.60565) (xy 110.063705 -115.640845) (xy 109.983643 -115.668554) (xy 109.90131 -115.688528)
			(xy 109.817451 -115.700585) (xy 109.732826 -115.704617) (xy 109.648201 -115.700585) (xy 109.564342 -115.688528)
			(xy 109.482009 -115.668554) (xy 109.401947 -115.640845) (xy 109.324882 -115.60565) (xy 109.251512 -115.56329)
			(xy 109.1825 -115.514147) (xy 109.118472 -115.458666) (xy 109.060007 -115.397351) (xy 109.007636 -115.330755)
			(xy 108.961833 -115.259483) (xy 108.923011 -115.18418) (xy 108.891523 -115.105528) (xy 108.867655 -115.024238)
			(xy 108.851621 -114.941048) (xy 108.843568 -114.856711) (xy 36.01974 -114.856711) (xy 36.01974 -117.625114)
			(xy 36.020167 -117.635182) (xy 36.027889 -117.653779) (xy 36.034726 -117.661182) (xy 36.768532 -118.394988)
			(xy 36.775932 -118.401831) (xy 36.79453 -118.409555) (xy 36.8046 -118.409974) (xy 222.159322 -118.409974)
			(xy 222.192582 -118.410497) (xy 222.258531 -118.419186) (xy 222.322781 -118.436413) (xy 222.384231 -118.461883)
			(xy 222.441828 -118.495159) (xy 222.494587 -118.535672) (xy 222.518478 -118.558818) (xy 223.615758 -119.656098)
			(xy 223.638917 -119.679977) (xy 223.679428 -119.73274) (xy 223.712703 -119.79034) (xy 223.738173 -119.851792)
			(xy 223.755401 -119.916043) (xy 223.764092 -119.981994) (xy 223.764602 -120.015254) (xy 223.764602 -137.795)
			(xy 234.745787 -137.795) (xy 234.749742 -137.596168) (xy 234.761597 -137.397649) (xy 234.781336 -137.19976)
			(xy 234.808927 -137.002811) (xy 234.844325 -136.807115) (xy 234.887476 -136.612981) (xy 234.938311 -136.420716)
			(xy 234.99675 -136.230624) (xy 235.0627 -136.043006) (xy 235.136056 -135.858158) (xy 235.216704 -135.676373)
			(xy 235.304515 -135.497937) (xy 235.39935 -135.323134) (xy 235.501061 -135.152239) (xy 235.609484 -134.985523)
			(xy 235.724451 -134.823249) (xy 235.845778 -134.665675) (xy 235.973273 -134.513048) (xy 236.106736 -134.365611)
			(xy 236.245954 -134.223596) (xy 236.390709 -134.087229) (xy 236.540771 -133.956724) (xy 236.695902 -133.832288)
			(xy 236.855858 -133.714119) (xy 237.020385 -133.602402) (xy 237.189224 -133.497314) (xy 237.362108 -133.399022)
			(xy 237.538762 -133.307681) (xy 237.718908 -133.223435) (xy 237.902261 -133.146418) (xy 238.088531 -133.076751)
			(xy 238.277424 -133.014545) (xy 238.46864 -132.959897) (xy 238.661878 -132.912895) (xy 238.856831 -132.873613)
			(xy 239.053192 -132.842112) (xy 239.25065 -132.818443) (xy 239.448894 -132.802642) (xy 239.647608 -132.794736)
			(xy 239.747044 -132.794248) (xy 261.747 -132.794248) (xy 261.846436 -132.794742) (xy 262.04515 -132.802649)
			(xy 262.243393 -132.818449) (xy 262.440851 -132.842118) (xy 262.637211 -132.873619) (xy 262.832165 -132.912902)
			(xy 263.025402 -132.959904) (xy 263.216618 -133.014551) (xy 263.40551 -133.076758) (xy 263.591779 -133.146424)
			(xy 263.775132 -133.223442) (xy 263.955278 -133.307687) (xy 264.131932 -133.399028) (xy 264.304815 -133.49732)
			(xy 264.473653 -133.602408) (xy 264.638181 -133.714125) (xy 264.798136 -133.832295) (xy 264.953267 -133.95673)
			(xy 265.103329 -134.087235) (xy 265.248083 -134.223602) (xy 265.387301 -134.365616) (xy 265.520764 -134.513053)
			(xy 265.648259 -134.66568) (xy 265.769585 -134.823254) (xy 265.884551 -134.985528) (xy 265.992975 -135.152243)
			(xy 266.094685 -135.323138) (xy 266.18952 -135.497941) (xy 266.277331 -135.676376) (xy 266.357979 -135.858161)
			(xy 266.431335 -136.043009) (xy 266.497285 -136.230627) (xy 266.555723 -136.420719) (xy 266.606558 -136.612983)
			(xy 266.649709 -136.807117) (xy 266.685107 -137.002812) (xy 266.712698 -137.199761) (xy 266.732437 -137.39765)
			(xy 266.744293 -137.596168) (xy 266.748247 -137.795) (xy 266.744293 -137.993832) (xy 266.732437 -138.19235)
			(xy 266.712698 -138.390239) (xy 266.685107 -138.587188) (xy 266.649709 -138.782883) (xy 266.606558 -138.977017)
			(xy 266.555723 -139.169281) (xy 266.497285 -139.359373) (xy 266.431335 -139.546991) (xy 266.357979 -139.731839)
			(xy 266.277331 -139.913624) (xy 266.18952 -140.092059) (xy 266.094685 -140.266862) (xy 265.992975 -140.437757)
			(xy 265.884551 -140.604472) (xy 265.769585 -140.766746) (xy 265.648259 -140.92432) (xy 265.520764 -141.076947)
			(xy 265.387301 -141.224384) (xy 265.248083 -141.366398) (xy 265.103329 -141.502765) (xy 264.953267 -141.63327)
			(xy 264.798136 -141.757705) (xy 264.638181 -141.875875) (xy 264.473653 -141.987592) (xy 264.304815 -142.09268)
			(xy 264.131932 -142.190972) (xy 263.955278 -142.282313) (xy 263.775132 -142.366558) (xy 263.591779 -142.443576)
			(xy 263.40551 -142.513242) (xy 263.216618 -142.575449) (xy 263.025402 -142.630096) (xy 262.832165 -142.677098)
			(xy 262.637211 -142.716381) (xy 262.440851 -142.747882) (xy 262.243393 -142.771551) (xy 262.04515 -142.787351)
			(xy 261.846436 -142.795258) (xy 261.747 -142.795752) (xy 239.747044 -142.795752) (xy 239.647608 -142.795264)
			(xy 239.448894 -142.787358) (xy 239.25065 -142.771557) (xy 239.053192 -142.747888) (xy 238.856831 -142.716387)
			(xy 238.661878 -142.677105) (xy 238.46864 -142.630103) (xy 238.277424 -142.575455) (xy 238.088531 -142.513249)
			(xy 237.902261 -142.443582) (xy 237.718908 -142.366565) (xy 237.538762 -142.282319) (xy 237.362108 -142.190978)
			(xy 237.189224 -142.092686) (xy 237.020385 -141.987598) (xy 236.855858 -141.875881) (xy 236.695902 -141.757712)
			(xy 236.540771 -141.633276) (xy 236.390709 -141.502771) (xy 236.245954 -141.366404) (xy 236.106736 -141.224389)
			(xy 235.973273 -141.076952) (xy 235.845778 -140.924325) (xy 235.724451 -140.766751) (xy 235.609484 -140.604477)
			(xy 235.501061 -140.437761) (xy 235.39935 -140.266866) (xy 235.304515 -140.092063) (xy 235.216704 -139.913627)
			(xy 235.136056 -139.731842) (xy 235.0627 -139.546994) (xy 234.99675 -139.359376) (xy 234.938311 -139.169284)
			(xy 234.887476 -138.977019) (xy 234.844325 -138.782885) (xy 234.808927 -138.587189) (xy 234.781336 -138.39024)
			(xy 234.761597 -138.192351) (xy 234.749742 -137.993832) (xy 234.745787 -137.795) (xy 223.764602 -137.795)
			(xy 223.764602 -139.67587) (xy 223.765001 -139.685857) (xy 223.772629 -139.704316) (xy 223.786766 -139.718425)
			(xy 223.795844 -139.722606) (xy 223.859244 -139.749731) (xy 223.983087 -139.810416) (xy 224.103157 -139.878262)
			(xy 224.219041 -139.953035) (xy 224.330339 -140.034476) (xy 224.436668 -140.122306) (xy 224.537663 -140.216221)
			(xy 224.632974 -140.315899) (xy 224.722274 -140.420996) (xy 224.805256 -140.531151) (xy 224.881633 -140.645983)
			(xy 224.951142 -140.765098) (xy 225.013545 -140.888085) (xy 225.068626 -141.014521) (xy 225.116196 -141.14397)
			(xy 225.15609 -141.275987) (xy 225.188172 -141.410116) (xy 225.21233 -141.545897) (xy 225.228482 -141.682861)
			(xy 225.236573 -141.820536) (xy 225.236573 -141.958449) (xy 225.228484 -142.096124) (xy 225.212333 -142.233088)
			(xy 225.188175 -142.368868) (xy 225.156094 -142.502998) (xy 225.116201 -142.635015) (xy 225.068632 -142.764464)
			(xy 225.013552 -142.890901) (xy 224.95115 -143.013888) (xy 224.881641 -143.133004) (xy 224.805264 -143.247837)
			(xy 224.722284 -143.357992) (xy 224.632984 -143.463089) (xy 224.537674 -143.562768) (xy 224.43668 -143.656684)
			(xy 224.330351 -143.744515) (xy 224.219054 -143.825956) (xy 224.10317 -143.90073) (xy 223.983101 -143.968576)
			(xy 223.859258 -144.029263) (xy 223.795844 -144.056354) (xy 223.786857 -144.060656) (xy 223.772817 -144.074765)
			(xy 223.765166 -144.093141) (xy 223.764602 -144.10309) (xy 223.764602 -144.991582) (xy 223.76504 -145.001645)
			(xy 223.772776 -145.020228) (xy 223.779588 -145.02765) (xy 224.720912 -145.968974) (xy 224.72831 -145.975821)
			(xy 224.746908 -145.983556) (xy 224.75698 -145.98396)
		)
		(stroke
			(width 0)
			(type solid)
		)
		(fill yes)
		(layer "In4.Cu")
		(net "P52V_HS")
	)
	(gr_arc
		(start 2.999994 -128.729994)
		(mid 0.878678 -129.608672)
		(end 0 -131.729988)
		(stroke
			(width 2.032)
			(type default)
		)
		(layer "In4.Cu")
	)
	(gr_line
		(start 2.999994 -116.229892)
		(end 9.59993 -116.229892)
		(stroke
			(width 2.032)
			(type default)
		)
		(layer "In4.Cu")
	)
	(gr_arc
		(start 2.999994 -31.569914)
		(mid 0.878678 -32.448592)
		(end 0 -34.569908)
		(stroke
			(width 2.032)
			(type default)
		)
		(layer "In4.Cu")
	)
	(gr_line
		(start 2.999994 -19.070066)
		(end 9.59993 -19.070066)
		(stroke
			(width 2.032)
			(type default)
		)
		(layer "In4.Cu")
	)
	(gr_arc
		(start 4.99999 0)
		(mid 1.464463 -1.464463)
		(end 0 -4.99999)
		(stroke
			(width 2.032)
			(type default)
		)
		(layer "In4.Cu")
	)
	(gr_line
		(start 8.1534 -77.1906)
		(end 8.1534 -68.5546)
		(stroke
			(width 1.016)
			(type default)
		)
		(layer "In4.Cu")
	)
	(gr_line
		(start 8.1534 -68.5546)
		(end 9.1186 -67.5894)
		(stroke
			(width 1.016)
			(type default)
		)
		(layer "In4.Cu")
	)
	(gr_line
		(start 8.9154 -77.9526)
		(end 8.1534 -77.1906)
		(stroke
			(width 1.016)
			(type default)
		)
		(layer "In4.Cu")
	)
	(gr_line
		(start 9.1186 -67.5894)
		(end 37.4904 -67.5894)
		(stroke
			(width 1.016)
			(type default)
		)
		(layer "In4.Cu")
	)
	(gr_line
		(start 9.59993 -128.729994)
		(end 2.999994 -128.729994)
		(stroke
			(width 2.032)
			(type default)
		)
		(layer "In4.Cu")
	)
	(gr_arc
		(start 9.59993 -128.729994)
		(mid 9.953557 -128.583675)
		(end 10.100056 -128.230122)
		(stroke
			(width 2.032)
			(type default)
		)
		(layer "In4.Cu")
	)
	(gr_line
		(start 9.59993 -31.569914)
		(end 2.999994 -31.569914)
		(stroke
			(width 2.032)
			(type default)
		)
		(layer "In4.Cu")
	)
	(gr_arc
		(start 9.59993 -31.569914)
		(mid 9.953401 -31.42345)
		(end 10.100056 -31.070042)
		(stroke
			(width 2.032)
			(type default)
		)
		(layer "In4.Cu")
	)
	(gr_line
		(start 10.100056 -128.230122)
		(end 10.100056 -118.917974)
		(stroke
			(width 2.032)
			(type default)
		)
		(layer "In4.Cu")
	)
	(gr_line
		(start 10.100056 -118.917974)
		(end 10.100056 -116.730018)
		(stroke
			(width 2.032)
			(type default)
		)
		(layer "In4.Cu")
	)
	(gr_arc
		(start 10.100056 -116.730018)
		(mid 9.953572 -116.376376)
		(end 9.59993 -116.229892)
		(stroke
			(width 2.032)
			(type default)
		)
		(layer "In4.Cu")
	)
	(gr_line
		(start 10.100056 -31.070042)
		(end 10.100056 -19.569938)
		(stroke
			(width 2.032)
			(type default)
		)
		(layer "In4.Cu")
	)
	(gr_arc
		(start 10.100056 -19.569938)
		(mid 9.953467 -19.21655)
		(end 9.59993 -19.070066)
		(stroke
			(width 2.032)
			(type default)
		)
		(layer "In4.Cu")
	)
	(gr_line
		(start 10.100056 -19.569938)
		(end 31.253938 -19.569938)
		(stroke
			(width 1.016)
			(type default)
		)
		(layer "In4.Cu")
	)
	(gr_line
		(start 10.668 -25.654)
		(end 30.988 -25.654)
		(stroke
			(width 2.54)
			(type default)
		)
		(layer "In4.Cu")
	)
	(gr_line
		(start 10.922 -29.337)
		(end 10.922 -24.638)
		(stroke
			(width 2.54)
			(type default)
		)
		(layer "In4.Cu")
	)
	(gr_line
		(start 10.922 -28.575)
		(end 11.303 -28.956)
		(stroke
			(width 2.54)
			(type default)
		)
		(layer "In4.Cu")
	)
	(gr_line
		(start 10.922 -27.432)
		(end 10.922 -28.575)
		(stroke
			(width 2.54)
			(type default)
		)
		(layer "In4.Cu")
	)
	(gr_line
		(start 10.922 -24.638)
		(end 11.811 -23.749)
		(stroke
			(width 2.54)
			(type default)
		)
		(layer "In4.Cu")
	)
	(gr_line
		(start 11.049 -27.559)
		(end 10.922 -27.432)
		(stroke
			(width 2.54)
			(type default)
		)
		(layer "In4.Cu")
	)
	(gr_line
		(start 11.049 -21.59)
		(end 11.049 -20.701)
		(stroke
			(width 2.54)
			(type default)
		)
		(layer "In4.Cu")
	)
	(gr_line
		(start 11.049 -20.701)
		(end 30.353 -20.701)
		(stroke
			(width 2.54)
			(type default)
		)
		(layer "In4.Cu")
	)
	(gr_line
		(start 11.303 -28.956)
		(end 30.353 -28.956)
		(stroke
			(width 2.54)
			(type default)
		)
		(layer "In4.Cu")
	)
	(gr_line
		(start 11.303 -21.844)
		(end 11.049 -21.59)
		(stroke
			(width 2.54)
			(type default)
		)
		(layer "In4.Cu")
	)
	(gr_line
		(start 11.43 -29.845)
		(end 10.922 -29.337)
		(stroke
			(width 2.54)
			(type default)
		)
		(layer "In4.Cu")
	)
	(gr_line
		(start 11.684 -21.463)
		(end 11.303 -21.844)
		(stroke
			(width 2.54)
			(type default)
		)
		(layer "In4.Cu")
	)
	(gr_line
		(start 11.811 -23.749)
		(end 30.48 -23.749)
		(stroke
			(width 2.54)
			(type default)
		)
		(layer "In4.Cu")
	)
	(gr_line
		(start 14.9606 -77.9526)
		(end 8.9154 -77.9526)
		(stroke
			(width 1.016)
			(type default)
		)
		(layer "In4.Cu")
	)
	(gr_line
		(start 15.24 -117.91061)
		(end 15.24 -78.232)
		(stroke
			(width 1.016)
			(type default)
		)
		(layer "In4.Cu")
	)
	(gr_line
		(start 15.24 -78.232)
		(end 14.9606 -77.9526)
		(stroke
			(width 1.016)
			(type default)
		)
		(layer "In4.Cu")
	)
	(gr_line
		(start 16.247364 -118.917974)
		(end 15.24 -117.91061)
		(stroke
			(width 1.016)
			(type default)
		)
		(layer "In4.Cu")
	)
	(gr_circle
		(center 27.5844 -66.43624)
		(end 28.4734 -66.43624)
		(stroke
			(width 0.2)
			(type default)
		)
		(fill no)
		(layer "In4.Cu")
	)
	(gr_circle
		(center 27.5844 -65.67424)
		(end 28.4734 -65.67424)
		(stroke
			(width 0.2)
			(type default)
		)
		(fill no)
		(layer "In4.Cu")
	)
	(gr_circle
		(center 27.5844 -64.91224)
		(end 28.4734 -64.91224)
		(stroke
			(width 0.2)
			(type default)
		)
		(fill no)
		(layer "In4.Cu")
	)
	(gr_circle
		(center 28.3464 -66.43624)
		(end 29.2354 -66.43624)
		(stroke
			(width 0.2)
			(type default)
		)
		(fill no)
		(layer "In4.Cu")
	)
	(gr_circle
		(center 28.3464 -65.67424)
		(end 29.2354 -65.67424)
		(stroke
			(width 0.2)
			(type default)
		)
		(fill no)
		(layer "In4.Cu")
	)
	(gr_circle
		(center 28.3464 -64.91224)
		(end 29.2354 -64.91224)
		(stroke
			(width 0.2)
			(type default)
		)
		(fill no)
		(layer "In4.Cu")
	)
	(gr_line
		(start 30.353 -28.956)
		(end 30.734 -28.575)
		(stroke
			(width 2.54)
			(type default)
		)
		(layer "In4.Cu")
	)
	(gr_line
		(start 30.353 -27.559)
		(end 11.049 -27.559)
		(stroke
			(width 2.54)
			(type default)
		)
		(layer "In4.Cu")
	)
	(gr_line
		(start 30.353 -25.654)
		(end 28.829 -27.178)
		(stroke
			(width 2.54)
			(type default)
		)
		(layer "In4.Cu")
	)
	(gr_line
		(start 30.353 -20.701)
		(end 30.353 -25.654)
		(stroke
			(width 2.54)
			(type default)
		)
		(layer "In4.Cu")
	)
	(gr_line
		(start 30.48 -29.845)
		(end 11.43 -29.845)
		(stroke
			(width 2.54)
			(type default)
		)
		(layer "In4.Cu")
	)
	(gr_line
		(start 30.48 -23.749)
		(end 30.861 -24.13)
		(stroke
			(width 2.54)
			(type default)
		)
		(layer "In4.Cu")
	)
	(gr_line
		(start 30.48 -21.463)
		(end 11.684 -21.463)
		(stroke
			(width 2.54)
			(type default)
		)
		(layer "In4.Cu")
	)
	(gr_line
		(start 30.734 -29.591)
		(end 30.48 -29.845)
		(stroke
			(width 2.54)
			(type default)
		)
		(layer "In4.Cu")
	)
	(gr_line
		(start 30.734 -28.575)
		(end 30.734 -29.591)
		(stroke
			(width 2.54)
			(type default)
		)
		(layer "In4.Cu")
	)
	(gr_line
		(start 30.861 -24.13)
		(end 30.861 -21.844)
		(stroke
			(width 2.54)
			(type default)
		)
		(layer "In4.Cu")
	)
	(gr_line
		(start 30.861 -21.844)
		(end 30.48 -21.463)
		(stroke
			(width 2.54)
			(type default)
		)
		(layer "In4.Cu")
	)
	(gr_line
		(start 30.988 -26.924)
		(end 30.353 -27.559)
		(stroke
			(width 2.54)
			(type default)
		)
		(layer "In4.Cu")
	)
	(gr_line
		(start 30.988 -25.654)
		(end 30.988 -26.924)
		(stroke
			(width 2.54)
			(type default)
		)
		(layer "In4.Cu")
	)
	(gr_line
		(start 31.253938 -19.569938)
		(end 31.877 -20.193)
		(stroke
			(width 1.016)
			(type default)
		)
		(layer "In4.Cu")
	)
	(gr_line
		(start 31.413958 -31.070042)
		(end 10.100056 -31.070042)
		(stroke
			(width 1.016)
			(type default)
		)
		(layer "In4.Cu")
	)
	(gr_line
		(start 31.877 -30.607)
		(end 31.413958 -31.070042)
		(stroke
			(width 1.016)
			(type default)
		)
		(layer "In4.Cu")
	)
	(gr_line
		(start 31.877 -20.193)
		(end 31.877 -30.607)
		(stroke
			(width 1.016)
			(type default)
		)
		(layer "In4.Cu")
	)
	(gr_line
		(start 34.925 -57.15)
		(end 39.630858 -61.855858)
		(stroke
			(width 1.016)
			(type default)
		)
		(layer "In4.Cu")
	)
	(gr_line
		(start 34.925 -56.261)
		(end 34.925 -57.15)
		(stroke
			(width 1.016)
			(type default)
		)
		(layer "In4.Cu")
	)
	(gr_line
		(start 34.925 -56.261)
		(end 34.925 -46.433994)
		(stroke
			(width 1.016)
			(type default)
		)
		(layer "In4.Cu")
	)
	(gr_line
		(start 34.925 -46.433994)
		(end 57.531 -23.827994)
		(stroke
			(width 1.016)
			(type default)
		)
		(layer "In4.Cu")
	)
	(gr_line
		(start 35.51174 -117.856508)
		(end 34.450274 -118.917974)
		(stroke
			(width 1.016)
			(type default)
		)
		(layer "In4.Cu")
	)
	(gr_line
		(start 35.51174 -84.78266)
		(end 35.51174 -118.917974)
		(stroke
			(width 1.016)
			(type default)
		)
		(layer "In4.Cu")
	)
	(gr_line
		(start 36.573206 -118.917974)
		(end 35.51174 -117.856508)
		(stroke
			(width 1.016)
			(type default)
		)
		(layer "In4.Cu")
	)
	(gr_line
		(start 36.9824 -83.312)
		(end 35.51174 -84.78266)
		(stroke
			(width 1.016)
			(type default)
		)
		(layer "In4.Cu")
	)
	(gr_line
		(start 37.4904 -67.5894)
		(end 38.354 -68.453)
		(stroke
			(width 1.016)
			(type default)
		)
		(layer "In4.Cu")
	)
	(gr_line
		(start 37.4904 -67.5894)
		(end 39.296086 -67.5894)
		(stroke
			(width 1.016)
			(type default)
		)
		(layer "In4.Cu")
	)
	(gr_line
		(start 37.653722 -146.937222)
		(end 39.497 -145.093944)
		(stroke
			(width 1.016)
			(type default)
		)
		(layer "In4.Cu")
	)
	(gr_circle
		(center 38.261036 -55.642002)
		(end 39.150036 -55.642002)
		(stroke
			(width 0.2)
			(type default)
		)
		(fill no)
		(layer "In4.Cu")
	)
	(gr_line
		(start 38.3286 -68.199)
		(end 39.605458 -66.922142)
		(stroke
			(width 1.016)
			(type default)
		)
		(layer "In4.Cu")
	)
	(gr_line
		(start 38.354 -74.832972)
		(end 46.833028 -83.312)
		(stroke
			(width 1.016)
			(type default)
		)
		(layer "In4.Cu")
	)
	(gr_line
		(start 38.354 -69.729858)
		(end 38.354 -74.832972)
		(stroke
			(width 1.016)
			(type default)
		)
		(layer "In4.Cu")
	)
	(gr_line
		(start 38.354 -69.729858)
		(end 38.354 -68.453)
		(stroke
			(width 1.016)
			(type default)
		)
		(layer "In4.Cu")
	)
	(gr_circle
		(center 38.692836 -58.436002)
		(end 39.581836 -58.436002)
		(stroke
			(width 0.2)
			(type default)
		)
		(fill no)
		(layer "In4.Cu")
	)
	(gr_circle
		(center 38.692836 -57.547002)
		(end 39.581836 -57.547002)
		(stroke
			(width 0.2)
			(type default)
		)
		(fill no)
		(layer "In4.Cu")
	)
	(gr_circle
		(center 38.692836 -56.658002)
		(end 39.581836 -56.658002)
		(stroke
			(width 0.2)
			(type default)
		)
		(fill no)
		(layer "In4.Cu")
	)
	(gr_circle
		(center 38.98392 -54.1909)
		(end 39.87292 -54.1909)
		(stroke
			(width 0.2)
			(type default)
		)
		(fill no)
		(layer "In4.Cu")
	)
	(gr_circle
		(center 39.378636 -58.817002)
		(end 40.267636 -58.817002)
		(stroke
			(width 0.2)
			(type default)
		)
		(fill no)
		(layer "In4.Cu")
	)
	(gr_circle
		(center 39.378636 -57.928002)
		(end 40.267636 -57.928002)
		(stroke
			(width 0.2)
			(type default)
		)
		(fill no)
		(layer "In4.Cu")
	)
	(gr_circle
		(center 39.378636 -57.039002)
		(end 40.267636 -57.039002)
		(stroke
			(width 0.2)
			(type default)
		)
		(fill no)
		(layer "In4.Cu")
	)
	(gr_line
		(start 39.497 -146.99996)
		(end 4.99999 -146.99996)
		(stroke
			(width 2.032)
			(type default)
		)
		(layer "In4.Cu")
	)
	(gr_line
		(start 39.497 -146.99996)
		(end 39.497 -118.917974)
		(stroke
			(width 1.016)
			(type default)
		)
		(layer "In4.Cu")
	)
	(gr_line
		(start 39.497 -120.523)
		(end 37.891974 -118.917974)
		(stroke
			(width 1.016)
			(type default)
		)
		(layer "In4.Cu")
	)
	(gr_line
		(start 39.497 -118.917974)
		(end 16.247364 -118.917974)
		(stroke
			(width 1.016)
			(type default)
		)
		(layer "In4.Cu")
	)
	(gr_line
		(start 39.497 -118.917974)
		(end 41.102026 -118.917974)
		(stroke
			(width 1.016)
			(type default)
		)
		(layer "In4.Cu")
	)
	(gr_line
		(start 39.630858 -68.453)
		(end 38.354 -69.729858)
		(stroke
			(width 1.016)
			(type default)
		)
		(layer "In4.Cu")
	)
	(gr_line
		(start 39.630858 -68.453)
		(end 38.354 -68.453)
		(stroke
			(width 1.016)
			(type default)
		)
		(layer "In4.Cu")
	)
	(gr_line
		(start 39.630858 -61.855858)
		(end 39.630858 -68.453)
		(stroke
			(width 1.016)
			(type default)
		)
		(layer "In4.Cu")
	)
	(gr_line
		(start 40.907716 -68.453)
		(end 39.630858 -67.176142)
		(stroke
			(width 1.016)
			(type default)
		)
		(layer "In4.Cu")
	)
	(gr_line
		(start 41.102026 -118.917974)
		(end 39.497 -120.523)
		(stroke
			(width 1.016)
			(type default)
		)
		(layer "In4.Cu")
	)
	(gr_line
		(start 41.102026 -118.917974)
		(end 222.159322 -118.917974)
		(stroke
			(width 1.016)
			(type default)
		)
		(layer "In4.Cu")
	)
	(gr_line
		(start 41.340278 -146.937222)
		(end 39.497 -145.093944)
		(stroke
			(width 1.016)
			(type default)
		)
		(layer "In4.Cu")
	)
	(gr_line
		(start 45.363384 -82.550254)
		(end 44.601638 -83.312)
		(stroke
			(width 1.016)
			(type default)
		)
		(layer "In4.Cu")
	)
	(gr_line
		(start 45.363384 -81.842356)
		(end 45.363384 -82.550254)
		(stroke
			(width 1.016)
			(type default)
		)
		(layer "In4.Cu")
	)
	(gr_line
		(start 46.833028 -83.312)
		(end 36.9824 -83.312)
		(stroke
			(width 1.016)
			(type default)
		)
		(layer "In4.Cu")
	)
	(gr_line
		(start 46.833028 -83.312)
		(end 149.098 -83.312)
		(stroke
			(width 1.016)
			(type default)
		)
		(layer "In4.Cu")
	)
	(gr_line
		(start 49.793906 -68.453)
		(end 39.630858 -68.453)
		(stroke
			(width 1.016)
			(type default)
		)
		(layer "In4.Cu")
	)
	(gr_line
		(start 49.793906 -68.453)
		(end 56.173878 -74.832972)
		(stroke
			(width 1.016)
			(type default)
		)
		(layer "In4.Cu")
	)
	(gr_line
		(start 56.173878 -74.832972)
		(end 78.476094 -74.832972)
		(stroke
			(width 1.016)
			(type default)
		)
		(layer "In4.Cu")
	)
	(gr_circle
		(center 62.850014 -77.71765)
		(end 63.739014 -77.71765)
		(stroke
			(width 0.2)
			(type default)
		)
		(fill no)
		(layer "In4.Cu")
	)
	(gr_line
		(start 78.476094 -74.832972)
		(end 86.93277 -66.376296)
		(stroke
			(width 1.016)
			(type default)
		)
		(layer "In4.Cu")
	)
	(gr_line
		(start 86.93277 -66.376296)
		(end 212.57641 -66.376296)
		(stroke
			(width 1.016)
			(type default)
		)
		(layer "In4.Cu")
	)
	(gr_circle
		(center 102.849934 -77.71765)
		(end 103.738934 -77.71765)
		(stroke
			(width 0.2)
			(type default)
		)
		(fill no)
		(layer "In4.Cu")
	)
	(gr_circle
		(center 104.469946 -70.409816)
		(end 106.667046 -70.409816)
		(stroke
			(width 0.2)
			(type default)
		)
		(fill no)
		(layer "In4.Cu")
	)
	(gr_circle
		(center 108.279946 -70.409816)
		(end 110.477046 -70.409816)
		(stroke
			(width 0.2)
			(type default)
		)
		(fill no)
		(layer "In4.Cu")
	)
	(gr_circle
		(center 110.362746 -71.929244)
		(end 111.251746 -71.929244)
		(stroke
			(width 0.2)
			(type default)
		)
		(fill no)
		(layer "In4.Cu")
	)
	(gr_circle
		(center 110.362746 -70.913244)
		(end 111.251746 -70.913244)
		(stroke
			(width 0.2)
			(type default)
		)
		(fill no)
		(layer "In4.Cu")
	)
	(gr_circle
		(center 110.362746 -69.897244)
		(end 111.251746 -69.897244)
		(stroke
			(width 0.2)
			(type default)
		)
		(fill no)
		(layer "In4.Cu")
	)
	(gr_circle
		(center 110.362746 -68.881244)
		(end 111.251746 -68.881244)
		(stroke
			(width 0.2)
			(type default)
		)
		(fill no)
		(layer "In4.Cu")
	)
	(gr_circle
		(center 111.378746 -71.929244)
		(end 112.267746 -71.929244)
		(stroke
			(width 0.2)
			(type default)
		)
		(fill no)
		(layer "In4.Cu")
	)
	(gr_circle
		(center 111.378746 -70.913244)
		(end 112.267746 -70.913244)
		(stroke
			(width 0.2)
			(type default)
		)
		(fill no)
		(layer "In4.Cu")
	)
	(gr_circle
		(center 111.378746 -69.897244)
		(end 112.267746 -69.897244)
		(stroke
			(width 0.2)
			(type default)
		)
		(fill no)
		(layer "In4.Cu")
	)
	(gr_circle
		(center 111.378746 -68.881244)
		(end 112.267746 -68.881244)
		(stroke
			(width 0.2)
			(type default)
		)
		(fill no)
		(layer "In4.Cu")
	)
	(gr_circle
		(center 112.394746 -71.929244)
		(end 113.283746 -71.929244)
		(stroke
			(width 0.2)
			(type default)
		)
		(fill no)
		(layer "In4.Cu")
	)
	(gr_circle
		(center 112.394746 -70.913244)
		(end 113.283746 -70.913244)
		(stroke
			(width 0.2)
			(type default)
		)
		(fill no)
		(layer "In4.Cu")
	)
	(gr_circle
		(center 112.394746 -69.897244)
		(end 113.283746 -69.897244)
		(stroke
			(width 0.2)
			(type default)
		)
		(fill no)
		(layer "In4.Cu")
	)
	(gr_circle
		(center 112.394746 -68.881244)
		(end 113.283746 -68.881244)
		(stroke
			(width 0.2)
			(type default)
		)
		(fill no)
		(layer "In4.Cu")
	)
	(gr_circle
		(center 142.850108 -77.71765)
		(end 143.739108 -77.71765)
		(stroke
			(width 0.2)
			(type default)
		)
		(fill no)
		(layer "In4.Cu")
	)
	(gr_circle
		(center 144.47012 -70.409816)
		(end 146.66722 -70.409816)
		(stroke
			(width 0.2)
			(type default)
		)
		(fill no)
		(layer "In4.Cu")
	)
	(gr_circle
		(center 148.28012 -70.409816)
		(end 150.47722 -70.409816)
		(stroke
			(width 0.2)
			(type default)
		)
		(fill no)
		(layer "In4.Cu")
	)
	(gr_line
		(start 149.098 -83.312)
		(end 157.099 -91.313)
		(stroke
			(width 1.016)
			(type default)
		)
		(layer "In4.Cu")
	)
	(gr_line
		(start 149.225 -22.733)
		(end 148.130006 -23.827994)
		(stroke
			(width 1.016)
			(type default)
		)
		(layer "In4.Cu")
	)
	(gr_line
		(start 149.225 -22.733)
		(end 149.225 -23.827994)
		(stroke
			(width 1.016)
			(type default)
		)
		(layer "In4.Cu")
	)
	(gr_line
		(start 149.225 -22.733)
		(end 150.319994 -23.827994)
		(stroke
			(width 1.016)
			(type default)
		)
		(layer "In4.Cu")
	)
	(gr_line
		(start 149.225 -1.634744)
		(end 148.130006 -0.53975)
		(stroke
			(width 1.016)
			(type default)
		)
		(layer "In4.Cu")
	)
	(gr_line
		(start 149.225 -1.634744)
		(end 150.319994 -0.53975)
		(stroke
			(width 1.016)
			(type default)
		)
		(layer "In4.Cu")
	)
	(gr_line
		(start 149.225 0)
		(end 149.225 -22.733)
		(stroke
			(width 1.016)
			(type default)
		)
		(layer "In4.Cu")
	)
	(gr_line
		(start 157.099 -91.313)
		(end 175.895 -91.313)
		(stroke
			(width 1.016)
			(type default)
		)
		(layer "In4.Cu")
	)
	(gr_line
		(start 161.925 -23.827994)
		(end 57.531 -23.827994)
		(stroke
			(width 1.016)
			(type default)
		)
		(layer "In4.Cu")
	)
	(gr_line
		(start 161.925 0)
		(end 4.99999 0)
		(stroke
			(width 2.032)
			(type default)
		)
		(layer "In4.Cu")
	)
	(gr_circle
		(center 162.1028 -11.811)
		(end 162.9918 -11.811)
		(stroke
			(width 0.2)
			(type default)
		)
		(fill no)
		(layer "In4.Cu")
	)
	(gr_circle
		(center 162.1028 -11.176)
		(end 162.9918 -11.176)
		(stroke
			(width 0.2)
			(type default)
		)
		(fill no)
		(layer "In4.Cu")
	)
	(gr_circle
		(center 162.7886 -10.7442)
		(end 163.6776 -10.7442)
		(stroke
			(width 0.2)
			(type default)
		)
		(fill no)
		(layer "In4.Cu")
	)
	(gr_circle
		(center 162.8394 -12.2174)
		(end 163.7284 -12.2174)
		(stroke
			(width 0.2)
			(type default)
		)
		(fill no)
		(layer "In4.Cu")
	)
	(gr_line
		(start 163.019994 -23.827994)
		(end 161.925 -23.827994)
		(stroke
			(width 1.016)
			(type default)
		)
		(layer "In4.Cu")
	)
	(gr_line
		(start 163.019994 -23.827994)
		(end 191.142366 -23.827994)
		(stroke
			(width 1.016)
			(type default)
		)
		(layer "In4.Cu")
	)
	(gr_line
		(start 175.895 -91.313)
		(end 219.583 -91.313)
		(stroke
			(width 1.016)
			(type default)
		)
		(layer "In4.Cu")
	)
	(gr_circle
		(center 182.850282 -77.71765)
		(end 183.739282 -77.71765)
		(stroke
			(width 0.2)
			(type default)
		)
		(fill no)
		(layer "In4.Cu")
	)
	(gr_circle
		(center 184.470294 -70.409816)
		(end 186.667394 -70.409816)
		(stroke
			(width 0.2)
			(type default)
		)
		(fill no)
		(layer "In4.Cu")
	)
	(gr_line
		(start 184.785 -146.99996)
		(end 39.497 -146.99996)
		(stroke
			(width 2.032)
			(type default)
		)
		(layer "In4.Cu")
	)
	(gr_circle
		(center 188.280294 -70.409816)
		(end 190.477394 -70.409816)
		(stroke
			(width 0.2)
			(type default)
		)
		(fill no)
		(layer "In4.Cu")
	)
	(gr_line
		(start 191.142366 0)
		(end 161.925 0)
		(stroke
			(width 2.032)
			(type default)
		)
		(layer "In4.Cu")
	)
	(gr_line
		(start 191.142366 0)
		(end 286.004 0)
		(stroke
			(width 2.032)
			(type default)
		)
		(layer "In4.Cu")
	)
	(gr_line
		(start 202.389994 -23.827994)
		(end 191.142366 -23.827994)
		(stroke
			(width 1.016)
			(type default)
		)
		(layer "In4.Cu")
	)
	(gr_line
		(start 204.216 -45.226732)
		(end 204.216 -25.654)
		(stroke
			(width 1.016)
			(type default)
		)
		(layer "In4.Cu")
	)
	(gr_line
		(start 204.216 -25.654)
		(end 202.389994 -23.827994)
		(stroke
			(width 1.016)
			(type default)
		)
		(layer "In4.Cu")
	)
	(gr_line
		(start 205.121002 -46.131734)
		(end 204.216 -45.226732)
		(stroke
			(width 1.016)
			(type default)
		)
		(layer "In4.Cu")
	)
	(gr_line
		(start 212.57641 -66.376296)
		(end 214.150448 -64.802258)
		(stroke
			(width 1.016)
			(type default)
		)
		(layer "In4.Cu")
	)
	(gr_line
		(start 212.598508 -46.131734)
		(end 205.121002 -46.131734)
		(stroke
			(width 1.016)
			(type default)
		)
		(layer "In4.Cu")
	)
	(gr_line
		(start 214.150448 -64.802258)
		(end 214.150448 -47.683674)
		(stroke
			(width 1.016)
			(type default)
		)
		(layer "In4.Cu")
	)
	(gr_line
		(start 214.150448 -47.683674)
		(end 212.598508 -46.131734)
		(stroke
			(width 1.016)
			(type default)
		)
		(layer "In4.Cu")
	)
	(gr_line
		(start 215.0364 -38.481)
		(end 215.9254 -39.37)
		(stroke
			(width 1.016)
			(type default)
		)
		(layer "In4.Cu")
	)
	(gr_line
		(start 215.0364 -22.86)
		(end 215.0364 -38.481)
		(stroke
			(width 1.016)
			(type default)
		)
		(layer "In4.Cu")
	)
	(gr_line
		(start 215.9254 -39.37)
		(end 239.5474 -39.37)
		(stroke
			(width 1.016)
			(type default)
		)
		(layer "In4.Cu")
	)
	(gr_line
		(start 216.1794 -21.717)
		(end 215.0364 -22.86)
		(stroke
			(width 1.016)
			(type default)
		)
		(layer "In4.Cu")
	)
	(gr_line
		(start 219.583 -91.313)
		(end 219.964 -90.932)
		(stroke
			(width 1.016)
			(type default)
		)
		(layer "In4.Cu")
	)
	(gr_line
		(start 219.964 -90.932)
		(end 219.964 -72.730614)
		(stroke
			(width 1.016)
			(type default)
		)
		(layer "In4.Cu")
	)
	(gr_line
		(start 219.964 -72.730614)
		(end 234.401614 -58.293)
		(stroke
			(width 1.016)
			(type default)
		)
		(layer "In4.Cu")
	)
	(gr_line
		(start 221.413324 -147.066254)
		(end 223.256602 -145.222976)
		(stroke
			(width 1.016)
			(type default)
		)
		(layer "In4.Cu")
	)
	(gr_line
		(start 222.159322 -118.917974)
		(end 223.256602 -120.015254)
		(stroke
			(width 1.016)
			(type default)
		)
		(layer "In4.Cu")
	)
	(gr_line
		(start 223.256602 -120.015254)
		(end 223.256602 -147.000214)
		(stroke
			(width 1.016)
			(type default)
		)
		(layer "In4.Cu")
	)
	(gr_line
		(start 225.09988 -147.066254)
		(end 223.256602 -145.222976)
		(stroke
			(width 1.016)
			(type default)
		)
		(layer "In4.Cu")
	)
	(gr_line
		(start 234.401614 -58.293)
		(end 251.82195 -58.293)
		(stroke
			(width 1.016)
			(type default)
		)
		(layer "In4.Cu")
	)
	(gr_line
		(start 237.109 -146.558)
		(end 236.601 -147.066)
		(stroke
			(width 1.016)
			(type default)
		)
		(layer "In4.Cu")
	)
	(gr_line
		(start 239.5474 -39.37)
		(end 246.9134 -32.004)
		(stroke
			(width 1.016)
			(type default)
		)
		(layer "In4.Cu")
	)
	(gr_line
		(start 246.9134 -32.004)
		(end 269.0114 -32.004)
		(stroke
			(width 1.016)
			(type default)
		)
		(layer "In4.Cu")
	)
	(gr_line
		(start 251.82195 -58.293)
		(end 258.55295 -51.562)
		(stroke
			(width 1.016)
			(type default)
		)
		(layer "In4.Cu")
	)
	(gr_circle
		(center 258.219956 -50.232818)
		(end 259.108956 -50.232818)
		(stroke
			(width 0.2)
			(type default)
		)
		(fill no)
		(layer "In4.Cu")
	)
	(gr_circle
		(center 258.219956 -48.327818)
		(end 259.108956 -48.327818)
		(stroke
			(width 0.2)
			(type default)
		)
		(fill no)
		(layer "In4.Cu")
	)
	(gr_circle
		(center 258.219956 -47.565818)
		(end 259.108956 -47.565818)
		(stroke
			(width 0.2)
			(type default)
		)
		(fill no)
		(layer "In4.Cu")
	)
	(gr_circle
		(center 258.530598 -39.18712)
		(end 259.419598 -39.18712)
		(stroke
			(width 0.2)
			(type default)
		)
		(fill no)
		(layer "In4.Cu")
	)
	(gr_circle
		(center 258.548886 -38.461696)
		(end 259.437886 -38.461696)
		(stroke
			(width 0.2)
			(type default)
		)
		(fill no)
		(layer "In4.Cu")
	)
	(gr_line
		(start 258.55295 -51.562)
		(end 270.637 -51.562)
		(stroke
			(width 1.016)
			(type default)
		)
		(layer "In4.Cu")
	)
	(gr_circle
		(center 258.83362 -40.72382)
		(end 259.72262 -40.72382)
		(stroke
			(width 0.2)
			(type default)
		)
		(fill no)
		(layer "In4.Cu")
	)
	(gr_circle
		(center 258.83616 -39.95674)
		(end 259.72516 -39.95674)
		(stroke
			(width 0.2)
			(type default)
		)
		(fill no)
		(layer "In4.Cu")
	)
	(gr_circle
		(center 259.0038 -42.3164)
		(end 259.8928 -42.3164)
		(stroke
			(width 0.2)
			(type default)
		)
		(fill no)
		(layer "In4.Cu")
	)
	(gr_circle
		(center 259.588 -43.4848)
		(end 260.477 -43.4848)
		(stroke
			(width 0.2)
			(type default)
		)
		(fill no)
		(layer "In4.Cu")
	)
	(gr_circle
		(center 259.630672 -41.092882)
		(end 260.519672 -41.092882)
		(stroke
			(width 0.2)
			(type default)
		)
		(fill no)
		(layer "In4.Cu")
	)
	(gr_circle
		(center 259.630672 -39.592758)
		(end 260.519672 -39.592758)
		(stroke
			(width 0.2)
			(type default)
		)
		(fill no)
		(layer "In4.Cu")
	)
	(gr_circle
		(center 260.182106 -37.2364)
		(end 261.071106 -37.2364)
		(stroke
			(width 0.2)
			(type default)
		)
		(fill no)
		(layer "In4.Cu")
	)
	(gr_line
		(start 269.0114 -32.004)
		(end 270.4084 -33.401)
		(stroke
			(width 1.016)
			(type default)
		)
		(layer "In4.Cu")
	)
	(gr_line
		(start 270.4084 -33.401)
		(end 282.6004 -33.401)
		(stroke
			(width 1.016)
			(type default)
		)
		(layer "In4.Cu")
	)
	(gr_line
		(start 270.637 -51.562)
		(end 271.78 -50.419)
		(stroke
			(width 1.016)
			(type default)
		)
		(layer "In4.Cu")
	)
	(gr_line
		(start 271.78 -50.419)
		(end 271.78 -43.18)
		(stroke
			(width 1.016)
			(type default)
		)
		(layer "In4.Cu")
	)
	(gr_line
		(start 271.78 -43.18)
		(end 274.066 -40.894)
		(stroke
			(width 1.016)
			(type default)
		)
		(layer "In4.Cu")
	)
	(gr_line
		(start 271.907 -21.717)
		(end 216.1794 -21.717)
		(stroke
			(width 1.016)
			(type default)
		)
		(layer "In4.Cu")
	)
	(gr_circle
		(center 272.5928 -23.0886)
		(end 273.4818 -23.0886)
		(stroke
			(width 0.2)
			(type default)
		)
		(fill no)
		(layer "In4.Cu")
	)
	(gr_line
		(start 273.304 -20.32)
		(end 271.907 -21.717)
		(stroke
			(width 1.016)
			(type default)
		)
		(layer "In4.Cu")
	)
	(gr_line
		(start 273.304 -1.742186)
		(end 273.304 -1.524)
		(stroke
			(width 1.016)
			(type default)
		)
		(layer "In4.Cu")
	)
	(gr_line
		(start 273.304 -1.524)
		(end 271.399 0.381)
		(stroke
			(width 1.016)
			(type default)
		)
		(layer "In4.Cu")
	)
	(gr_line
		(start 273.304 -1.524)
		(end 275.209 0.381)
		(stroke
			(width 1.016)
			(type default)
		)
		(layer "In4.Cu")
	)
	(gr_line
		(start 273.304 0.381)
		(end 273.304 -20.32)
		(stroke
			(width 1.016)
			(type default)
		)
		(layer "In4.Cu")
	)
	(gr_circle
		(center 273.6088 -23.0886)
		(end 274.4978 -23.0886)
		(stroke
			(width 0.2)
			(type default)
		)
		(fill no)
		(layer "In4.Cu")
	)
	(gr_line
		(start 274.066 -40.894)
		(end 282.321 -40.894)
		(stroke
			(width 1.016)
			(type default)
		)
		(layer "In4.Cu")
	)
	(gr_circle
		(center 275.41855 -33.070038)
		(end 276.30755 -33.070038)
		(stroke
			(width 0.2)
			(type default)
		)
		(fill no)
		(layer "In4.Cu")
	)
	(gr_circle
		(center 277.368 -20.955)
		(end 278.257 -20.955)
		(stroke
			(width 0.2)
			(type default)
		)
		(fill no)
		(layer "In4.Cu")
	)
	(gr_line
		(start 278.19985 -146.99996)
		(end 184.785 -146.99996)
		(stroke
			(width 2.032)
			(type default)
		)
		(layer "In4.Cu")
	)
	(gr_line
		(start 278.19985 -146.99996)
		(end 323.000116 -146.99996)
		(stroke
			(width 2.032)
			(type default)
		)
		(layer "In4.Cu")
	)
	(gr_line
		(start 278.19985 -145.508218)
		(end 276.878542 -146.829526)
		(stroke
			(width 1.016)
			(type default)
		)
		(layer "In4.Cu")
	)
	(gr_line
		(start 278.19985 -145.508218)
		(end 279.521158 -146.829526)
		(stroke
			(width 1.016)
			(type default)
		)
		(layer "In4.Cu")
	)
	(gr_line
		(start 278.19985 -134.326122)
		(end 279.565862 -132.96011)
		(stroke
			(width 1.016)
			(type default)
		)
		(layer "In4.Cu")
	)
	(gr_line
		(start 278.19985 -132.96011)
		(end 278.19985 -146.99996)
		(stroke
			(width 1.016)
			(type default)
		)
		(layer "In4.Cu")
	)
	(gr_line
		(start 278.19985 -132.96011)
		(end 278.19985 -57.37225)
		(stroke
			(width 1.016)
			(type default)
		)
		(layer "In4.Cu")
	)
	(gr_line
		(start 278.19985 -131.594098)
		(end 279.565862 -132.96011)
		(stroke
			(width 1.016)
			(type default)
		)
		(layer "In4.Cu")
	)
	(gr_line
		(start 278.19985 -126.19228)
		(end 278.19985 -131.594098)
		(stroke
			(width 1.016)
			(type default)
		)
		(layer "In4.Cu")
	)
	(gr_line
		(start 278.19985 -97.85985)
		(end 279.6921 -96.3676)
		(stroke
			(width 1.016)
			(type default)
		)
		(layer "In4.Cu")
	)
	(gr_line
		(start 278.19985 -94.87535)
		(end 279.6921 -96.3676)
		(stroke
			(width 1.016)
			(type default)
		)
		(layer "In4.Cu")
	)
	(gr_line
		(start 278.19985 -61.16574)
		(end 279.648666 -59.716924)
		(stroke
			(width 1.016)
			(type default)
		)
		(layer "In4.Cu")
	)
	(gr_line
		(start 278.19985 -58.268108)
		(end 279.648666 -59.716924)
		(stroke
			(width 1.016)
			(type default)
		)
		(layer "In4.Cu")
	)
	(gr_line
		(start 278.19985 -57.90565)
		(end 278.19985 -53.90515)
		(stroke
			(width 1.016)
			(type default)
		)
		(layer "In4.Cu")
	)
	(gr_line
		(start 278.19985 -53.90515)
		(end 283.1338 -48.9712)
		(stroke
			(width 1.016)
			(type default)
		)
		(layer "In4.Cu")
	)
	(gr_line
		(start 278.768302 -59.716924)
		(end 280.81732 -59.716924)
		(stroke
			(width 1.016)
			(type default)
		)
		(layer "In4.Cu")
	)
	(gr_line
		(start 282.321 -40.894)
		(end 283.845 -39.37)
		(stroke
			(width 1.016)
			(type default)
		)
		(layer "In4.Cu")
	)
	(gr_line
		(start 282.6004 -33.401)
		(end 283.7434 -32.258)
		(stroke
			(width 1.016)
			(type default)
		)
		(layer "In4.Cu")
	)
	(gr_line
		(start 282.6004 -33.401)
		(end 283.7688 -33.401)
		(stroke
			(width 1.016)
			(type default)
		)
		(layer "In4.Cu")
	)
	(gr_line
		(start 283.1338 -48.9712)
		(end 295.588944 -48.9712)
		(stroke
			(width 1.016)
			(type default)
		)
		(layer "In4.Cu")
	)
	(gr_line
		(start 283.7434 -34.544)
		(end 282.6004 -33.401)
		(stroke
			(width 1.016)
			(type default)
		)
		(layer "In4.Cu")
	)
	(gr_line
		(start 283.845 -39.37)
		(end 283.845 -30.099)
		(stroke
			(width 1.016)
			(type default)
		)
		(layer "In4.Cu")
	)
	(gr_line
		(start 283.845 -30.099)
		(end 284.353 -29.591)
		(stroke
			(width 1.016)
			(type default)
		)
		(layer "In4.Cu")
	)
	(gr_line
		(start 284.353 -29.591)
		(end 289.296856 -29.591)
		(stroke
			(width 1.016)
			(type default)
		)
		(layer "In4.Cu")
	)
	(gr_line
		(start 285.623 0.508)
		(end 286.004 0.127)
		(stroke
			(width 1.016)
			(type default)
		)
		(layer "In4.Cu")
	)
	(gr_line
		(start 286.004 0.127)
		(end 286.004 0)
		(stroke
			(width 1.016)
			(type default)
		)
		(layer "In4.Cu")
	)
	(gr_line
		(start 289.296856 -29.591)
		(end 289.687 -29.981144)
		(stroke
			(width 1.016)
			(type default)
		)
		(layer "In4.Cu")
	)
	(gr_line
		(start 289.687 -40.132)
		(end 290.449 -40.894)
		(stroke
			(width 1.016)
			(type default)
		)
		(layer "In4.Cu")
	)
	(gr_line
		(start 289.687 -29.981144)
		(end 289.687 -40.132)
		(stroke
			(width 1.016)
			(type default)
		)
		(layer "In4.Cu")
	)
	(gr_line
		(start 289.848036 0)
		(end 286.004 0)
		(stroke
			(width 2.032)
			(type default)
		)
		(layer "In4.Cu")
	)
	(gr_line
		(start 290.449 -40.894)
		(end 294.767 -40.894)
		(stroke
			(width 1.016)
			(type default)
		)
		(layer "In4.Cu")
	)
	(gr_line
		(start 291.200078 -59.716924)
		(end 279.648666 -59.716924)
		(stroke
			(width 1.016)
			(type default)
		)
		(layer "In4.Cu")
	)
	(gr_circle
		(center 294.1828 -34.9758)
		(end 295.0718 -34.9758)
		(stroke
			(width 0.2)
			(type default)
		)
		(fill no)
		(layer "In4.Cu")
	)
	(gr_line
		(start 294.767 -40.894)
		(end 296.0878 -42.2148)
		(stroke
			(width 1.016)
			(type default)
		)
		(layer "In4.Cu")
	)
	(gr_line
		(start 295.588944 -48.9712)
		(end 296.0878 -48.472344)
		(stroke
			(width 1.016)
			(type default)
		)
		(layer "In4.Cu")
	)
	(gr_line
		(start 296.0878 -42.2148)
		(end 296.0878 -48.472344)
		(stroke
			(width 1.016)
			(type default)
		)
		(layer "In4.Cu")
	)
	(gr_circle
		(center 297.561 -54.356)
		(end 298.45 -54.356)
		(stroke
			(width 0.2)
			(type default)
		)
		(fill no)
		(layer "In4.Cu")
	)
	(gr_circle
		(center 297.561 -53.594)
		(end 298.45 -53.594)
		(stroke
			(width 0.2)
			(type default)
		)
		(fill no)
		(layer "In4.Cu")
	)
	(gr_circle
		(center 297.561 -52.832)
		(end 298.45 -52.832)
		(stroke
			(width 0.2)
			(type default)
		)
		(fill no)
		(layer "In4.Cu")
	)
	(gr_circle
		(center 297.561 -52.07)
		(end 298.45 -52.07)
		(stroke
			(width 0.2)
			(type default)
		)
		(fill no)
		(layer "In4.Cu")
	)
	(gr_line
		(start 298.271184 -96.3676)
		(end 278.19985 -96.3676)
		(stroke
			(width 1.016)
			(type default)
		)
		(layer "In4.Cu")
	)
	(gr_circle
		(center 298.323 -54.356)
		(end 299.212 -54.356)
		(stroke
			(width 0.2)
			(type default)
		)
		(fill no)
		(layer "In4.Cu")
	)
	(gr_circle
		(center 298.323 -53.594)
		(end 299.212 -53.594)
		(stroke
			(width 0.2)
			(type default)
		)
		(fill no)
		(layer "In4.Cu")
	)
	(gr_circle
		(center 298.323 -52.832)
		(end 299.212 -52.832)
		(stroke
			(width 0.2)
			(type default)
		)
		(fill no)
		(layer "In4.Cu")
	)
	(gr_circle
		(center 298.323 -52.07)
		(end 299.212 -52.07)
		(stroke
			(width 0.2)
			(type default)
		)
		(fill no)
		(layer "In4.Cu")
	)
	(gr_line
		(start 298.525184 -59.716924)
		(end 291.200078 -59.716924)
		(stroke
			(width 1.016)
			(type default)
		)
		(layer "In4.Cu")
	)
	(gr_line
		(start 298.533566 -132.96011)
		(end 278.19985 -132.96011)
		(stroke
			(width 1.016)
			(type default)
		)
		(layer "In4.Cu")
	)
	(gr_line
		(start 298.533566 -132.96011)
		(end 299.763434 -131.730242)
		(stroke
			(width 1.016)
			(type default)
		)
		(layer "In4.Cu")
	)
	(gr_line
		(start 299.763434 -131.730242)
		(end 299.763434 -126.359666)
		(stroke
			(width 1.016)
			(type default)
		)
		(layer "In4.Cu")
	)
	(gr_line
		(start 299.763434 -127.672338)
		(end 299.763434 -126.219966)
		(stroke
			(width 1.016)
			(type default)
		)
		(layer "In4.Cu")
	)
	(gr_line
		(start 299.763434 -126.359666)
		(end 299.763434 -60.955174)
		(stroke
			(width 1.016)
			(type default)
		)
		(layer "In4.Cu")
	)
	(gr_line
		(start 299.763434 -126.219966)
		(end 303.6824 -122.301)
		(stroke
			(width 1.016)
			(type default)
		)
		(layer "In4.Cu")
	)
	(gr_line
		(start 299.763434 -125.046994)
		(end 299.763434 -126.359666)
		(stroke
			(width 1.016)
			(type default)
		)
		(layer "In4.Cu")
	)
	(gr_line
		(start 299.763434 -125.046994)
		(end 299.763434 -122.1994)
		(stroke
			(width 1.016)
			(type default)
		)
		(layer "In4.Cu")
	)
	(gr_line
		(start 299.763434 -97.85985)
		(end 298.271184 -96.3676)
		(stroke
			(width 1.016)
			(type default)
		)
		(layer "In4.Cu")
	)
	(gr_line
		(start 299.763434 -96.3676)
		(end 298.271184 -96.3676)
		(stroke
			(width 1.016)
			(type default)
		)
		(layer "In4.Cu")
	)
	(gr_line
		(start 299.763434 -94.87535)
		(end 298.271184 -96.3676)
		(stroke
			(width 1.016)
			(type default)
		)
		(layer "In4.Cu")
	)
	(gr_line
		(start 299.763434 -60.955174)
		(end 298.525184 -59.716924)
		(stroke
			(width 1.016)
			(type default)
		)
		(layer "In4.Cu")
	)
	(gr_line
		(start 300.498764 -73.6092)
		(end 299.906436 -74.201528)
		(stroke
			(width 1.016)
			(type default)
		)
		(layer "In4.Cu")
	)
	(gr_line
		(start 300.498764 -73.6092)
		(end 299.906436 -73.016872)
		(stroke
			(width 1.016)
			(type default)
		)
		(layer "In4.Cu")
	)
	(gr_line
		(start 301.084742 -122.1994)
		(end 299.763434 -123.520708)
		(stroke
			(width 1.016)
			(type default)
		)
		(layer "In4.Cu")
	)
	(gr_line
		(start 301.084742 -122.1994)
		(end 299.763434 -120.878092)
		(stroke
			(width 1.016)
			(type default)
		)
		(layer "In4.Cu")
	)
	(gr_line
		(start 301.447708 -122.503692)
		(end 300.1264 -123.825)
		(stroke
			(width 1.016)
			(type default)
		)
		(layer "In4.Cu")
	)
	(gr_line
		(start 302.509428 -122.301)
		(end 299.763434 -125.046994)
		(stroke
			(width 1.016)
			(type default)
		)
		(layer "In4.Cu")
	)
	(gr_line
		(start 303.6824 -122.301)
		(end 302.509428 -122.301)
		(stroke
			(width 1.016)
			(type default)
		)
		(layer "In4.Cu")
	)
	(gr_line
		(start 306.451 -73.6092)
		(end 300.498764 -73.6092)
		(stroke
			(width 1.016)
			(type default)
		)
		(layer "In4.Cu")
	)
	(gr_line
		(start 306.451 -73.6092)
		(end 308.6608 -75.819)
		(stroke
			(width 1.016)
			(type default)
		)
		(layer "In4.Cu")
	)
	(gr_line
		(start 308.6608 -75.819)
		(end 306.451 -73.6092)
		(stroke
			(width 1.016)
			(type default)
		)
		(layer "In4.Cu")
	)
	(gr_line
		(start 308.6608 -75.819)
		(end 319.8876 -75.819)
		(stroke
			(width 1.016)
			(type default)
		)
		(layer "In4.Cu")
	)
	(gr_circle
		(center 311.410096 -72.879966)
		(end 312.809128 -72.879966)
		(stroke
			(width 0.2)
			(type default)
		)
		(fill no)
		(layer "In4.Cu")
	)
	(gr_line
		(start 319.6336 -122.1994)
		(end 299.763434 -122.1994)
		(stroke
			(width 1.016)
			(type default)
		)
		(layer "In4.Cu")
	)
	(gr_line
		(start 319.8876 -75.819)
		(end 320.929 -76.8604)
		(stroke
			(width 1.016)
			(type default)
		)
		(layer "In4.Cu")
	)
	(gr_line
		(start 320.929 -120.904)
		(end 319.6336 -122.1994)
		(stroke
			(width 1.016)
			(type default)
		)
		(layer "In4.Cu")
	)
	(gr_line
		(start 320.929 -76.8604)
		(end 320.929 -120.904)
		(stroke
			(width 1.016)
			(type default)
		)
		(layer "In4.Cu")
	)
	(gr_arc
		(start 323.000116 -146.99996)
		(mid 326.535622 -145.535489)
		(end 328.000106 -141.99997)
		(stroke
			(width 2.032)
			(type default)
		)
		(layer "In4.Cu")
	)
	(gr_line
		(start 323.000116 0)
		(end 287.909 0)
		(stroke
			(width 2.032)
			(type default)
		)
		(layer "In4.Cu")
	)
	(gr_line
		(start 328.000106 -141.99997)
		(end 328.000106 -4.99999)
		(stroke
			(width 2.032)
			(type default)
		)
		(layer "In4.Cu")
	)
	(gr_arc
		(start 328.000106 -4.99999)
		(mid 326.53564 -1.464464)
		(end 323.000116 0)
		(stroke
			(width 2.032)
			(type default)
		)
		(layer "In4.Cu")
	)
	(gr_arc
		(start 0 -141.99997)
		(mid 1.464463 -145.535497)
		(end 4.99999 -146.99996)
		(stroke
			(width 2.032)
			(type default)
		)
		(layer "In5.Cu")
	)
	(gr_line
		(start 0 -131.729988)
		(end 0 -141.99997)
		(stroke
			(width 2.032)
			(type default)
		)
		(layer "In5.Cu")
	)
	(gr_arc
		(start 0 -113.229898)
		(mid 0.878678 -115.351214)
		(end 2.999994 -116.229892)
		(stroke
			(width 2.032)
			(type default)
		)
		(layer "In5.Cu")
	)
	(gr_line
		(start 0 -34.569908)
		(end 0 -113.229898)
		(stroke
			(width 2.032)
			(type default)
		)
		(layer "In5.Cu")
	)
	(gr_arc
		(start 0 -16.070072)
		(mid 0.878678 -18.191388)
		(end 2.999994 -19.070066)
		(stroke
			(width 2.032)
			(type default)
		)
		(layer "In5.Cu")
	)
	(gr_line
		(start 0 -4.99999)
		(end 0 -16.070072)
		(stroke
			(width 2.032)
			(type default)
		)
		(layer "In5.Cu")
	)
	(gr_poly
		(pts
			(arc
				(start 298.302172 -132.45211)
				(mid 298.321695 -132.448209)
				(end 298.33824 -132.437124)
			)
			(arc
				(start 299.240448 -131.534916)
				(mid 299.251559 -131.518382)
				(end 299.255434 -131.498848)
			)
			(xy 299.255434 -122.167396) (xy 299.252894 -122.156474)
			(arc
				(start 299.250354 -122.15114)
				(mid 299.221372 -122.069537)
				(end 299.211492 -121.9835)
			)
			(arc
				(start 299.211492 -121.9835)
				(mid 299.221323 -121.897451)
				(end 299.250354 -121.81586)
			)
			(xy 299.252894 -121.810526) (xy 299.255434 -121.799604) (xy 299.255434 -121.278396) (xy 299.252894 -121.267474)
			(arc
				(start 299.250354 -121.26214)
				(mid 299.221372 -121.180537)
				(end 299.211492 -121.0945)
			)
			(arc
				(start 299.211492 -121.0945)
				(mid 299.221323 -121.008451)
				(end 299.250354 -120.92686)
			)
			(xy 299.252894 -120.921526) (xy 299.255434 -120.910604) (xy 299.255434 -120.389396) (xy 299.252894 -120.378474)
			(arc
				(start 299.250354 -120.37314)
				(mid 299.221372 -120.291537)
				(end 299.211492 -120.2055)
			)
			(arc
				(start 299.211492 -120.2055)
				(mid 299.221323 -120.119451)
				(end 299.250354 -120.03786)
			)
			(xy 299.252894 -120.032526) (xy 299.255434 -120.021604) (xy 299.255434 -119.500396) (xy 299.252894 -119.489474)
			(arc
				(start 299.250354 -119.48414)
				(mid 299.221372 -119.402537)
				(end 299.211492 -119.3165)
			)
			(arc
				(start 299.211492 -119.3165)
				(mid 299.221323 -119.230451)
				(end 299.250354 -119.14886)
			)
			(xy 299.252894 -119.143526) (xy 299.255434 -119.132604)
			(arc
				(start 299.255434 -98.091244)
				(mid 299.251533 -98.071721)
				(end 299.240448 -98.055176)
			)
			(arc
				(start 298.075858 -96.890586)
				(mid 298.059324 -96.879475)
				(end 298.03979 -96.8756)
			)
			(arc
				(start 279.923494 -96.8756)
				(mid 279.903971 -96.879501)
				(end 279.887426 -96.890586)
			)
			(arc
				(start 278.722836 -98.055176)
				(mid 278.711725 -98.07171)
				(end 278.70785 -98.091244)
			)
			(arc
				(start 278.70785 -131.362704)
				(mid 278.711751 -131.382227)
				(end 278.722836 -131.398772)
			)
			(arc
				(start 279.761188 -132.437124)
				(mid 279.777722 -132.448235)
				(end 279.797256 -132.45211)
			)
		)
		(stroke
			(width 0)
			(type solid)
		)
		(fill yes)
		(layer "In5.Cu")
		(net "P52V_HS1_DRAIN_1")
	)
	(gr_poly
		(pts
			(arc
				(start 298.03979 -95.8596)
				(mid 298.059313 -95.855699)
				(end 298.075858 -95.844614)
			)
			(arc
				(start 299.240448 -94.680024)
				(mid 299.251559 -94.66349)
				(end 299.255434 -94.643956)
			)
			(arc
				(start 299.255434 -86.018878)
				(mid 299.25339 -86.004863)
				(end 299.24756 -85.991954)
			)
			(arc
				(start 299.24756 -85.991954)
				(mid 299.203848 -85.894376)
				(end 299.188886 -85.7885)
			)
			(arc
				(start 299.188886 -85.7885)
				(mid 299.203802 -85.682611)
				(end 299.24756 -85.585046)
			)
			(arc
				(start 299.24756 -85.585046)
				(mid 299.253395 -85.572139)
				(end 299.255434 -85.558122)
			)
			(arc
				(start 299.255434 -85.129878)
				(mid 299.25339 -85.115863)
				(end 299.24756 -85.102954)
			)
			(arc
				(start 299.24756 -85.102954)
				(mid 299.203848 -85.005376)
				(end 299.188886 -84.8995)
			)
			(arc
				(start 299.188886 -84.8995)
				(mid 299.203802 -84.793611)
				(end 299.24756 -84.696046)
			)
			(arc
				(start 299.24756 -84.696046)
				(mid 299.253395 -84.683139)
				(end 299.255434 -84.669122)
			)
			(arc
				(start 299.255434 -84.240878)
				(mid 299.25339 -84.226863)
				(end 299.24756 -84.213954)
			)
			(arc
				(start 299.24756 -84.213954)
				(mid 299.203848 -84.116376)
				(end 299.188886 -84.0105)
			)
			(arc
				(start 299.188886 -84.0105)
				(mid 299.203802 -83.904611)
				(end 299.24756 -83.807046)
			)
			(arc
				(start 299.24756 -83.807046)
				(mid 299.253395 -83.794139)
				(end 299.255434 -83.780122)
			)
			(arc
				(start 299.255434 -83.351878)
				(mid 299.25339 -83.337863)
				(end 299.24756 -83.324954)
			)
			(arc
				(start 299.24756 -83.324954)
				(mid 299.203848 -83.227376)
				(end 299.188886 -83.1215)
			)
			(arc
				(start 299.188886 -83.1215)
				(mid 299.203802 -83.015611)
				(end 299.24756 -82.918046)
			)
			(arc
				(start 299.24756 -82.918046)
				(mid 299.253395 -82.905139)
				(end 299.255434 -82.891122)
			)
			(xy 299.255434 -78.790546)
			(arc
				(start 299.254672 -78.786482)
				(mid 299.251029 -78.755972)
				(end 299.249846 -78.725268)
			)
			(arc
				(start 299.249846 -78.725268)
				(mid 299.251022 -78.694563)
				(end 299.254672 -78.664054)
			)
			(xy 299.255434 -78.65999) (xy 299.255434 -77.774546)
			(arc
				(start 299.254672 -77.770482)
				(mid 299.251029 -77.739972)
				(end 299.249846 -77.709268)
			)
			(arc
				(start 299.249846 -77.709268)
				(mid 299.251022 -77.678563)
				(end 299.254672 -77.648054)
			)
			(xy 299.255434 -77.64399)
			(arc
				(start 299.255434 -61.186568)
				(mid 299.251533 -61.167045)
				(end 299.240448 -61.1505)
			)
			(arc
				(start 298.329858 -60.23991)
				(mid 298.313324 -60.228799)
				(end 298.29379 -60.224924)
			)
			(arc
				(start 279.88006 -60.224924)
				(mid 279.860537 -60.228825)
				(end 279.843992 -60.23991)
			)
			(arc
				(start 278.722836 -61.361066)
				(mid 278.711725 -61.3776)
				(end 278.70785 -61.397134)
			)
			(arc
				(start 278.70785 -94.643956)
				(mid 278.711751 -94.663479)
				(end 278.722836 -94.680024)
			)
			(arc
				(start 279.887426 -95.844614)
				(mid 279.90396 -95.855725)
				(end 279.923494 -95.8596)
			)
		)
		(stroke
			(width 0)
			(type solid)
		)
		(fill yes)
		(layer "In5.Cu")
		(net "P52V_HS1_DRAIN_2")
	)
	(gr_poly
		(pts
			(arc
				(start 275.104606 -93.472)
				(mid 275.124129 -93.468099)
				(end 275.140674 -93.457014)
			)
			(arc
				(start 275.419566 -93.178122)
				(mid 275.430677 -93.161588)
				(end 275.434552 -93.142054)
			)
			(arc
				(start 275.434552 -91.158314)
				(mid 275.429547 -91.136326)
				(end 275.415502 -91.11869)
			)
			(arc
				(start 275.415502 -91.11869)
				(mid 275.081521 -90.424)
				(end 275.415502 -89.72931)
			)
			(arc
				(start 275.415502 -89.72931)
				(mid 275.429524 -89.711663)
				(end 275.434552 -89.689686)
			)
			(arc
				(start 275.434552 -67.223894)
				(mid 275.430651 -67.204371)
				(end 275.419566 -67.187826)
			)
			(arc
				(start 275.277326 -67.045586)
				(mid 275.260792 -67.034475)
				(end 275.241258 -67.0306)
			)
			(arc
				(start 269.623794 -67.0306)
				(mid 269.604271 -67.034501)
				(end 269.587726 -67.045586)
			)
			(arc
				(start 269.204186 -67.429126)
				(mid 269.193075 -67.44566)
				(end 269.1892 -67.465194)
			)
			(arc
				(start 269.1892 -70.202806)
				(mid 269.193101 -70.222329)
				(end 269.204186 -70.238874)
			)
			(arc
				(start 269.714726 -70.749414)
				(mid 269.73126 -70.760525)
				(end 269.750794 -70.7644)
			)
			(arc
				(start 272.9484 -70.7644)
				(mid 273.142789 -70.803084)
				(end 273.307556 -70.913244)
			)
			(arc
				(start 274.044156 -71.649844)
				(mid 274.154314 -71.814612)
				(end 274.193 -72.009)
			)
			(arc
				(start 274.193 -78.486)
				(mid 274.154316 -78.680389)
				(end 274.044156 -78.845156)
			)
			(arc
				(start 273.358356 -79.530956)
				(mid 273.193588 -79.641114)
				(end 272.9992 -79.6798)
			)
			(arc
				(start 269.674594 -79.6798)
				(mid 269.655071 -79.683701)
				(end 269.638526 -79.694786)
			)
			(arc
				(start 269.204186 -80.129126)
				(mid 269.193075 -80.14566)
				(end 269.1892 -80.165194)
			)
			(arc
				(start 269.1892 -84.045806)
				(mid 269.193101 -84.065329)
				(end 269.204186 -84.081874)
			)
			(arc
				(start 269.562326 -84.440014)
				(mid 269.57886 -84.451125)
				(end 269.598394 -84.455)
			)
			(arc
				(start 272.923 -84.455)
				(mid 273.117389 -84.493684)
				(end 273.282156 -84.603844)
			)
			(arc
				(start 274.044156 -85.365844)
				(mid 274.154314 -85.530612)
				(end 274.193 -85.725)
			)
			(arc
				(start 274.193 -90.043)
				(mid 274.154316 -90.237389)
				(end 274.044156 -90.402156)
			)
			(arc
				(start 273.536156 -90.910156)
				(mid 273.371388 -91.020314)
				(end 273.177 -91.059)
			)
			(arc
				(start 269.725394 -91.059)
				(mid 269.705871 -91.062901)
				(end 269.689326 -91.073986)
			)
			(arc
				(start 269.204186 -91.559126)
				(mid 269.193075 -91.57566)
				(end 269.1892 -91.595194)
			)
			(arc
				(start 269.1892 -93.36278)
				(mid 269.193101 -93.382303)
				(end 269.204186 -93.398848)
			)
			(arc
				(start 269.262352 -93.457014)
				(mid 269.278886 -93.468125)
				(end 269.29842 -93.472)
			)
		)
		(stroke
			(width 0)
			(type solid)
		)
		(fill yes)
		(layer "In5.Cu")
		(net "P52V_HS1_GATE2_R")
	)
	(gr_poly
		(pts
			(arc
				(start 34.21888 -118.409974)
				(mid 34.238403 -118.406073)
				(end 34.254948 -118.394988)
			)
			(arc
				(start 34.988754 -117.661182)
				(mid 34.999865 -117.644648)
				(end 35.00374 -117.625114)
			)
			(arc
				(start 35.00374 -84.78266)
				(mid 35.042424 -84.588271)
				(end 35.152584 -84.423504)
			)
			(arc
				(start 36.623244 -82.952844)
				(mid 36.788012 -82.842686)
				(end 36.9824 -82.804)
			)
			(arc
				(start 40.214042 -82.804)
				(mid 40.240942 -82.796293)
				(end 40.259762 -82.775552)
			)
			(xy 40.306244 -82.680302) (xy 40.303196 -82.6516)
			(arc
				(start 40.294052 -82.639916)
				(mid 40.154351 -82.382065)
				(end 40.106092 -82.0928)
			)
			(arc
				(start 40.106092 -82.0928)
				(mid 40.9956 -81.203292)
				(end 41.885108 -82.0928)
			)
			(arc
				(start 41.885108 -82.0928)
				(mid 41.836848 -82.382065)
				(end 41.697148 -82.639916)
			)
			(xy 41.688004 -82.6516) (xy 41.684956 -82.680302)
			(arc
				(start 41.731438 -82.775552)
				(mid 41.75021 -82.796371)
				(end 41.777158 -82.804)
			)
			(arc
				(start 44.370244 -82.804)
				(mid 44.389767 -82.800099)
				(end 44.406312 -82.789014)
			)
			(arc
				(start 44.840398 -82.354928)
				(mid 44.851509 -82.338394)
				(end 44.855384 -82.31886)
			)
			(arc
				(start 44.855384 -82.07375)
				(mid 44.851483 -82.054227)
				(end 44.840398 -82.037682)
			)
			(arc
				(start 37.994844 -75.192128)
				(mid 37.884686 -75.02736)
				(end 37.846 -74.832972)
			)
			(arc
				(start 37.846 -68.684394)
				(mid 37.842099 -68.664871)
				(end 37.831014 -68.648326)
			)
			(arc
				(start 37.295074 -68.112386)
				(mid 37.27854 -68.101275)
				(end 37.259006 -68.0974)
			)
			(arc
				(start 9.349994 -68.0974)
				(mid 9.330471 -68.101301)
				(end 9.313926 -68.112386)
			)
			(arc
				(start 8.676386 -68.749926)
				(mid 8.665275 -68.76646)
				(end 8.6614 -68.785994)
			)
			(arc
				(start 8.6614 -76.959206)
				(mid 8.665301 -76.978729)
				(end 8.676386 -76.995274)
			)
			(arc
				(start 9.110726 -77.429614)
				(mid 9.12726 -77.440725)
				(end 9.146794 -77.4446)
			)
			(arc
				(start 14.9606 -77.4446)
				(mid 15.154989 -77.483284)
				(end 15.319756 -77.593444)
			)
			(arc
				(start 15.599156 -77.872844)
				(mid 15.709314 -78.037612)
				(end 15.748 -78.232)
			)
			(arc
				(start 15.748 -117.679216)
				(mid 15.751901 -117.698739)
				(end 15.762986 -117.715284)
			)
			(arc
				(start 16.44269 -118.394988)
				(mid 16.459224 -118.406099)
				(end 16.478758 -118.409974)
			)
		)
		(stroke
			(width 0)
			(type solid)
		)
		(fill yes)
		(layer "In5.Cu")
		(net "P52V_FAN")
	)
	(gr_poly
		(pts
			(arc
				(start 276.602444 -132.45211)
				(mid 276.621967 -132.448209)
				(end 276.638512 -132.437124)
			)
			(arc
				(start 277.676864 -131.398772)
				(mid 277.687975 -131.382238)
				(end 277.69185 -131.362704)
			)
			(arc
				(start 277.69185 -106.78033)
				(mid 277.684083 -106.753333)
				(end 277.663148 -106.73461)
			)
			(xy 277.56739 -106.688382) (xy 277.538434 -106.691684)
			(arc
				(start 277.527004 -106.700828)
				(mid 277.266243 -106.844954)
				(end 276.972522 -106.894884)
			)
			(arc
				(start 276.972522 -106.894884)
				(mid 276.343365 -106.634279)
				(end 276.08276 -106.005122)
			)
			(arc
				(start 276.08276 -106.005122)
				(mid 276.083765 -105.965074)
				(end 276.08657 -105.925112)
			)
			(xy 276.087332 -105.914444) (xy 276.080728 -105.894124)
			(arc
				(start 276.022816 -105.830878)
				(mid 276.005769 -105.818619)
				(end 275.985224 -105.814368)
			)
			(arc
				(start 269.357348 -105.814368)
				(mid 269.337825 -105.818269)
				(end 269.32128 -105.829354)
			)
			(xy 269.204186 -105.946448) (xy 269.19682 -105.95356) (xy 269.1892 -105.972356)
			(arc
				(start 269.1892 -107.286806)
				(mid 269.193101 -107.306329)
				(end 269.204186 -107.322874)
			)
			(arc
				(start 269.587726 -107.706414)
				(mid 269.60426 -107.717525)
				(end 269.623794 -107.7214)
			)
			(arc
				(start 272.6944 -107.7214)
				(mid 272.888789 -107.760084)
				(end 273.053556 -107.870244)
			)
			(arc
				(start 274.044156 -108.860844)
				(mid 274.154314 -109.025612)
				(end 274.193 -109.22)
			)
			(arc
				(start 274.193 -114.554)
				(mid 274.154316 -114.748389)
				(end 274.044156 -114.913156)
			)
			(arc
				(start 273.231356 -115.725956)
				(mid 273.066588 -115.836114)
				(end 272.8722 -115.8748)
			)
			(arc
				(start 269.547594 -115.8748)
				(mid 269.528071 -115.878701)
				(end 269.511526 -115.889786)
			)
			(xy 269.204186 -116.197126) (xy 269.19682 -116.204238) (xy 269.1892 -116.223034)
			(arc
				(start 269.1892 -119.732806)
				(mid 269.193101 -119.752329)
				(end 269.204186 -119.768874)
			)
			(arc
				(start 269.460726 -120.025414)
				(mid 269.47726 -120.036525)
				(end 269.496794 -120.0404)
			)
			(arc
				(start 272.9484 -120.0404)
				(mid 273.142789 -120.079084)
				(end 273.307556 -120.189244)
			)
			(arc
				(start 274.044156 -120.925844)
				(mid 274.154314 -121.090612)
				(end 274.193 -121.285)
			)
			(arc
				(start 274.193 -126.619)
				(mid 274.154316 -126.813389)
				(end 274.044156 -126.978156)
			)
			(arc
				(start 273.383756 -127.638556)
				(mid 273.218988 -127.748714)
				(end 273.0246 -127.7874)
			)
			(arc
				(start 269.649194 -127.7874)
				(mid 269.629671 -127.791301)
				(end 269.613126 -127.802386)
			)
			(xy 269.204186 -128.211326) (xy 269.19682 -128.218438) (xy 269.1892 -128.237234)
			(arc
				(start 269.1892 -131.924806)
				(mid 269.193101 -131.944329)
				(end 269.204186 -131.960874)
			)
			(arc
				(start 269.680436 -132.437124)
				(mid 269.69697 -132.448235)
				(end 269.716504 -132.45211)
			)
		)
		(stroke
			(width 0)
			(type solid)
		)
		(fill yes)
		(layer "In5.Cu")
		(net "P52V_HS1_GATE1_R")
	)
	(gr_poly
		(pts
			(xy 319.402206 -121.6914) (xy 319.412276 -121.690976) (xy 319.430879 -121.68326) (xy 319.438274 -121.676414)
			(xy 320.406014 -120.708674) (xy 320.412866 -120.701278) (xy 320.420604 -120.682679) (xy 320.421 -120.672606)
			(xy 320.421 -77.091794) (xy 320.420576 -77.081724) (xy 320.41286 -77.063121) (xy 320.406014 -77.055726)
			(xy 319.692274 -76.341986) (xy 319.684878 -76.335134) (xy 319.666279 -76.327396) (xy 319.656206 -76.327)
			(xy 308.6608 -76.327) (xy 308.62754 -76.326479) (xy 308.56159 -76.317791) (xy 308.497339 -76.300566)
			(xy 308.435888 -76.275097) (xy 308.378289 -76.241821) (xy 308.325529 -76.201308) (xy 308.301644 -76.178156)
			(xy 306.255674 -74.132186) (xy 306.248278 -74.125334) (xy 306.229679 -74.117596) (xy 306.219606 -74.1172)
			(xy 300.730158 -74.1172) (xy 300.720091 -74.117631) (xy 300.701498 -74.125356) (xy 300.69409 -74.132186)
			(xy 300.28642 -74.539856) (xy 300.27958 -74.547257) (xy 300.271863 -74.565855) (xy 300.271434 -74.575924)
			(xy 300.271434 -88.45423) (xy 300.271729 -88.462103) (xy 300.276515 -88.477104) (xy 300.280832 -88.483694)
			(xy 300.295759 -88.505354) (xy 300.32016 -88.551955) (xy 300.337926 -88.601467) (xy 300.348721 -88.652951)
			(xy 300.352339 -88.705429) (xy 300.348712 -88.757907) (xy 300.33791 -88.809389) (xy 300.320136 -88.858899)
			(xy 300.295729 -88.905496) (xy 300.280832 -88.927178) (xy 300.276501 -88.933762) (xy 300.271707 -88.948766)
			(xy 300.271434 -88.956642) (xy 300.271434 -101.454966) (xy 307.269651 -101.454966) (xy 307.273647 -101.2731)
			(xy 307.285627 -101.091585) (xy 307.305569 -100.910772) (xy 307.333434 -100.731009) (xy 307.369168 -100.552644)
			(xy 307.412701 -100.37602) (xy 307.463951 -100.201479) (xy 307.522818 -100.029357) (xy 307.589189 -99.859987)
			(xy 307.662935 -99.693696) (xy 307.743914 -99.530805) (xy 307.831969 -99.371628) (xy 307.926932 -99.216472)
			(xy 308.028617 -99.065637) (xy 308.13683 -98.919415) (xy 308.251362 -98.778086) (xy 308.37199 -98.641925)
			(xy 308.498483 -98.511193) (xy 308.630596 -98.386144) (xy 308.768074 -98.267018) (xy 308.910652 -98.154046)
			(xy 309.058055 -98.047446) (xy 309.209998 -97.947423) (xy 309.366187 -97.854171) (xy 309.526322 -97.767869)
			(xy 309.690093 -97.688684) (xy 309.857184 -97.616769) (xy 310.027272 -97.552263) (xy 310.20003 -97.495291)
			(xy 310.375124 -97.445961) (xy 310.552215 -97.40437) (xy 310.730962 -97.370597) (xy 310.91102 -97.344709)
			(xy 311.092042 -97.326754) (xy 311.273677 -97.316768) (xy 311.455576 -97.31477) (xy 311.637387 -97.320764)
			(xy 311.818759 -97.334737) (xy 311.999343 -97.356664) (xy 312.178789 -97.386502) (xy 312.356751 -97.424193)
			(xy 312.532886 -97.469664) (xy 312.706854 -97.522828) (xy 312.878318 -97.583582) (xy 313.046949 -97.651809)
			(xy 313.21242 -97.727377) (xy 313.374412 -97.81014) (xy 313.532612 -97.899939) (xy 313.686715 -97.9966)
			(xy 313.836424 -98.099937) (xy 313.981449 -98.209749) (xy 314.121511 -98.325826) (xy 314.256339 -98.447943)
			(xy 314.385673 -98.575864) (xy 314.509264 -98.709343) (xy 314.626872 -98.848121) (xy 314.738271 -98.991932)
			(xy 314.843246 -99.140496) (xy 314.941594 -99.293528) (xy 315.033125 -99.450733) (xy 315.117663 -99.611806)
			(xy 315.195044 -99.776437) (xy 315.265119 -99.944308) (xy 315.327753 -100.115095) (xy 315.382824 -100.288468)
			(xy 315.430228 -100.464093) (xy 315.469871 -100.64163) (xy 315.501678 -100.820737) (xy 315.525587 -101.001069)
			(xy 315.541552 -101.182277) (xy 315.549542 -101.364011) (xy 315.550042 -101.454966) (xy 315.549542 -101.545921)
			(xy 315.541552 -101.727655) (xy 315.525587 -101.908863) (xy 315.501678 -102.089195) (xy 315.469871 -102.268302)
			(xy 315.430228 -102.445839) (xy 315.382824 -102.621464) (xy 315.327753 -102.794837) (xy 315.265119 -102.965624)
			(xy 315.195044 -103.133495) (xy 315.117663 -103.298126) (xy 315.033125 -103.459199) (xy 314.941594 -103.616404)
			(xy 314.843246 -103.769436) (xy 314.738271 -103.918) (xy 314.626872 -104.061811) (xy 314.509264 -104.200589)
			(xy 314.385673 -104.334068) (xy 314.256339 -104.461989) (xy 314.121511 -104.584106) (xy 313.981449 -104.700183)
			(xy 313.836424 -104.809995) (xy 313.686715 -104.913332) (xy 313.532612 -105.009993) (xy 313.374412 -105.099792)
			(xy 313.21242 -105.182555) (xy 313.046949 -105.258123) (xy 312.878318 -105.32635) (xy 312.706854 -105.387104)
			(xy 312.532886 -105.440268) (xy 312.356751 -105.485739) (xy 312.178789 -105.52343) (xy 311.999343 -105.553268)
			(xy 311.818759 -105.575195) (xy 311.637387 -105.589168) (xy 311.455576 -105.595162) (xy 311.273677 -105.593164)
			(xy 311.092042 -105.583178) (xy 310.91102 -105.565223) (xy 310.730962 -105.539335) (xy 310.552215 -105.505562)
			(xy 310.375124 -105.463971) (xy 310.20003 -105.414641) (xy 310.027272 -105.357669) (xy 309.857184 -105.293163)
			(xy 309.690093 -105.221248) (xy 309.526322 -105.142063) (xy 309.366187 -105.055761) (xy 309.209998 -104.962509)
			(xy 309.058055 -104.862486) (xy 308.910652 -104.755886) (xy 308.768074 -104.642914) (xy 308.630596 -104.523788)
			(xy 308.498483 -104.398739) (xy 308.37199 -104.268007) (xy 308.251362 -104.131846) (xy 308.13683 -103.990517)
			(xy 308.028617 -103.844295) (xy 307.926932 -103.69346) (xy 307.831969 -103.538304) (xy 307.743914 -103.379127)
			(xy 307.662935 -103.216236) (xy 307.589189 -103.049945) (xy 307.522818 -102.880575) (xy 307.463951 -102.708453)
			(xy 307.412701 -102.533912) (xy 307.369168 -102.357288) (xy 307.333434 -102.178923) (xy 307.305569 -101.99916)
			(xy 307.285627 -101.818347) (xy 307.273647 -101.636832) (xy 307.269651 -101.454966) (xy 300.271434 -101.454966)
			(xy 300.271434 -120.646698) (xy 300.271857 -120.656768) (xy 300.279575 -120.67537) (xy 300.28642 -120.682766)
			(xy 301.280068 -121.676414) (xy 301.287466 -121.683259) (xy 301.306065 -121.690982) (xy 301.316136 -121.6914)
		)
		(stroke
			(width 0)
			(type solid)
		)
		(fill yes)
		(layer "In5.Cu")
		(net "P52V_1")
	)
	(gr_poly
		(pts
			(xy 326.00011 -166.271956) (xy 326.055917 -166.271446) (xy 326.167218 -166.263105) (xy 326.277585 -166.246469)
			(xy 326.386399 -166.221631) (xy 326.493054 -166.188731) (xy 326.596951 -166.147953) (xy 326.697511 -166.099525)
			(xy 326.79417 -166.043717) (xy 326.886389 -165.980841) (xy 326.973651 -165.91125) (xy 327.055468 -165.835332)
			(xy 327.131383 -165.753513) (xy 327.200971 -165.666249) (xy 327.263843 -165.574028) (xy 327.319648 -165.477367)
			(xy 327.368073 -165.376806) (xy 327.408848 -165.272907) (xy 327.441744 -165.166251) (xy 327.466578 -165.057436)
			(xy 327.48321 -164.947068) (xy 327.491548 -164.835767) (xy 327.492106 -164.77996) (xy 327.492106 -150.999952)
			(xy 327.491583 -150.944146) (xy 327.483238 -150.832846) (xy 327.4666 -150.722481) (xy 327.441761 -150.613668)
			(xy 327.408861 -150.507016) (xy 327.368082 -150.40312) (xy 327.319653 -150.302562) (xy 327.263845 -150.205904)
			(xy 327.20097 -150.113687) (xy 327.13138 -150.026426) (xy 327.055463 -149.94461) (xy 326.973645 -149.868695)
			(xy 326.886382 -149.799107) (xy 326.794164 -149.736235) (xy 326.697504 -149.680429) (xy 326.596945 -149.632003)
			(xy 326.493048 -149.591227) (xy 326.386395 -149.558329) (xy 326.277581 -149.533493) (xy 326.167216 -149.516857)
			(xy 326.055916 -149.508516) (xy 326.00011 -149.507956) (xy 154.399996 -149.507956) (xy 154.344188 -149.508478)
			(xy 154.232885 -149.516819) (xy 154.122517 -149.533454) (xy 154.0137 -149.558291) (xy 153.907043 -149.591189)
			(xy 153.803144 -149.631966) (xy 153.702581 -149.680394) (xy 153.605919 -149.7362) (xy 153.513698 -149.799075)
			(xy 153.426433 -149.868664) (xy 153.344612 -149.944581) (xy 153.268693 -150.026399) (xy 153.199101 -150.113662)
			(xy 153.136224 -150.205882) (xy 153.080414 -150.302543) (xy 153.031984 -150.403103) (xy 152.991204 -150.507002)
			(xy 152.958302 -150.613657) (xy 152.933462 -150.722474) (xy 152.916824 -150.832842) (xy 152.908479 -150.944144)
			(xy 152.908 -150.999952) (xy 152.908 -161.844536) (xy 155.304225 -161.844536) (xy 155.304225 -161.715396)
			(xy 155.312175 -161.586501) (xy 155.328045 -161.458341) (xy 155.351774 -161.3314) (xy 155.383273 -161.206161)
			(xy 155.422422 -161.083098) (xy 155.469073 -160.962679) (xy 155.523048 -160.84536) (xy 155.584143 -160.731586)
			(xy 155.652126 -160.621789) (xy 155.72674 -160.516386) (xy 155.807701 -160.415776) (xy 155.894701 -160.320341)
			(xy 155.987412 -160.230442) (xy 156.085482 -160.146421) (xy 156.188537 -160.068597) (xy 156.296188 -159.997265)
			(xy 156.408027 -159.932695) (xy 156.523628 -159.875133) (xy 156.642553 -159.824796) (xy 156.764352 -159.781876)
			(xy 156.888562 -159.746535) (xy 157.014711 -159.718908) (xy 157.142323 -159.699099) (xy 157.270912 -159.687183)
			(xy 157.39999 -159.683207) (xy 157.529068 -159.687183) (xy 157.657657 -159.699099) (xy 157.785269 -159.718908)
			(xy 157.911418 -159.746535) (xy 158.035628 -159.781876) (xy 158.157427 -159.824796) (xy 158.276352 -159.875133)
			(xy 158.391953 -159.932695) (xy 158.503792 -159.997265) (xy 158.611443 -160.068597) (xy 158.714498 -160.146421)
			(xy 158.812568 -160.230442) (xy 158.905279 -160.320341) (xy 158.992279 -160.415776) (xy 159.07324 -160.516386)
			(xy 159.147854 -160.621789) (xy 159.215837 -160.731586) (xy 159.276932 -160.84536) (xy 159.330907 -160.962679)
			(xy 159.377558 -161.083098) (xy 159.416707 -161.206161) (xy 159.448206 -161.3314) (xy 159.471935 -161.458341)
			(xy 159.487805 -161.586501) (xy 159.495755 -161.715396) (xy 159.496252 -161.779966) (xy 159.495755 -161.844536)
			(xy 320.904351 -161.844536) (xy 320.904351 -161.715396) (xy 320.912301 -161.586501) (xy 320.928171 -161.458341)
			(xy 320.9519 -161.3314) (xy 320.983399 -161.206161) (xy 321.022548 -161.083098) (xy 321.069199 -160.962679)
			(xy 321.123174 -160.84536) (xy 321.184269 -160.731586) (xy 321.252252 -160.621789) (xy 321.326866 -160.516386)
			(xy 321.407827 -160.415776) (xy 321.494827 -160.320341) (xy 321.587538 -160.230442) (xy 321.685608 -160.146421)
			(xy 321.788663 -160.068597) (xy 321.896314 -159.997265) (xy 322.008153 -159.932695) (xy 322.123754 -159.875133)
			(xy 322.242679 -159.824796) (xy 322.364478 -159.781876) (xy 322.488688 -159.746535) (xy 322.614837 -159.718908)
			(xy 322.742449 -159.699099) (xy 322.871038 -159.687183) (xy 323.000116 -159.683207) (xy 323.129194 -159.687183)
			(xy 323.257783 -159.699099) (xy 323.385395 -159.718908) (xy 323.511544 -159.746535) (xy 323.635754 -159.781876)
			(xy 323.757553 -159.824796) (xy 323.876478 -159.875133) (xy 323.992079 -159.932695) (xy 324.103918 -159.997265)
			(xy 324.211569 -160.068597) (xy 324.314624 -160.146421) (xy 324.412694 -160.230442) (xy 324.505405 -160.320341)
			(xy 324.592405 -160.415776) (xy 324.673366 -160.516386) (xy 324.74798 -160.621789) (xy 324.815963 -160.731586)
			(xy 324.877058 -160.84536) (xy 324.931033 -160.962679) (xy 324.977684 -161.083098) (xy 325.016833 -161.206161)
			(xy 325.048332 -161.3314) (xy 325.072061 -161.458341) (xy 325.087931 -161.586501) (xy 325.095881 -161.715396)
			(xy 325.096378 -161.779966) (xy 325.095881 -161.844536) (xy 325.087931 -161.973431) (xy 325.072061 -162.101591)
			(xy 325.048332 -162.228532) (xy 325.016833 -162.353771) (xy 324.977684 -162.476834) (xy 324.931033 -162.597253)
			(xy 324.877058 -162.714572) (xy 324.815963 -162.828346) (xy 324.74798 -162.938143) (xy 324.673366 -163.043546)
			(xy 324.592405 -163.144156) (xy 324.505405 -163.239591) (xy 324.412694 -163.32949) (xy 324.314624 -163.413511)
			(xy 324.211569 -163.491335) (xy 324.103918 -163.562667) (xy 323.992079 -163.627237) (xy 323.876478 -163.684799)
			(xy 323.757553 -163.735136) (xy 323.635754 -163.778056) (xy 323.511544 -163.813397) (xy 323.385395 -163.841024)
			(xy 323.257783 -163.860833) (xy 323.129194 -163.872749) (xy 323.000116 -163.876726) (xy 322.871038 -163.872749)
			(xy 322.742449 -163.860833) (xy 322.614837 -163.841024) (xy 322.488688 -163.813397) (xy 322.364478 -163.778056)
			(xy 322.242679 -163.735136) (xy 322.123754 -163.684799) (xy 322.008153 -163.627237) (xy 321.896314 -163.562667)
			(xy 321.788663 -163.491335) (xy 321.685608 -163.413511) (xy 321.587538 -163.32949) (xy 321.494827 -163.239591)
			(xy 321.407827 -163.144156) (xy 321.326866 -163.043546) (xy 321.252252 -162.938143) (xy 321.184269 -162.828346)
			(xy 321.123174 -162.714572) (xy 321.069199 -162.597253) (xy 321.022548 -162.476834) (xy 320.983399 -162.353771)
			(xy 320.9519 -162.228532) (xy 320.928171 -162.101591) (xy 320.912301 -161.973431) (xy 320.904351 -161.844536)
			(xy 159.495755 -161.844536) (xy 159.487805 -161.973431) (xy 159.471935 -162.101591) (xy 159.448206 -162.228532)
			(xy 159.416707 -162.353771) (xy 159.377558 -162.476834) (xy 159.330907 -162.597253) (xy 159.276932 -162.714572)
			(xy 159.215837 -162.828346) (xy 159.147854 -162.938143) (xy 159.07324 -163.043546) (xy 158.992279 -163.144156)
			(xy 158.905279 -163.239591) (xy 158.812568 -163.32949) (xy 158.714498 -163.413511) (xy 158.611443 -163.491335)
			(xy 158.503792 -163.562667) (xy 158.391953 -163.627237) (xy 158.276352 -163.684799) (xy 158.157427 -163.735136)
			(xy 158.035628 -163.778056) (xy 157.911418 -163.813397) (xy 157.785269 -163.841024) (xy 157.657657 -163.860833)
			(xy 157.529068 -163.872749) (xy 157.39999 -163.876726) (xy 157.270912 -163.872749) (xy 157.142323 -163.860833)
			(xy 157.014711 -163.841024) (xy 156.888562 -163.813397) (xy 156.764352 -163.778056) (xy 156.642553 -163.735136)
			(xy 156.523628 -163.684799) (xy 156.408027 -163.627237) (xy 156.296188 -163.562667) (xy 156.188537 -163.491335)
			(xy 156.085482 -163.413511) (xy 155.987412 -163.32949) (xy 155.894701 -163.239591) (xy 155.807701 -163.144156)
			(xy 155.72674 -163.043546) (xy 155.652126 -162.938143) (xy 155.584143 -162.828346) (xy 155.523048 -162.714572)
			(xy 155.469073 -162.597253) (xy 155.422422 -162.476834) (xy 155.383273 -162.353771) (xy 155.351774 -162.228532)
			(xy 155.328045 -162.101591) (xy 155.312175 -161.973431) (xy 155.304225 -161.844536) (xy 152.908 -161.844536)
			(xy 152.908 -164.77996) (xy 152.908508 -164.835769) (xy 152.916846 -164.947074) (xy 152.933479 -165.057444)
			(xy 152.958314 -165.166264) (xy 152.991211 -165.272922) (xy 153.031987 -165.376825) (xy 153.080414 -165.477389)
			(xy 153.13622 -165.574053) (xy 153.199095 -165.666277) (xy 153.268686 -165.753543) (xy 153.344603 -165.835366)
			(xy 153.426423 -165.911286) (xy 153.513688 -165.980879) (xy 153.605909 -166.043756) (xy 153.702572 -166.099566)
			(xy 153.803135 -166.147995) (xy 153.907036 -166.188775) (xy 154.013694 -166.221675) (xy 154.122512 -166.246513)
			(xy 154.232883 -166.263149) (xy 154.344187 -166.271491) (xy 154.399996 -166.271956)
		)
		(stroke
			(width 0)
			(type solid)
		)
		(fill yes)
		(layer "In5.Cu")
		(net "GND3")
	)
	(gr_poly
		(pts
			(xy 277.136606 -104.798368) (xy 277.146675 -104.797943) (xy 277.165275 -104.790224) (xy 277.172674 -104.783382)
			(xy 277.676864 -104.279192) (xy 277.677372 -104.278684) (xy 277.683958 -104.271304) (xy 277.691419 -104.253005)
			(xy 277.69185 -104.243124) (xy 277.69185 -96.417638) (xy 277.691459 -96.408144) (xy 277.684576 -96.390446)
			(xy 277.671761 -96.376432) (xy 277.663402 -96.371918) (xy 277.56866 -96.325182) (xy 277.539958 -96.327976)
			(xy 277.528528 -96.336866) (xy 277.49523 -96.361789) (xy 277.424785 -96.406018) (xy 277.350518 -96.443477)
			(xy 277.273078 -96.473838) (xy 277.193142 -96.496838) (xy 277.111408 -96.512273) (xy 277.02859 -96.520011)
			(xy 276.987 -96.520508) (xy 276.944652 -96.520004) (xy 276.860338 -96.511953) (xy 276.777172 -96.495924)
			(xy 276.695905 -96.472063) (xy 276.617275 -96.440584) (xy 276.541994 -96.401773) (xy 276.470742 -96.355983)
			(xy 276.404166 -96.303627) (xy 276.342868 -96.245179) (xy 276.287403 -96.181169) (xy 276.238274 -96.112177)
			(xy 276.195925 -96.038827) (xy 276.160741 -95.961784) (xy 276.133039 -95.881745) (xy 276.113071 -95.799436)
			(xy 276.101018 -95.715601) (xy 276.096988 -95.631) (xy 276.101018 -95.546399) (xy 276.113071 -95.462564)
			(xy 276.133039 -95.380255) (xy 276.160741 -95.300216) (xy 276.195925 -95.223173) (xy 276.238274 -95.149823)
			(xy 276.287403 -95.080831) (xy 276.342868 -95.016821) (xy 276.404166 -94.958373) (xy 276.470742 -94.906017)
			(xy 276.541994 -94.860227) (xy 276.617275 -94.821416) (xy 276.695905 -94.789937) (xy 276.777172 -94.766076)
			(xy 276.860338 -94.750047) (xy 276.944652 -94.741996) (xy 276.987 -94.741492) (xy 277.028591 -94.741961)
			(xy 277.111412 -94.749699) (xy 277.193149 -94.765135) (xy 277.273087 -94.788135) (xy 277.350529 -94.818498)
			(xy 277.424798 -94.855958) (xy 277.495246 -94.900188) (xy 277.528528 -94.925134) (xy 277.539958 -94.934024)
			(xy 277.56866 -94.936818) (xy 277.663402 -94.890082) (xy 277.671776 -94.885572) (xy 277.684648 -94.871589)
			(xy 277.691516 -94.853867) (xy 277.69185 -94.844362) (xy 277.69185 -58.268108) (xy 277.692371 -58.234847)
			(xy 277.701056 -58.168896) (xy 277.71828 -58.104643) (xy 277.743746 -58.04319) (xy 277.777019 -57.985588)
			(xy 277.817529 -57.932825) (xy 277.840694 -57.908952) (xy 281.668474 -54.081172) (xy 281.692354 -54.058016)
			(xy 281.745118 -54.017511) (xy 281.802719 -53.984242) (xy 281.864171 -53.95878) (xy 281.928422 -53.941561)
			(xy 281.994371 -53.932878) (xy 282.02763 -53.932328) (xy 292.131242 -53.932328) (xy 292.141309 -53.931898)
			(xy 292.159905 -53.924176) (xy 292.16731 -53.917342) (xy 295.564814 -50.519838) (xy 295.565322 -50.51933)
			(xy 295.571905 -50.511949) (xy 295.579354 -50.49365) (xy 295.5798 -50.48377) (xy 295.5798 -47.729394)
			(xy 295.579376 -47.719324) (xy 295.57166 -47.700721) (xy 295.564814 -47.693326) (xy 295.066974 -47.195486)
			(xy 295.059578 -47.188634) (xy 295.040979 -47.180896) (xy 295.030906 -47.1805) (xy 291.175948 -47.1805)
			(xy 291.17043 -47.180668) (xy 291.159667 -47.183107) (xy 291.154612 -47.185326) (xy 291.13099 -47.196248)
			(xy 291.122608 -47.202598) (xy 291.119052 -47.206662) (xy 291.090935 -47.238361) (xy 291.029602 -47.296832)
			(xy 290.962989 -47.349208) (xy 290.891698 -47.395014) (xy 290.816375 -47.433835) (xy 290.737703 -47.46532)
			(xy 290.656394 -47.489183) (xy 290.573185 -47.505209) (xy 290.488829 -47.513251) (xy 290.44646 -47.513748)
			(xy 290.445444 -47.513748) (xy 290.406928 -47.513318) (xy 290.330188 -47.506614) (xy 290.254316 -47.493296)
			(xy 290.17988 -47.473465) (xy 290.107439 -47.447268) (xy 290.072318 -47.431452) (xy 290.067238 -47.429166)
			(xy 290.056824 -47.42688) (xy 290.051536 -47.42588) (xy 290.040776 -47.42588) (xy 290.035488 -47.42688)
			(xy 290.024566 -47.429166) (xy 290.019486 -47.431452) (xy 289.998978 -47.440759) (xy 289.957174 -47.457531)
			(xy 289.93592 -47.46498) (xy 289.900821 -47.476713) (xy 289.829101 -47.494995) (xy 289.756109 -47.507246)
			(xy 289.682351 -47.513383) (xy 289.645344 -47.513748) (xy 289.64509 -47.513748) (xy 289.603634 -47.513271)
			(xy 289.521081 -47.505557) (xy 289.439604 -47.490195) (xy 289.35991 -47.46732) (xy 289.282689 -47.43713)
			(xy 289.208612 -47.399887) (xy 289.138321 -47.355914) (xy 289.072426 -47.305592) (xy 289.011498 -47.249357)
			(xy 288.98342 -47.218854) (xy 288.973006 -47.206916) (xy 288.969196 -47.202598) (xy 288.960814 -47.196248)
			(xy 288.936938 -47.185072) (xy 288.931873 -47.18291) (xy 288.921108 -47.1806) (xy 288.915602 -47.1805)
			(xy 286.336486 -47.1805) (xy 286.32507 -47.181136) (xy 286.304498 -47.191039) (xy 286.296862 -47.19955)
			(xy 286.248348 -47.259494) (xy 286.243198 -47.266472) (xy 286.237474 -47.282831) (xy 286.237172 -47.291498)
			(xy 286.237172 -47.304198) (xy 286.238442 -47.309532) (xy 286.247866 -47.356013) (xy 286.257918 -47.450323)
			(xy 286.258508 -47.497746) (xy 286.258508 -47.498) (xy 286.258033 -47.539102) (xy 286.250448 -47.620957)
			(xy 286.235343 -47.701762) (xy 286.212847 -47.780829) (xy 286.183151 -47.857483) (xy 286.146509 -47.93107)
			(xy 286.103234 -48.000962) (xy 286.053694 -48.066563) (xy 285.998313 -48.127313) (xy 285.937563 -48.182694)
			(xy 285.871962 -48.232234) (xy 285.80207 -48.275509) (xy 285.728483 -48.312151) (xy 285.651829 -48.341847)
			(xy 285.572762 -48.364343) (xy 285.491957 -48.379448) (xy 285.410102 -48.387033) (xy 285.369 -48.387508)
			(xy 285.367222 -48.387508) (xy 285.315166 -48.386741) (xy 285.211773 -48.374522) (xy 285.160974 -48.363124)
			(xy 285.158434 -48.362616) (xy 285.152338 -48.3616) (xy 285.144185 -48.360835) (xy 285.128115 -48.363935)
			(xy 285.120842 -48.367696) (xy 285.09468 -48.382174) (xy 285.088584 -48.38954) (xy 285.071312 -48.410114)
			(xy 285.068264 -48.419258) (xy 285.054105 -48.459377) (xy 285.01916 -48.536954) (xy 284.976966 -48.610838)
			(xy 284.927909 -48.680355) (xy 284.872437 -48.744869) (xy 284.811058 -48.80379) (xy 284.744331 -48.85658)
			(xy 284.672868 -48.902756) (xy 284.597322 -48.941896) (xy 284.518383 -48.973643) (xy 284.436773 -48.997705)
			(xy 284.353238 -49.013864) (xy 284.268542 -49.02197) (xy 284.226 -49.022508) (xy 284.225492 -49.022508)
			(xy 284.184551 -49.022027) (xy 284.103019 -49.014474) (xy 284.022525 -48.99946) (xy 283.943752 -48.977114)
			(xy 283.867365 -48.947622) (xy 283.794012 -48.911236) (xy 283.724313 -48.868263) (xy 283.658858 -48.819067)
			(xy 283.598201 -48.764064) (xy 283.570172 -48.734218) (xy 283.569918 -48.733964) (xy 283.562552 -48.72609)
			(xy 283.540708 -48.716438) (xy 283.533086 -48.713396) (xy 283.51676 -48.71183) (xy 283.508704 -48.71339)
			(xy 283.501084 -48.715168) (xy 283.495242 -48.718216) (xy 283.457082 -48.737588) (xy 283.377775 -48.769762)
			(xy 283.295741 -48.794161) (xy 283.211742 -48.810559) (xy 283.126554 -48.818804) (xy 283.083762 -48.819308)
			(xy 283.083 -48.819308) (xy 283.041898 -48.818833) (xy 282.960043 -48.811248) (xy 282.879238 -48.796143)
			(xy 282.800171 -48.773647) (xy 282.723517 -48.743951) (xy 282.64993 -48.707309) (xy 282.580038 -48.664034)
			(xy 282.514437 -48.614494) (xy 282.453687 -48.559113) (xy 282.398306 -48.498363) (xy 282.348766 -48.432762)
			(xy 282.305491 -48.36287) (xy 282.268849 -48.289283) (xy 282.239153 -48.212629) (xy 282.216657 -48.133562)
			(xy 282.201552 -48.052757) (xy 282.193967 -47.970902) (xy 282.193492 -47.9298) (xy 282.193492 -47.929546)
			(xy 282.193923 -47.889955) (xy 282.200961 -47.811086) (xy 282.214983 -47.733156) (xy 282.23588 -47.656781)
			(xy 282.263486 -47.582567) (xy 282.297582 -47.511102) (xy 282.337898 -47.442952) (xy 282.384115 -47.378657)
			(xy 282.409646 -47.348394) (xy 282.419298 -47.336964) (xy 282.423616 -47.307754) (xy 282.378912 -47.210218)
			(xy 282.372562 -47.196502) (xy 282.347924 -47.1805) (xy 280.710894 -47.1805) (xy 280.700824 -47.180924)
			(xy 280.682221 -47.18864) (xy 280.674826 -47.195486) (xy 278.234112 -49.6362) (xy 285.093159 -49.6362)
			(xy 285.09719 -49.551598) (xy 285.109243 -49.467762) (xy 285.129211 -49.385452) (xy 285.156912 -49.305412)
			(xy 285.192097 -49.228367) (xy 285.234445 -49.155016) (xy 285.283574 -49.086023) (xy 285.339038 -49.022012)
			(xy 285.400336 -48.963562) (xy 285.466912 -48.911204) (xy 285.538164 -48.865412) (xy 285.613445 -48.826599)
			(xy 285.692075 -48.795118) (xy 285.773342 -48.771254) (xy 285.856509 -48.755222) (xy 285.940823 -48.747169)
			(xy 285.983172 -48.746664) (xy 286.024585 -48.747103) (xy 286.107056 -48.754768) (xy 286.188456 -48.770071)
			(xy 286.268079 -48.792879) (xy 286.345236 -48.822996) (xy 286.38246 -48.841152) (xy 286.392777 -48.845742)
			(xy 286.415322 -48.846392) (xy 286.425894 -48.842422) (xy 286.468239 -48.824491) (xy 286.555816 -48.796434)
			(xy 286.64582 -48.77756) (xy 286.737291 -48.768071) (xy 286.783272 -48.767492) (xy 286.825938 -48.767984)
			(xy 286.910879 -48.776144) (xy 286.994648 -48.792402) (xy 287.076474 -48.816609) (xy 287.155606 -48.848541)
			(xy 287.231316 -48.887905) (xy 287.302908 -48.93434) (xy 287.369723 -48.987418) (xy 287.431148 -49.046651)
			(xy 287.486617 -49.111494) (xy 287.535621 -49.181353) (xy 287.577709 -49.255583) (xy 287.612494 -49.333503)
			(xy 287.626552 -49.37379) (xy 287.630761 -49.384635) (xy 287.647113 -49.401156) (xy 287.669044 -49.40886)
			(xy 287.680654 -49.40808) (xy 287.705905 -49.405417) (xy 287.756609 -49.402622) (xy 287.782 -49.402492)
			(xy 287.824348 -49.402996) (xy 287.908662 -49.411047) (xy 287.991828 -49.427076) (xy 288.073095 -49.450937)
			(xy 288.151725 -49.482416) (xy 288.227006 -49.521227) (xy 288.298258 -49.567017) (xy 288.364834 -49.619373)
			(xy 288.426132 -49.677821) (xy 288.481597 -49.741831) (xy 288.530726 -49.810823) (xy 288.573075 -49.884173)
			(xy 288.608259 -49.961216) (xy 288.635961 -50.041255) (xy 288.655929 -50.123564) (xy 288.667982 -50.207399)
			(xy 288.672013 -50.292) (xy 288.667982 -50.376601) (xy 288.655929 -50.460436) (xy 288.635961 -50.542745)
			(xy 288.608259 -50.622784) (xy 288.573075 -50.699827) (xy 288.530726 -50.773177) (xy 288.481597 -50.842169)
			(xy 288.426132 -50.906179) (xy 288.364834 -50.964627) (xy 288.298258 -51.016983) (xy 288.227006 -51.062773)
			(xy 288.151725 -51.101584) (xy 288.073095 -51.133063) (xy 287.991828 -51.156924) (xy 287.908662 -51.172953)
			(xy 287.824348 -51.181004) (xy 287.782 -51.181508) (xy 287.739333 -51.181042) (xy 287.654392 -51.172878)
			(xy 287.570622 -51.156618) (xy 287.488795 -51.132409) (xy 287.409663 -51.100474) (xy 287.333953 -51.061108)
			(xy 287.262361 -51.014671) (xy 287.195546 -50.961591) (xy 287.134122 -50.902356) (xy 287.078653 -50.837511)
			(xy 287.02965 -50.767651) (xy 286.987562 -50.693419) (xy 286.952778 -50.615497) (xy 286.93872 -50.57521)
			(xy 286.934449 -50.564396) (xy 286.918124 -50.547876) (xy 286.896219 -50.540156) (xy 286.884618 -50.54092)
			(xy 286.859367 -50.543586) (xy 286.808663 -50.546379) (xy 286.783272 -50.546508) (xy 286.741859 -50.546054)
			(xy 286.659389 -50.538393) (xy 286.577989 -50.523094) (xy 286.498365 -50.500288) (xy 286.421208 -50.470175)
			(xy 286.383984 -50.45202) (xy 286.373658 -50.447458) (xy 286.351122 -50.446792) (xy 286.34055 -50.45075)
			(xy 286.298212 -50.468697) (xy 286.210632 -50.496751) (xy 286.120626 -50.51562) (xy 286.029153 -50.525104)
			(xy 285.983172 -50.52568) (xy 285.940823 -50.525231) (xy 285.856509 -50.517178) (xy 285.773342 -50.501146)
			(xy 285.692075 -50.477282) (xy 285.613445 -50.445801) (xy 285.538164 -50.406988) (xy 285.466912 -50.361196)
			(xy 285.400336 -50.308838) (xy 285.339038 -50.250388) (xy 285.283574 -50.186377) (xy 285.234445 -50.117384)
			(xy 285.192097 -50.044033) (xy 285.156912 -49.966988) (xy 285.129211 -49.886948) (xy 285.109243 -49.804638)
			(xy 285.09719 -49.720802) (xy 285.093159 -49.6362) (xy 278.234112 -49.6362) (xy 277.097236 -50.773076)
			(xy 277.091148 -50.779578) (xy 277.083575 -50.795686) (xy 277.082027 -50.813419) (xy 277.084028 -50.822098)
			(xy 277.084028 -50.822352) (xy 277.093731 -50.860059) (xy 277.107287 -50.936736) (xy 277.114086 -51.014305)
			(xy 277.114508 -51.053238) (xy 277.114508 -51.054) (xy 277.113979 -51.09755) (xy 277.105467 -51.184232)
			(xy 277.088526 -51.269668) (xy 277.063317 -51.35304) (xy 277.030081 -51.433549) (xy 276.989137 -51.510425)
			(xy 276.940877 -51.582932) (xy 276.885762 -51.650376) (xy 276.824321 -51.712111) (xy 276.790766 -51.7398)
			(xy 277.874988 -51.7398) (xy 277.879018 -51.655199) (xy 277.891071 -51.571364) (xy 277.911039 -51.489055)
			(xy 277.938741 -51.409016) (xy 277.973925 -51.331973) (xy 278.016274 -51.258623) (xy 278.065403 -51.189631)
			(xy 278.120868 -51.125621) (xy 278.182166 -51.067173) (xy 278.248742 -51.014817) (xy 278.319994 -50.969027)
			(xy 278.395275 -50.930216) (xy 278.473905 -50.898737) (xy 278.555172 -50.874876) (xy 278.638338 -50.858847)
			(xy 278.722652 -50.850796) (xy 278.765 -50.850292) (xy 278.803284 -50.85068) (xy 278.879573 -50.857219)
			(xy 278.955015 -50.8703) (xy 279.029052 -50.889827) (xy 279.065228 -50.902362) (xy 279.073665 -50.905013)
			(xy 279.091335 -50.905013) (xy 279.099772 -50.902362) (xy 279.13595 -50.889837) (xy 279.20999 -50.870329)
			(xy 279.285431 -50.857249) (xy 279.361717 -50.850694) (xy 279.4 -50.850292) (xy 279.442348 -50.850796)
			(xy 279.526662 -50.858847) (xy 279.609828 -50.874876) (xy 279.691095 -50.898737) (xy 279.769725 -50.930216)
			(xy 279.845006 -50.969027) (xy 279.916258 -51.014817) (xy 279.982834 -51.067173) (xy 280.044132 -51.125621)
			(xy 280.099597 -51.189631) (xy 280.148726 -51.258623) (xy 280.191075 -51.331973) (xy 280.226259 -51.409016)
			(xy 280.253961 -51.489055) (xy 280.273929 -51.571364) (xy 280.285982 -51.655199) (xy 280.290013 -51.7398)
			(xy 280.285982 -51.824401) (xy 280.273929 -51.908236) (xy 280.253961 -51.990545) (xy 280.226259 -52.070584)
			(xy 280.191075 -52.147627) (xy 280.148726 -52.220977) (xy 280.099597 -52.289969) (xy 280.044132 -52.353979)
			(xy 279.982834 -52.412427) (xy 279.916258 -52.464783) (xy 279.845006 -52.510573) (xy 279.769725 -52.549384)
			(xy 279.691095 -52.580863) (xy 279.609828 -52.604724) (xy 279.526662 -52.620753) (xy 279.442348 -52.628804)
			(xy 279.4 -52.629308) (xy 279.361716 -52.62892) (xy 279.285427 -52.622381) (xy 279.209985 -52.6093)
			(xy 279.135948 -52.589773) (xy 279.099772 -52.577238) (xy 279.091335 -52.574587) (xy 279.073665 -52.574587)
			(xy 279.065228 -52.577238) (xy 279.02905 -52.589763) (xy 278.95501 -52.609271) (xy 278.879569 -52.622351)
			(xy 278.803283 -52.628906) (xy 278.765 -52.629308) (xy 278.722652 -52.628804) (xy 278.638338 -52.620753)
			(xy 278.555172 -52.604724) (xy 278.473905 -52.580863) (xy 278.395275 -52.549384) (xy 278.319994 -52.510573)
			(xy 278.248742 -52.464783) (xy 278.182166 -52.412427) (xy 278.120868 -52.353979) (xy 278.065403 -52.289969)
			(xy 278.016274 -52.220977) (xy 277.973925 -52.147627) (xy 277.938741 -52.070584) (xy 277.911039 -51.990545)
			(xy 277.891071 -51.908236) (xy 277.879018 -51.824401) (xy 277.874988 -51.7398) (xy 276.790766 -51.7398)
			(xy 276.757141 -51.767547) (xy 276.684865 -51.816152) (xy 276.608185 -51.857462) (xy 276.527835 -51.891081)
			(xy 276.486366 -51.904392) (xy 276.47011 -51.909472) (xy 276.450552 -51.935888) (xy 276.450552 -89.635076)
			(xy 276.450721 -89.641085) (xy 276.453548 -89.652766) (xy 276.45614 -89.65819) (xy 276.46757 -89.680288)
			(xy 276.47077 -89.685355) (xy 276.479111 -89.693956) (xy 276.48408 -89.697306) (xy 276.48662 -89.69883)
			(xy 276.520997 -89.723876) (xy 276.585305 -89.779552) (xy 276.644005 -89.841111) (xy 276.696561 -89.907993)
			(xy 276.742494 -89.979585) (xy 276.781383 -90.055235) (xy 276.812873 -90.134252) (xy 276.836678 -90.215914)
			(xy 276.852579 -90.299475) (xy 276.860431 -90.384172) (xy 276.860163 -90.469233) (xy 276.851777 -90.553879)
			(xy 276.835349 -90.637338) (xy 276.811031 -90.718848) (xy 276.779043 -90.797665) (xy 276.739677 -90.873068)
			(xy 276.693295 -90.94437) (xy 276.640318 -91.010919) (xy 276.581231 -91.072107) (xy 276.516573 -91.127376)
			(xy 276.482048 -91.152218) (xy 276.476968 -91.155774) (xy 276.46884 -91.165172) (xy 276.456394 -91.189302)
			(xy 276.4536 -91.19489) (xy 276.450552 -91.206828) (xy 276.450552 -93.373448) (xy 276.450034 -93.40671)
			(xy 276.441354 -93.472664) (xy 276.424135 -93.53692) (xy 276.398672 -93.598377) (xy 276.365402 -93.655983)
			(xy 276.324894 -93.708751) (xy 276.301708 -93.732604) (xy 275.695156 -94.339156) (xy 275.671276 -94.362312)
			(xy 275.618512 -94.402818) (xy 275.560911 -94.436089) (xy 275.49946 -94.461553) (xy 275.435209 -94.478775)
			(xy 275.369259 -94.487461) (xy 275.336 -94.488) (xy 273.776694 -94.488) (xy 273.766624 -94.488424)
			(xy 273.748021 -94.49614) (xy 273.740626 -94.502986) (xy 273.572986 -94.670626) (xy 273.566134 -94.678022)
			(xy 273.558396 -94.696621) (xy 273.558 -94.706694) (xy 273.558 -96.923606) (xy 273.558458 -96.933484)
			(xy 273.565898 -96.951786) (xy 273.572478 -96.959166) (xy 273.572732 -96.95942) (xy 274.044156 -97.430844)
			(xy 274.067312 -97.454724) (xy 274.107818 -97.507488) (xy 274.141089 -97.565089) (xy 274.166553 -97.62654)
			(xy 274.183775 -97.690791) (xy 274.192461 -97.756741) (xy 274.193 -97.79) (xy 274.193 -101.981) (xy 274.192479 -102.01426)
			(xy 274.183791 -102.08021) (xy 274.166566 -102.144461) (xy 274.141097 -102.205912) (xy 274.107821 -102.263511)
			(xy 274.067308 -102.316271) (xy 274.044156 -102.340156) (xy 273.536156 -102.848156) (xy 273.512276 -102.871312)
			(xy 273.459512 -102.911818) (xy 273.401911 -102.945089) (xy 273.34046 -102.970553) (xy 273.276209 -102.987775)
			(xy 273.210259 -102.996461) (xy 273.177 -102.997) (xy 272.570194 -102.997) (xy 272.560124 -102.997424)
			(xy 272.541521 -103.00514) (xy 272.534126 -103.011986) (xy 272.379186 -103.166926) (xy 272.372334 -103.174322)
			(xy 272.364596 -103.192921) (xy 272.3642 -103.202994) (xy 272.3642 -104.705658) (xy 272.364667 -104.715532)
			(xy 272.372121 -104.73382) (xy 272.378678 -104.741218) (xy 272.378932 -104.741472) (xy 272.420842 -104.783382)
			(xy 272.42135 -104.78389) (xy 272.428733 -104.790469) (xy 272.447031 -104.797914) (xy 272.45691 -104.798368)
		)
		(stroke
			(width 0)
			(type solid)
		)
		(fill yes)
		(layer "In5.Cu")
		(net "P52V_HS1_1272_GATE")
	)
	(gr_poly
		(pts
			(xy 221.756224 -145.98396) (xy 221.766291 -145.983531) (xy 221.784886 -145.975806) (xy 221.792292 -145.968974)
			(xy 222.733616 -145.02765) (xy 222.740464 -145.020253) (xy 222.748193 -145.001654) (xy 222.748602 -144.991582)
			(xy 222.748602 -144.282414) (xy 222.74826 -144.272883) (xy 222.741388 -144.255108) (xy 222.728481 -144.241088)
			(xy 222.711334 -144.232772) (xy 222.701866 -144.231614) (xy 222.633396 -144.225687) (xy 222.497246 -144.206835)
			(xy 222.362431 -144.180055) (xy 222.229412 -144.145438) (xy 222.098645 -144.103105) (xy 221.970576 -144.053198)
			(xy 221.845644 -143.995889) (xy 221.724277 -143.931374) (xy 221.606889 -143.859874) (xy 221.493882 -143.781633)
			(xy 221.385642 -143.696919) (xy 221.282541 -143.606021) (xy 221.18493 -143.509251) (xy 221.093144 -143.40694)
			(xy 221.007497 -143.299438) (xy 220.928281 -143.187112) (xy 220.855767 -143.070347) (xy 220.790205 -142.949543)
			(xy 220.731817 -142.825111) (xy 220.680804 -142.697479) (xy 220.63734 -142.567083) (xy 220.601574 -142.434369)
			(xy 220.573629 -142.299791) (xy 220.553599 -142.163809) (xy 220.541554 -142.026889) (xy 220.537534 -141.889498)
			(xy 220.541554 -141.752108) (xy 220.5536 -141.615188) (xy 220.573629 -141.479206) (xy 220.601575 -141.344628)
			(xy 220.637341 -141.211914) (xy 220.680805 -141.081518) (xy 220.731818 -140.953886) (xy 220.790206 -140.829455)
			(xy 220.855769 -140.70865) (xy 220.928282 -140.591885) (xy 221.007498 -140.479559) (xy 221.093146 -140.372057)
			(xy 221.184932 -140.269746) (xy 221.282543 -140.172977) (xy 221.385645 -140.082079) (xy 221.493884 -139.997365)
			(xy 221.606891 -139.919124) (xy 221.72428 -139.847624) (xy 221.845647 -139.78311) (xy 221.970579 -139.725801)
			(xy 222.098648 -139.675894) (xy 222.229415 -139.633561) (xy 222.362434 -139.598945) (xy 222.497249 -139.572165)
			(xy 222.633399 -139.553313) (xy 222.701866 -139.547346) (xy 222.711323 -139.546178) (xy 222.728432 -139.537821)
			(xy 222.741326 -139.52381) (xy 222.748237 -139.506067) (xy 222.748602 -139.496546) (xy 222.748602 -120.246648)
			(xy 222.748169 -120.236582) (xy 222.740442 -120.217991) (xy 222.733616 -120.21058) (xy 221.963996 -119.44096)
			(xy 221.9566 -119.434108) (xy 221.938002 -119.426365) (xy 221.927928 -119.425974) (xy 177.772314 -119.425974)
			(xy 177.761095 -119.426569) (xy 177.740787 -119.436114) (xy 177.726438 -119.453366) (xy 177.723038 -119.464074)
			(xy 177.698654 -119.559324) (xy 177.696348 -119.570372) (xy 177.700471 -119.592532) (xy 177.713697 -119.610784)
			(xy 177.723292 -119.616728) (xy 177.723546 -119.616728) (xy 177.77655 -119.646354) (xy 177.878908 -119.711698)
			(xy 177.976674 -119.783734) (xy 178.06941 -119.862139) (xy 178.156701 -119.946562) (xy 178.23816 -120.036628)
			(xy 178.31342 -120.131933) (xy 178.382147 -120.232052) (xy 178.444033 -120.336539) (xy 178.498802 -120.444925)
			(xy 178.546209 -120.556727) (xy 178.586042 -120.671447) (xy 178.618125 -120.78857) (xy 178.642312 -120.907575)
			(xy 178.658498 -121.02793) (xy 178.666608 -121.149097) (xy 178.667156 -121.209816) (xy 178.666649 -121.270543)
			(xy 178.658536 -121.391727) (xy 178.642348 -121.512098) (xy 178.618156 -121.631119) (xy 178.586068 -121.748258)
			(xy 178.546228 -121.862993) (xy 178.498813 -121.97481) (xy 178.444036 -122.083211) (xy 178.382141 -122.18771)
			(xy 178.313404 -122.287843) (xy 178.238132 -122.38316) (xy 178.156662 -122.473238) (xy 178.069358 -122.557672)
			(xy 177.976609 -122.636086) (xy 177.878829 -122.708131) (xy 177.776456 -122.773484) (xy 177.669946 -122.831853)
			(xy 177.559776 -122.882977) (xy 177.446436 -122.926629) (xy 177.330435 -122.962613) (xy 177.212289 -122.990769)
			(xy 177.092526 -123.01097) (xy 176.971681 -123.023127) (xy 176.850294 -123.027186) (xy 176.728907 -123.023127)
			(xy 176.608062 -123.01097) (xy 176.488299 -122.990769) (xy 176.370153 -122.962613) (xy 176.254152 -122.926629)
			(xy 176.140812 -122.882977) (xy 176.030642 -122.831853) (xy 175.924132 -122.773484) (xy 175.821759 -122.708131)
			(xy 175.723979 -122.636086) (xy 175.63123 -122.557672) (xy 175.543926 -122.473238) (xy 175.462456 -122.38316)
			(xy 175.387184 -122.287843) (xy 175.318447 -122.18771) (xy 175.256552 -122.083211) (xy 175.201775 -121.97481)
			(xy 175.15436 -121.862993) (xy 175.11452 -121.748258) (xy 175.082432 -121.631119) (xy 175.05824 -121.512098)
			(xy 175.042052 -121.391727) (xy 175.033939 -121.270543) (xy 175.033432 -121.209816) (xy 175.033928 -121.149096)
			(xy 175.042038 -121.027926) (xy 175.058224 -120.907569) (xy 175.082414 -120.788562) (xy 175.114498 -120.671436)
			(xy 175.154334 -120.556715) (xy 175.201744 -120.444911) (xy 175.256516 -120.336524) (xy 175.318405 -120.232037)
			(xy 175.387136 -120.131917) (xy 175.4624 -120.036612) (xy 175.543862 -119.946547) (xy 175.631159 -119.862124)
			(xy 175.723899 -119.783721) (xy 175.821669 -119.711688) (xy 175.924033 -119.646346) (xy 175.977042 -119.616728)
			(xy 175.977296 -119.616728) (xy 175.986836 -119.610742) (xy 175.999977 -119.592483) (xy 176.004131 -119.570374)
			(xy 176.001934 -119.559324) (xy 175.97755 -119.464074) (xy 175.97418 -119.453353) (xy 175.95984 -119.436085)
			(xy 175.9395 -119.426593) (xy 175.928274 -119.425974) (xy 170.152314 -119.425974) (xy 170.141095 -119.426569)
			(xy 170.120787 -119.436114) (xy 170.106438 -119.453366) (xy 170.103038 -119.464074) (xy 170.078654 -119.559324)
			(xy 170.076348 -119.570372) (xy 170.080471 -119.592532) (xy 170.093697 -119.610784) (xy 170.103292 -119.616728)
			(xy 170.103546 -119.616728) (xy 170.15655 -119.646354) (xy 170.258908 -119.711698) (xy 170.356674 -119.783734)
			(xy 170.44941 -119.862139) (xy 170.536701 -119.946562) (xy 170.61816 -120.036628) (xy 170.69342 -120.131933)
			(xy 170.762147 -120.232052) (xy 170.824033 -120.336539) (xy 170.878802 -120.444925) (xy 170.926209 -120.556727)
			(xy 170.966042 -120.671447) (xy 170.998125 -120.78857) (xy 171.022312 -120.907575) (xy 171.038498 -121.02793)
			(xy 171.046608 -121.149097) (xy 171.047156 -121.209816) (xy 171.046649 -121.270543) (xy 171.038536 -121.391727)
			(xy 171.022348 -121.512098) (xy 170.998156 -121.631119) (xy 170.966068 -121.748258) (xy 170.926228 -121.862993)
			(xy 170.878813 -121.97481) (xy 170.824036 -122.083211) (xy 170.762141 -122.18771) (xy 170.693404 -122.287843)
			(xy 170.618132 -122.38316) (xy 170.536662 -122.473238) (xy 170.449358 -122.557672) (xy 170.356609 -122.636086)
			(xy 170.258829 -122.708131) (xy 170.156456 -122.773484) (xy 170.049946 -122.831853) (xy 169.939776 -122.882977)
			(xy 169.826436 -122.926629) (xy 169.710435 -122.962613) (xy 169.592289 -122.990769) (xy 169.472526 -123.01097)
			(xy 169.351681 -123.023127) (xy 169.230294 -123.027186) (xy 169.108907 -123.023127) (xy 168.988062 -123.01097)
			(xy 168.868299 -122.990769) (xy 168.750153 -122.962613) (xy 168.634152 -122.926629) (xy 168.520812 -122.882977)
			(xy 168.410642 -122.831853) (xy 168.304132 -122.773484) (xy 168.201759 -122.708131) (xy 168.103979 -122.636086)
			(xy 168.01123 -122.557672) (xy 167.923926 -122.473238) (xy 167.842456 -122.38316) (xy 167.767184 -122.287843)
			(xy 167.698447 -122.18771) (xy 167.636552 -122.083211) (xy 167.581775 -121.97481) (xy 167.53436 -121.862993)
			(xy 167.49452 -121.748258) (xy 167.462432 -121.631119) (xy 167.43824 -121.512098) (xy 167.422052 -121.391727)
			(xy 167.413939 -121.270543) (xy 167.413432 -121.209816) (xy 167.413928 -121.149096) (xy 167.422038 -121.027926)
			(xy 167.438224 -120.907569) (xy 167.462414 -120.788562) (xy 167.494498 -120.671436) (xy 167.534334 -120.556715)
			(xy 167.581744 -120.444911) (xy 167.636516 -120.336524) (xy 167.698405 -120.232037) (xy 167.767136 -120.131917)
			(xy 167.8424 -120.036612) (xy 167.923862 -119.946547) (xy 168.011159 -119.862124) (xy 168.103899 -119.783721)
			(xy 168.201669 -119.711688) (xy 168.304033 -119.646346) (xy 168.357042 -119.616728) (xy 168.357296 -119.616728)
			(xy 168.366836 -119.610742) (xy 168.379977 -119.592483) (xy 168.384131 -119.570374) (xy 168.381934 -119.559324)
			(xy 168.35755 -119.464074) (xy 168.35418 -119.453353) (xy 168.33984 -119.436085) (xy 168.3195 -119.426593)
			(xy 168.308274 -119.425974) (xy 137.77214 -119.425974) (xy 137.760918 -119.426564) (xy 137.7406 -119.436104)
			(xy 137.726243 -119.453358) (xy 137.722864 -119.464074) (xy 137.69848 -119.559324) (xy 137.696174 -119.570371)
			(xy 137.700298 -119.59253) (xy 137.713527 -119.610777) (xy 137.723118 -119.616728) (xy 137.723372 -119.616728)
			(xy 137.776365 -119.646363) (xy 137.878702 -119.711724) (xy 137.976446 -119.783773) (xy 138.069161 -119.862188)
			(xy 138.156433 -119.946619) (xy 138.237873 -120.036689) (xy 138.313116 -120.131996) (xy 138.381827 -120.232115)
			(xy 138.443699 -120.336598) (xy 138.498456 -120.44498) (xy 138.545854 -120.556776) (xy 138.585681 -120.671488)
			(xy 138.617759 -120.788603) (xy 138.641945 -120.907599) (xy 138.658131 -121.027944) (xy 138.666245 -121.149102)
			(xy 138.666728 -121.209816) (xy 138.666221 -121.270535) (xy 138.65811 -121.391701) (xy 138.641924 -121.512056)
			(xy 138.617735 -121.63106) (xy 138.585652 -121.748183) (xy 138.545817 -121.862901) (xy 138.498409 -121.974703)
			(xy 138.443639 -122.083089) (xy 138.381753 -122.187574) (xy 138.313025 -122.287692) (xy 138.237764 -122.382996)
			(xy 138.156306 -122.473061) (xy 138.069013 -122.557484) (xy 137.976277 -122.635887) (xy 137.878511 -122.707922)
			(xy 137.776152 -122.773265) (xy 137.669657 -122.831626) (xy 137.559502 -122.882743) (xy 137.446179 -122.926389)
			(xy 137.330194 -122.962368) (xy 137.212064 -122.99052) (xy 137.092318 -123.010718) (xy 136.97149 -123.022874)
			(xy 136.85012 -123.026932) (xy 136.72875 -123.022874) (xy 136.607922 -123.010718) (xy 136.488176 -122.99052)
			(xy 136.370046 -122.962368) (xy 136.254061 -122.926389) (xy 136.140738 -122.882743) (xy 136.030583 -122.831626)
			(xy 135.924088 -122.773265) (xy 135.821729 -122.707922) (xy 135.723963 -122.635887) (xy 135.631227 -122.557484)
			(xy 135.543934 -122.473061) (xy 135.462476 -122.382996) (xy 135.387215 -122.287692) (xy 135.318487 -122.187574)
			(xy 135.256601 -122.083089) (xy 135.201831 -121.974703) (xy 135.154423 -121.862901) (xy 135.114588 -121.748183)
			(xy 135.082505 -121.63106) (xy 135.058316 -121.512056) (xy 135.04213 -121.391701) (xy 135.034019 -121.270535)
			(xy 135.033512 -121.209816) (xy 135.034018 -121.149102) (xy 135.042127 -121.027944) (xy 135.058307 -120.907598)
			(xy 135.082489 -120.788602) (xy 135.114564 -120.671486) (xy 135.154387 -120.556774) (xy 135.201783 -120.444977)
			(xy 135.256539 -120.336594) (xy 135.31841 -120.232111) (xy 135.387121 -120.131992) (xy 135.462364 -120.036685)
			(xy 135.543805 -119.946617) (xy 135.631078 -119.862187) (xy 135.723794 -119.783775) (xy 135.821541 -119.711729)
			(xy 135.92388 -119.646372) (xy 135.976868 -119.616728) (xy 135.977122 -119.616728) (xy 135.986659 -119.61074)
			(xy 135.999793 -119.59248) (xy 136.003944 -119.570375) (xy 136.00176 -119.559324) (xy 135.977376 -119.464074)
			(xy 135.974007 -119.45335) (xy 135.959668 -119.436075) (xy 135.939328 -119.426573) (xy 135.9281 -119.425974)
			(xy 130.15214 -119.425974) (xy 130.140918 -119.426564) (xy 130.1206 -119.436104) (xy 130.106243 -119.453358)
			(xy 130.102864 -119.464074) (xy 130.07848 -119.559324) (xy 130.076174 -119.570371) (xy 130.080298 -119.59253)
			(xy 130.093527 -119.610777) (xy 130.103118 -119.616728) (xy 130.103372 -119.616728) (xy 130.156365 -119.646363)
			(xy 130.258702 -119.711724) (xy 130.356446 -119.783773) (xy 130.449161 -119.862188) (xy 130.536433 -119.946619)
			(xy 130.617873 -120.036689) (xy 130.693116 -120.131996) (xy 130.761827 -120.232115) (xy 130.823699 -120.336598)
			(xy 130.878456 -120.44498) (xy 130.925854 -120.556776) (xy 130.965681 -120.671488) (xy 130.997759 -120.788603)
			(xy 131.021945 -120.907599) (xy 131.038131 -121.027944) (xy 131.046245 -121.149102) (xy 131.046728 -121.209816)
			(xy 131.046221 -121.270535) (xy 131.03811 -121.391701) (xy 131.021924 -121.512056) (xy 130.997735 -121.63106)
			(xy 130.965652 -121.748183) (xy 130.925817 -121.862901) (xy 130.878409 -121.974703) (xy 130.823639 -122.083089)
			(xy 130.761753 -122.187574) (xy 130.693025 -122.287692) (xy 130.617764 -122.382996) (xy 130.536306 -122.473061)
			(xy 130.449013 -122.557484) (xy 130.356277 -122.635887) (xy 130.258511 -122.707922) (xy 130.156152 -122.773265)
			(xy 130.049657 -122.831626) (xy 129.939502 -122.882743) (xy 129.826179 -122.926389) (xy 129.710194 -122.962368)
			(xy 129.592064 -122.99052) (xy 129.472318 -123.010718) (xy 129.35149 -123.022874) (xy 129.23012 -123.026932)
			(xy 129.10875 -123.022874) (xy 128.987922 -123.010718) (xy 128.868176 -122.99052) (xy 128.750046 -122.962368)
			(xy 128.634061 -122.926389) (xy 128.520738 -122.882743) (xy 128.410583 -122.831626) (xy 128.304088 -122.773265)
			(xy 128.201729 -122.707922) (xy 128.103963 -122.635887) (xy 128.011227 -122.557484) (xy 127.923934 -122.473061)
			(xy 127.842476 -122.382996) (xy 127.767215 -122.287692) (xy 127.698487 -122.187574) (xy 127.636601 -122.083089)
			(xy 127.581831 -121.974703) (xy 127.534423 -121.862901) (xy 127.494588 -121.748183) (xy 127.462505 -121.63106)
			(xy 127.438316 -121.512056) (xy 127.42213 -121.391701) (xy 127.414019 -121.270535) (xy 127.413512 -121.209816)
			(xy 127.414018 -121.149102) (xy 127.422127 -121.027944) (xy 127.438307 -120.907598) (xy 127.462489 -120.788602)
			(xy 127.494564 -120.671486) (xy 127.534387 -120.556774) (xy 127.581783 -120.444977) (xy 127.636539 -120.336594)
			(xy 127.69841 -120.232111) (xy 127.767121 -120.131992) (xy 127.842364 -120.036685) (xy 127.923805 -119.946617)
			(xy 128.011078 -119.862187) (xy 128.103794 -119.783775) (xy 128.201541 -119.711729) (xy 128.30388 -119.646372)
			(xy 128.356868 -119.616728) (xy 128.357122 -119.616728) (xy 128.366659 -119.61074) (xy 128.379793 -119.59248)
			(xy 128.383944 -119.570375) (xy 128.38176 -119.559324) (xy 128.357376 -119.464074) (xy 128.354007 -119.45335)
			(xy 128.339668 -119.436075) (xy 128.319328 -119.426573) (xy 128.3081 -119.425974) (xy 97.771966 -119.425974)
			(xy 97.76074 -119.426559) (xy 97.740413 -119.436094) (xy 97.726047 -119.453349) (xy 97.72269 -119.464074)
			(xy 97.698306 -119.559324) (xy 97.696001 -119.570374) (xy 97.700122 -119.592537) (xy 97.713341 -119.610797)
			(xy 97.722944 -119.616728) (xy 97.723198 -119.616728) (xy 97.776208 -119.646343) (xy 97.87857 -119.711687)
			(xy 97.976338 -119.783721) (xy 98.069077 -119.862126) (xy 98.156372 -119.946549) (xy 98.237832 -120.036615)
			(xy 98.313095 -120.13192) (xy 98.381824 -120.23204) (xy 98.443713 -120.336527) (xy 98.498483 -120.444914)
			(xy 98.545892 -120.556718) (xy 98.585727 -120.671439) (xy 98.617811 -120.788564) (xy 98.641999 -120.907571)
			(xy 98.658185 -121.027927) (xy 98.666296 -121.149096) (xy 98.666808 -121.209816) (xy 98.666301 -121.270543)
			(xy 98.658188 -121.391727) (xy 98.642 -121.512098) (xy 98.617808 -121.631119) (xy 98.58572 -121.748258)
			(xy 98.54588 -121.862993) (xy 98.498465 -121.97481) (xy 98.443688 -122.083211) (xy 98.381793 -122.18771)
			(xy 98.313056 -122.287843) (xy 98.237784 -122.38316) (xy 98.156314 -122.473238) (xy 98.06901 -122.557672)
			(xy 97.976261 -122.636086) (xy 97.878481 -122.708131) (xy 97.776108 -122.773484) (xy 97.669598 -122.831853)
			(xy 97.559428 -122.882977) (xy 97.446088 -122.926629) (xy 97.330087 -122.962613) (xy 97.211941 -122.990769)
			(xy 97.092178 -123.01097) (xy 96.971333 -123.023127) (xy 96.849946 -123.027186) (xy 96.728559 -123.023127)
			(xy 96.607714 -123.01097) (xy 96.487951 -122.990769) (xy 96.369805 -122.962613) (xy 96.253804 -122.926629)
			(xy 96.140464 -122.882977) (xy 96.030294 -122.831853) (xy 95.923784 -122.773484) (xy 95.821411 -122.708131)
			(xy 95.723631 -122.636086) (xy 95.630882 -122.557672) (xy 95.543578 -122.473238) (xy 95.462108 -122.38316)
			(xy 95.386836 -122.287843) (xy 95.318099 -122.18771) (xy 95.256204 -122.083211) (xy 95.201427 -121.97481)
			(xy 95.154012 -121.862993) (xy 95.114172 -121.748258) (xy 95.082084 -121.631119) (xy 95.057892 -121.512098)
			(xy 95.041704 -121.391727) (xy 95.033591 -121.270543) (xy 95.033084 -121.209816) (xy 95.03358 -121.149095)
			(xy 95.04169 -121.027925) (xy 95.057876 -120.907568) (xy 95.082065 -120.78856) (xy 95.114148 -120.671433)
			(xy 95.153984 -120.556712) (xy 95.201393 -120.444907) (xy 95.256164 -120.336518) (xy 95.318053 -120.23203)
			(xy 95.386782 -120.131909) (xy 95.462046 -120.036602) (xy 95.543507 -119.946535) (xy 95.630802 -119.862111)
			(xy 95.723542 -119.783706) (xy 95.821311 -119.71167) (xy 95.923673 -119.646326) (xy 95.976694 -119.616728)
			(xy 95.976948 -119.616728) (xy 95.986496 -119.610746) (xy 95.99965 -119.592488) (xy 96.003807 -119.570371)
			(xy 96.001586 -119.559324) (xy 95.977202 -119.464074) (xy 95.973834 -119.453347) (xy 95.959497 -119.436065)
			(xy 95.939156 -119.426553) (xy 95.927926 -119.425974) (xy 90.151966 -119.425974) (xy 90.14074 -119.426559)
			(xy 90.120413 -119.436094) (xy 90.106047 -119.453349) (xy 90.10269 -119.464074) (xy 90.078306 -119.559324)
			(xy 90.076001 -119.570374) (xy 90.080122 -119.592537) (xy 90.093341 -119.610797) (xy 90.102944 -119.616728)
			(xy 90.103198 -119.616728) (xy 90.156208 -119.646343) (xy 90.25857 -119.711687) (xy 90.356338 -119.783721)
			(xy 90.449077 -119.862126) (xy 90.536372 -119.946549) (xy 90.617832 -120.036615) (xy 90.693095 -120.13192)
			(xy 90.761824 -120.23204) (xy 90.823713 -120.336527) (xy 90.878483 -120.444914) (xy 90.925892 -120.556718)
			(xy 90.965727 -120.671439) (xy 90.997811 -120.788564) (xy 91.021999 -120.907571) (xy 91.038185 -121.027927)
			(xy 91.046296 -121.149096) (xy 91.046808 -121.209816) (xy 91.046301 -121.270543) (xy 91.038188 -121.391727)
			(xy 91.022 -121.512098) (xy 90.997808 -121.631119) (xy 90.96572 -121.748258) (xy 90.92588 -121.862993)
			(xy 90.878465 -121.97481) (xy 90.823688 -122.083211) (xy 90.761793 -122.18771) (xy 90.693056 -122.287843)
			(xy 90.617784 -122.38316) (xy 90.536314 -122.473238) (xy 90.44901 -122.557672) (xy 90.356261 -122.636086)
			(xy 90.258481 -122.708131) (xy 90.156108 -122.773484) (xy 90.049598 -122.831853) (xy 89.939428 -122.882977)
			(xy 89.826088 -122.926629) (xy 89.710087 -122.962613) (xy 89.591941 -122.990769) (xy 89.472178 -123.01097)
			(xy 89.351333 -123.023127) (xy 89.229946 -123.027186) (xy 89.108559 -123.023127) (xy 88.987714 -123.01097)
			(xy 88.867951 -122.990769) (xy 88.749805 -122.962613) (xy 88.633804 -122.926629) (xy 88.520464 -122.882977)
			(xy 88.410294 -122.831853) (xy 88.303784 -122.773484) (xy 88.201411 -122.708131) (xy 88.103631 -122.636086)
			(xy 88.010882 -122.557672) (xy 87.923578 -122.473238) (xy 87.842108 -122.38316) (xy 87.766836 -122.287843)
			(xy 87.698099 -122.18771) (xy 87.636204 -122.083211) (xy 87.581427 -121.97481) (xy 87.534012 -121.862993)
			(xy 87.494172 -121.748258) (xy 87.462084 -121.631119) (xy 87.437892 -121.512098) (xy 87.421704 -121.391727)
			(xy 87.413591 -121.270543) (xy 87.413084 -121.209816) (xy 87.41358 -121.149095) (xy 87.42169 -121.027925)
			(xy 87.437876 -120.907568) (xy 87.462065 -120.78856) (xy 87.494148 -120.671433) (xy 87.533984 -120.556712)
			(xy 87.581393 -120.444907) (xy 87.636164 -120.336518) (xy 87.698053 -120.23203) (xy 87.766782 -120.131909)
			(xy 87.842046 -120.036602) (xy 87.923507 -119.946535) (xy 88.010802 -119.862111) (xy 88.103542 -119.783706)
			(xy 88.201311 -119.71167) (xy 88.303673 -119.646326) (xy 88.356694 -119.616728) (xy 88.356948 -119.616728)
			(xy 88.366496 -119.610746) (xy 88.37965 -119.592488) (xy 88.383807 -119.570371) (xy 88.381586 -119.559324)
			(xy 88.357202 -119.464074) (xy 88.353834 -119.453347) (xy 88.339497 -119.436065) (xy 88.319156 -119.426553)
			(xy 88.307926 -119.425974) (xy 57.772046 -119.425974) (xy 57.760823 -119.426563) (xy 57.740503 -119.436102)
			(xy 57.726144 -119.453355) (xy 57.72277 -119.464074) (xy 57.698386 -119.559324) (xy 57.69608 -119.570371)
			(xy 57.700204 -119.592529) (xy 57.713435 -119.610775) (xy 57.723024 -119.616728) (xy 57.723278 -119.616728)
			(xy 57.776289 -119.646343) (xy 57.878651 -119.711686) (xy 57.976421 -119.78372) (xy 58.069161 -119.862123)
			(xy 58.156456 -119.946547) (xy 58.237918 -120.036612) (xy 58.313182 -120.131917) (xy 58.381911 -120.232037)
			(xy 58.4438 -120.336524) (xy 58.498572 -120.444912) (xy 58.545981 -120.556716) (xy 58.585817 -120.671437)
			(xy 58.617901 -120.788563) (xy 58.64209 -120.90757) (xy 58.658275 -121.027926) (xy 58.666386 -121.149096)
			(xy 58.666888 -121.209816) (xy 58.666381 -121.270543) (xy 58.658268 -121.391727) (xy 58.64208 -121.512098)
			(xy 58.617888 -121.631119) (xy 58.5858 -121.748258) (xy 58.54596 -121.862993) (xy 58.498545 -121.97481)
			(xy 58.443768 -122.083211) (xy 58.381873 -122.18771) (xy 58.313136 -122.287843) (xy 58.237864 -122.38316)
			(xy 58.156394 -122.473238) (xy 58.06909 -122.557672) (xy 57.976341 -122.636086) (xy 57.878561 -122.708131)
			(xy 57.776188 -122.773484) (xy 57.669678 -122.831853) (xy 57.559508 -122.882977) (xy 57.446168 -122.926629)
			(xy 57.330167 -122.962613) (xy 57.212021 -122.990769) (xy 57.092258 -123.01097) (xy 56.971413 -123.023127)
			(xy 56.850026 -123.027186) (xy 56.728639 -123.023127) (xy 56.607794 -123.01097) (xy 56.488031 -122.990769)
			(xy 56.369885 -122.962613) (xy 56.253884 -122.926629) (xy 56.140544 -122.882977) (xy 56.030374 -122.831853)
			(xy 55.923864 -122.773484) (xy 55.821491 -122.708131) (xy 55.723711 -122.636086) (xy 55.630962 -122.557672)
			(xy 55.543658 -122.473238) (xy 55.462188 -122.38316) (xy 55.386916 -122.287843) (xy 55.318179 -122.18771)
			(xy 55.256284 -122.083211) (xy 55.201507 -121.97481) (xy 55.154092 -121.862993) (xy 55.114252 -121.748258)
			(xy 55.082164 -121.631119) (xy 55.057972 -121.512098) (xy 55.041784 -121.391727) (xy 55.033671 -121.270543)
			(xy 55.033164 -121.209816) (xy 55.03366 -121.149095) (xy 55.04177 -121.027925) (xy 55.057956 -120.907567)
			(xy 55.082144 -120.788559) (xy 55.114228 -120.671432) (xy 55.154063 -120.55671) (xy 55.201472 -120.444905)
			(xy 55.256243 -120.336516) (xy 55.318131 -120.232027) (xy 55.38686 -120.131905) (xy 55.462123 -120.036598)
			(xy 55.543584 -119.946531) (xy 55.630879 -119.862105) (xy 55.723618 -119.783699) (xy 55.821386 -119.711663)
			(xy 55.923748 -119.646317) (xy 55.976774 -119.616728) (xy 55.977028 -119.616728) (xy 55.986564 -119.610739)
			(xy 55.999696 -119.59248) (xy 56.003847 -119.570375) (xy 56.001666 -119.559324) (xy 55.977282 -119.464074)
			(xy 55.973913 -119.453349) (xy 55.959575 -119.436073) (xy 55.939234 -119.426568) (xy 55.928006 -119.425974)
			(xy 50.152046 -119.425974) (xy 50.140823 -119.426563) (xy 50.120503 -119.436102) (xy 50.106144 -119.453355)
			(xy 50.10277 -119.464074) (xy 50.078386 -119.559324) (xy 50.07608 -119.570371) (xy 50.080204 -119.592529)
			(xy 50.093435 -119.610775) (xy 50.103024 -119.616728) (xy 50.103278 -119.616728) (xy 50.156289 -119.646343)
			(xy 50.258651 -119.711686) (xy 50.356421 -119.78372) (xy 50.449161 -119.862123) (xy 50.536456 -119.946547)
			(xy 50.617918 -120.036612) (xy 50.693182 -120.131917) (xy 50.761911 -120.232037) (xy 50.8238 -120.336524)
			(xy 50.878572 -120.444912) (xy 50.925981 -120.556716) (xy 50.965817 -120.671437) (xy 50.997901 -120.788563)
			(xy 51.02209 -120.90757) (xy 51.038275 -121.027926) (xy 51.046386 -121.149096) (xy 51.046888 -121.209816)
			(xy 51.046381 -121.270543) (xy 51.038268 -121.391727) (xy 51.02208 -121.512098) (xy 50.997888 -121.631119)
			(xy 50.9658 -121.748258) (xy 50.92596 -121.862993) (xy 50.878545 -121.97481) (xy 50.823768 -122.083211)
			(xy 50.761873 -122.18771) (xy 50.693136 -122.287843) (xy 50.617864 -122.38316) (xy 50.536394 -122.473238)
			(xy 50.44909 -122.557672) (xy 50.356341 -122.636086) (xy 50.258561 -122.708131) (xy 50.156188 -122.773484)
			(xy 50.049678 -122.831853) (xy 49.939508 -122.882977) (xy 49.826168 -122.926629) (xy 49.710167 -122.962613)
			(xy 49.592021 -122.990769) (xy 49.472258 -123.01097) (xy 49.351413 -123.023127) (xy 49.230026 -123.027186)
			(xy 49.108639 -123.023127) (xy 48.987794 -123.01097) (xy 48.868031 -122.990769) (xy 48.749885 -122.962613)
			(xy 48.633884 -122.926629) (xy 48.520544 -122.882977) (xy 48.410374 -122.831853) (xy 48.303864 -122.773484)
			(xy 48.201491 -122.708131) (xy 48.103711 -122.636086) (xy 48.010962 -122.557672) (xy 47.923658 -122.473238)
			(xy 47.842188 -122.38316) (xy 47.766916 -122.287843) (xy 47.698179 -122.18771) (xy 47.636284 -122.083211)
			(xy 47.581507 -121.97481) (xy 47.534092 -121.862993) (xy 47.494252 -121.748258) (xy 47.462164 -121.631119)
			(xy 47.437972 -121.512098) (xy 47.421784 -121.391727) (xy 47.413671 -121.270543) (xy 47.413164 -121.209816)
			(xy 47.41366 -121.149095) (xy 47.42177 -121.027925) (xy 47.437956 -120.907567) (xy 47.462144 -120.788559)
			(xy 47.494228 -120.671432) (xy 47.534063 -120.55671) (xy 47.581472 -120.444905) (xy 47.636243 -120.336516)
			(xy 47.698131 -120.232027) (xy 47.76686 -120.131905) (xy 47.842123 -120.036598) (xy 47.923584 -119.946531)
			(xy 48.010879 -119.862105) (xy 48.103618 -119.783699) (xy 48.201386 -119.711663) (xy 48.303748 -119.646317)
			(xy 48.356774 -119.616728) (xy 48.357028 -119.616728) (xy 48.366564 -119.610739) (xy 48.379696 -119.59248)
			(xy 48.383847 -119.570375) (xy 48.381666 -119.559324) (xy 48.357282 -119.464074) (xy 48.353913 -119.453349)
			(xy 48.339575 -119.436073) (xy 48.319234 -119.426568) (xy 48.308006 -119.425974) (xy 41.33342 -119.425974)
			(xy 41.323369 -119.42648) (xy 41.304809 -119.434201) (xy 41.297352 -119.44096) (xy 40.019986 -120.718326)
			(xy 40.013134 -120.725722) (xy 40.005396 -120.744321) (xy 40.005 -120.754394) (xy 40.005 -126.492)
			(xy 44.966872 -126.492) (xy 44.970902 -126.407397) (xy 44.982956 -126.32356) (xy 45.002925 -126.241249)
			(xy 45.030627 -126.161209) (xy 45.065812 -126.084164) (xy 45.108162 -126.010813) (xy 45.157292 -125.941819)
			(xy 45.212758 -125.877808) (xy 45.274058 -125.81936) (xy 45.340636 -125.767002) (xy 45.411889 -125.721211)
			(xy 45.487173 -125.6824) (xy 45.565805 -125.650921) (xy 45.647073 -125.627059) (xy 45.730241 -125.61103)
			(xy 45.814557 -125.60298) (xy 45.856906 -125.602492) (xy 45.857414 -125.602492) (xy 45.903746 -125.603096)
			(xy 45.995904 -125.612768) (xy 46.086558 -125.631964) (xy 46.174727 -125.660477) (xy 46.217332 -125.678692)
			(xy 46.227274 -125.682498) (xy 46.248538 -125.682498) (xy 46.25848 -125.678692) (xy 46.301082 -125.660468)
			(xy 46.38925 -125.631951) (xy 46.479906 -125.612759) (xy 46.572066 -125.6031) (xy 46.618398 -125.602492)
			(xy 46.618906 -125.602492) (xy 46.661254 -125.602996) (xy 46.745567 -125.611047) (xy 46.828733 -125.627077)
			(xy 46.909999 -125.650939) (xy 46.988629 -125.682418) (xy 47.06391 -125.721229) (xy 47.135161 -125.767019)
			(xy 47.201737 -125.819376) (xy 47.263034 -125.877823) (xy 47.318499 -125.941833) (xy 47.367627 -126.010825)
			(xy 47.409975 -126.084174) (xy 47.44516 -126.161217) (xy 47.472861 -126.241256) (xy 47.492829 -126.323565)
			(xy 47.504882 -126.407399) (xy 47.508913 -126.492) (xy 57.158872 -126.492) (xy 57.162902 -126.407397)
			(xy 57.174956 -126.32356) (xy 57.194925 -126.241249) (xy 57.222627 -126.161209) (xy 57.257812 -126.084164)
			(xy 57.300162 -126.010813) (xy 57.349292 -125.941819) (xy 57.404758 -125.877808) (xy 57.466058 -125.81936)
			(xy 57.532636 -125.767002) (xy 57.603889 -125.721211) (xy 57.679173 -125.6824) (xy 57.757805 -125.650921)
			(xy 57.839073 -125.627059) (xy 57.922241 -125.61103) (xy 58.006557 -125.60298) (xy 58.048906 -125.602492)
			(xy 58.049414 -125.602492) (xy 58.095746 -125.603096) (xy 58.187904 -125.612768) (xy 58.278558 -125.631964)
			(xy 58.366727 -125.660477) (xy 58.409332 -125.678692) (xy 58.419274 -125.682498) (xy 58.440538 -125.682498)
			(xy 58.45048 -125.678692) (xy 58.493082 -125.660468) (xy 58.58125 -125.631951) (xy 58.671906 -125.612759)
			(xy 58.764066 -125.6031) (xy 58.810398 -125.602492) (xy 58.810906 -125.602492) (xy 58.853254 -125.602996)
			(xy 58.937567 -125.611047) (xy 59.020733 -125.627077) (xy 59.101999 -125.650939) (xy 59.180629 -125.682418)
			(xy 59.25591 -125.721229) (xy 59.327161 -125.767019) (xy 59.393737 -125.819376) (xy 59.455034 -125.877823)
			(xy 59.510499 -125.941833) (xy 59.559627 -126.010825) (xy 59.601975 -126.084174) (xy 59.63716 -126.161217)
			(xy 59.664861 -126.241256) (xy 59.684829 -126.323565) (xy 59.696882 -126.407399) (xy 59.700913 -126.492)
			(xy 69.350872 -126.492) (xy 69.354902 -126.407397) (xy 69.366956 -126.32356) (xy 69.386925 -126.241249)
			(xy 69.414627 -126.161209) (xy 69.449812 -126.084164) (xy 69.492162 -126.010813) (xy 69.541292 -125.941819)
			(xy 69.596758 -125.877808) (xy 69.658058 -125.81936) (xy 69.724636 -125.767002) (xy 69.795889 -125.721211)
			(xy 69.871173 -125.6824) (xy 69.949805 -125.650921) (xy 70.031073 -125.627059) (xy 70.114241 -125.61103)
			(xy 70.198557 -125.60298) (xy 70.240906 -125.602492) (xy 70.241414 -125.602492) (xy 70.287746 -125.603096)
			(xy 70.379904 -125.612768) (xy 70.470558 -125.631964) (xy 70.558727 -125.660477) (xy 70.601332 -125.678692)
			(xy 70.611274 -125.682498) (xy 70.632538 -125.682498) (xy 70.64248 -125.678692) (xy 70.685082 -125.660468)
			(xy 70.77325 -125.631951) (xy 70.863906 -125.612759) (xy 70.956066 -125.6031) (xy 71.002398 -125.602492)
			(xy 71.002906 -125.602492) (xy 71.045254 -125.602996) (xy 71.129567 -125.611047) (xy 71.212733 -125.627077)
			(xy 71.293999 -125.650939) (xy 71.372629 -125.682418) (xy 71.44791 -125.721229) (xy 71.519161 -125.767019)
			(xy 71.585737 -125.819376) (xy 71.647034 -125.877823) (xy 71.702499 -125.941833) (xy 71.751627 -126.010825)
			(xy 71.793975 -126.084174) (xy 71.82916 -126.161217) (xy 71.856861 -126.241256) (xy 71.876829 -126.323565)
			(xy 71.888882 -126.407399) (xy 71.892913 -126.492) (xy 84.966772 -126.492) (xy 84.970802 -126.407396)
			(xy 84.982857 -126.323558) (xy 85.002826 -126.241246) (xy 85.030529 -126.161204) (xy 85.065715 -126.084159)
			(xy 85.108066 -126.010807) (xy 85.157198 -125.941813) (xy 85.212665 -125.877801) (xy 85.273966 -125.819352)
			(xy 85.340546 -125.766995) (xy 85.411801 -125.721204) (xy 85.487086 -125.682394) (xy 85.56572 -125.650916)
			(xy 85.646989 -125.627055) (xy 85.730159 -125.611028) (xy 85.814476 -125.602979) (xy 85.856826 -125.602492)
			(xy 85.857334 -125.602492) (xy 85.903665 -125.603124) (xy 85.995822 -125.612788) (xy 86.086476 -125.631976)
			(xy 86.174646 -125.66048) (xy 86.217252 -125.678692) (xy 86.227194 -125.682498) (xy 86.248458 -125.682498)
			(xy 86.2584 -125.678692) (xy 86.300999 -125.660461) (xy 86.389168 -125.631946) (xy 86.479825 -125.612756)
			(xy 86.571985 -125.603099) (xy 86.618318 -125.602492) (xy 86.618826 -125.602492) (xy 86.661174 -125.602997)
			(xy 86.745485 -125.61105) (xy 86.82865 -125.627081) (xy 86.909914 -125.650944) (xy 86.988542 -125.682424)
			(xy 87.063821 -125.721235) (xy 87.135071 -125.767026) (xy 87.201645 -125.819383) (xy 87.262941 -125.87783)
			(xy 87.318404 -125.941839) (xy 87.367531 -126.010831) (xy 87.409878 -126.08418) (xy 87.445061 -126.161222)
			(xy 87.472762 -126.241259) (xy 87.492729 -126.323567) (xy 87.504783 -126.407401) (xy 87.508813 -126.492)
			(xy 97.158772 -126.492) (xy 97.162802 -126.407396) (xy 97.174857 -126.323558) (xy 97.194826 -126.241246)
			(xy 97.222529 -126.161204) (xy 97.257715 -126.084159) (xy 97.300066 -126.010807) (xy 97.349198 -125.941813)
			(xy 97.404665 -125.877801) (xy 97.465966 -125.819352) (xy 97.532546 -125.766995) (xy 97.603801 -125.721204)
			(xy 97.679086 -125.682394) (xy 97.75772 -125.650916) (xy 97.838989 -125.627055) (xy 97.922159 -125.611028)
			(xy 98.006476 -125.602979) (xy 98.048826 -125.602492) (xy 98.049334 -125.602492) (xy 98.095665 -125.603124)
			(xy 98.187822 -125.612788) (xy 98.278476 -125.631976) (xy 98.366646 -125.66048) (xy 98.409252 -125.678692)
			(xy 98.419194 -125.682498) (xy 98.440458 -125.682498) (xy 98.4504 -125.678692) (xy 98.492999 -125.660461)
			(xy 98.581168 -125.631946) (xy 98.671825 -125.612756) (xy 98.763985 -125.603099) (xy 98.810318 -125.602492)
			(xy 98.810826 -125.602492) (xy 98.853174 -125.602997) (xy 98.937485 -125.61105) (xy 99.02065 -125.627081)
			(xy 99.101914 -125.650944) (xy 99.180542 -125.682424) (xy 99.255821 -125.721235) (xy 99.327071 -125.767026)
			(xy 99.393645 -125.819383) (xy 99.454941 -125.87783) (xy 99.510404 -125.941839) (xy 99.559531 -126.010831)
			(xy 99.601878 -126.08418) (xy 99.637061 -126.161222) (xy 99.664762 -126.241259) (xy 99.684729 -126.323567)
			(xy 99.696783 -126.407401) (xy 99.700813 -126.492) (xy 109.350772 -126.492) (xy 109.354802 -126.407396)
			(xy 109.366857 -126.323558) (xy 109.386826 -126.241246) (xy 109.414529 -126.161204) (xy 109.449715 -126.084159)
			(xy 109.492066 -126.010807) (xy 109.541198 -125.941813) (xy 109.596665 -125.877801) (xy 109.657966 -125.819352)
			(xy 109.724546 -125.766995) (xy 109.795801 -125.721204) (xy 109.871086 -125.682394) (xy 109.94972 -125.650916)
			(xy 110.030989 -125.627055) (xy 110.114159 -125.611028) (xy 110.198476 -125.602979) (xy 110.240826 -125.602492)
			(xy 110.241334 -125.602492) (xy 110.287665 -125.603124) (xy 110.379822 -125.612788) (xy 110.470476 -125.631976)
			(xy 110.558646 -125.66048) (xy 110.601252 -125.678692) (xy 110.611194 -125.682498) (xy 110.632458 -125.682498)
			(xy 110.6424 -125.678692) (xy 110.684999 -125.660461) (xy 110.773168 -125.631946) (xy 110.863825 -125.612756)
			(xy 110.955985 -125.603099) (xy 111.002318 -125.602492) (xy 111.002826 -125.602492) (xy 111.045174 -125.602997)
			(xy 111.129485 -125.61105) (xy 111.21265 -125.627081) (xy 111.293914 -125.650944) (xy 111.372542 -125.682424)
			(xy 111.447821 -125.721235) (xy 111.519071 -125.767026) (xy 111.585645 -125.819383) (xy 111.646941 -125.87783)
			(xy 111.702404 -125.941839) (xy 111.751531 -126.010831) (xy 111.793878 -126.08418) (xy 111.829061 -126.161222)
			(xy 111.856762 -126.241259) (xy 111.876729 -126.323567) (xy 111.888783 -126.407401) (xy 111.892813 -126.492)
			(xy 124.966988 -126.492) (xy 124.971018 -126.407399) (xy 124.983071 -126.323564) (xy 125.003039 -126.241255)
			(xy 125.030741 -126.161216) (xy 125.065925 -126.084173) (xy 125.108274 -126.010823) (xy 125.157403 -125.941831)
			(xy 125.212868 -125.877821) (xy 125.274166 -125.819373) (xy 125.340742 -125.767017) (xy 125.411994 -125.721227)
			(xy 125.487275 -125.682416) (xy 125.565905 -125.650937) (xy 125.647172 -125.627076) (xy 125.730338 -125.611047)
			(xy 125.814652 -125.602996) (xy 125.857 -125.602492) (xy 125.857508 -125.602492) (xy 125.90384 -125.603098)
			(xy 125.995998 -125.612769) (xy 126.086652 -125.631965) (xy 126.174821 -125.660477) (xy 126.217426 -125.678692)
			(xy 126.227368 -125.682498) (xy 126.248632 -125.682498) (xy 126.258574 -125.678692) (xy 126.301177 -125.66047)
			(xy 126.389344 -125.631952) (xy 126.48 -125.61276) (xy 126.57216 -125.6031) (xy 126.618492 -125.602492)
			(xy 126.619 -125.602492) (xy 126.661348 -125.602996) (xy 126.745662 -125.611047) (xy 126.828828 -125.627076)
			(xy 126.910095 -125.650937) (xy 126.988725 -125.682416) (xy 127.064006 -125.721227) (xy 127.135258 -125.767017)
			(xy 127.201834 -125.819373) (xy 127.263132 -125.877821) (xy 127.318597 -125.941831) (xy 127.367726 -126.010823)
			(xy 127.410075 -126.084173) (xy 127.445259 -126.161216) (xy 127.472961 -126.241255) (xy 127.492929 -126.323564)
			(xy 127.504982 -126.407399) (xy 127.509013 -126.492) (xy 137.158988 -126.492) (xy 137.163018 -126.407399)
			(xy 137.175071 -126.323564) (xy 137.195039 -126.241255) (xy 137.222741 -126.161216) (xy 137.257925 -126.084173)
			(xy 137.300274 -126.010823) (xy 137.349403 -125.941831) (xy 137.404868 -125.877821) (xy 137.466166 -125.819373)
			(xy 137.532742 -125.767017) (xy 137.603994 -125.721227) (xy 137.679275 -125.682416) (xy 137.757905 -125.650937)
			(xy 137.839172 -125.627076) (xy 137.922338 -125.611047) (xy 138.006652 -125.602996) (xy 138.049 -125.602492)
			(xy 138.049508 -125.602492) (xy 138.09584 -125.603098) (xy 138.187998 -125.612769) (xy 138.278652 -125.631965)
			(xy 138.366821 -125.660477) (xy 138.409426 -125.678692) (xy 138.419368 -125.682498) (xy 138.440632 -125.682498)
			(xy 138.450574 -125.678692) (xy 138.493177 -125.66047) (xy 138.581344 -125.631952) (xy 138.672 -125.61276)
			(xy 138.76416 -125.6031) (xy 138.810492 -125.602492) (xy 138.811 -125.602492) (xy 138.853348 -125.602996)
			(xy 138.937662 -125.611047) (xy 139.020828 -125.627076) (xy 139.102095 -125.650937) (xy 139.180725 -125.682416)
			(xy 139.256006 -125.721227) (xy 139.327258 -125.767017) (xy 139.393834 -125.819373) (xy 139.455132 -125.877821)
			(xy 139.510597 -125.941831) (xy 139.559726 -126.010823) (xy 139.602075 -126.084173) (xy 139.637259 -126.161216)
			(xy 139.664961 -126.241255) (xy 139.684929 -126.323564) (xy 139.696982 -126.407399) (xy 139.701013 -126.492)
			(xy 149.350988 -126.492) (xy 149.355018 -126.407399) (xy 149.367071 -126.323564) (xy 149.387039 -126.241255)
			(xy 149.414741 -126.161216) (xy 149.449925 -126.084173) (xy 149.492274 -126.010823) (xy 149.541403 -125.941831)
			(xy 149.596868 -125.877821) (xy 149.658166 -125.819373) (xy 149.724742 -125.767017) (xy 149.795994 -125.721227)
			(xy 149.871275 -125.682416) (xy 149.949905 -125.650937) (xy 150.031172 -125.627076) (xy 150.114338 -125.611047)
			(xy 150.198652 -125.602996) (xy 150.241 -125.602492) (xy 150.241508 -125.602492) (xy 150.28784 -125.603098)
			(xy 150.379998 -125.612769) (xy 150.470652 -125.631965) (xy 150.558821 -125.660477) (xy 150.601426 -125.678692)
			(xy 150.611368 -125.682498) (xy 150.632632 -125.682498) (xy 150.642574 -125.678692) (xy 150.685177 -125.66047)
			(xy 150.773344 -125.631952) (xy 150.864 -125.61276) (xy 150.95616 -125.6031) (xy 151.002492 -125.602492)
			(xy 151.003 -125.602492) (xy 151.045348 -125.602996) (xy 151.129662 -125.611047) (xy 151.212828 -125.627076)
			(xy 151.294095 -125.650937) (xy 151.372725 -125.682416) (xy 151.448006 -125.721227) (xy 151.519258 -125.767017)
			(xy 151.585834 -125.819373) (xy 151.647132 -125.877821) (xy 151.702597 -125.941831) (xy 151.751726 -126.010823)
			(xy 151.794075 -126.084173) (xy 151.829259 -126.161216) (xy 151.856961 -126.241255) (xy 151.876929 -126.323564)
			(xy 151.888982 -126.407399) (xy 151.893013 -126.492) (xy 164.967187 -126.492) (xy 164.971217 -126.407401)
			(xy 164.983271 -126.323567) (xy 165.003238 -126.241259) (xy 165.030939 -126.161222) (xy 165.066122 -126.08418)
			(xy 165.108469 -126.010831) (xy 165.157596 -125.941839) (xy 165.213059 -125.87783) (xy 165.274355 -125.819383)
			(xy 165.340929 -125.767026) (xy 165.412179 -125.721235) (xy 165.487458 -125.682424) (xy 165.566086 -125.650944)
			(xy 165.64735 -125.627081) (xy 165.730515 -125.61105) (xy 165.814826 -125.602997) (xy 165.857174 -125.602492)
			(xy 165.857682 -125.602492) (xy 165.904014 -125.603107) (xy 165.996171 -125.612776) (xy 166.086825 -125.631969)
			(xy 166.174994 -125.660478) (xy 166.2176 -125.678692) (xy 166.227542 -125.682498) (xy 166.248806 -125.682498)
			(xy 166.258748 -125.678692) (xy 166.301354 -125.660479) (xy 166.389521 -125.631959) (xy 166.480175 -125.612764)
			(xy 166.572334 -125.603101) (xy 166.618666 -125.602492) (xy 166.619174 -125.602492) (xy 166.661524 -125.602979)
			(xy 166.745841 -125.611028) (xy 166.829011 -125.627055) (xy 166.91028 -125.650916) (xy 166.988914 -125.682394)
			(xy 167.064199 -125.721204) (xy 167.135454 -125.766995) (xy 167.202034 -125.819352) (xy 167.263335 -125.877801)
			(xy 167.318802 -125.941813) (xy 167.367934 -126.010807) (xy 167.410285 -126.084159) (xy 167.445471 -126.161204)
			(xy 167.473174 -126.241246) (xy 167.493143 -126.323558) (xy 167.505198 -126.407396) (xy 167.509228 -126.492)
			(xy 177.159187 -126.492) (xy 177.163217 -126.407401) (xy 177.175271 -126.323567) (xy 177.195238 -126.241259)
			(xy 177.222939 -126.161222) (xy 177.258122 -126.08418) (xy 177.300469 -126.010831) (xy 177.349596 -125.941839)
			(xy 177.405059 -125.87783) (xy 177.466355 -125.819383) (xy 177.532929 -125.767026) (xy 177.604179 -125.721235)
			(xy 177.679458 -125.682424) (xy 177.758086 -125.650944) (xy 177.83935 -125.627081) (xy 177.922515 -125.61105)
			(xy 178.006826 -125.602997) (xy 178.049174 -125.602492) (xy 178.049682 -125.602492) (xy 178.096014 -125.603107)
			(xy 178.188171 -125.612776) (xy 178.278825 -125.631969) (xy 178.366994 -125.660478) (xy 178.4096 -125.678692)
			(xy 178.419542 -125.682498) (xy 178.440806 -125.682498) (xy 178.450748 -125.678692) (xy 178.493354 -125.660479)
			(xy 178.581521 -125.631959) (xy 178.672175 -125.612764) (xy 178.764334 -125.603101) (xy 178.810666 -125.602492)
			(xy 178.811174 -125.602492) (xy 178.853524 -125.602979) (xy 178.937841 -125.611028) (xy 179.021011 -125.627055)
			(xy 179.10228 -125.650916) (xy 179.180914 -125.682394) (xy 179.256199 -125.721204) (xy 179.327454 -125.766995)
			(xy 179.394034 -125.819352) (xy 179.455335 -125.877801) (xy 179.510802 -125.941813) (xy 179.559934 -126.010807)
			(xy 179.602285 -126.084159) (xy 179.637471 -126.161204) (xy 179.665174 -126.241246) (xy 179.685143 -126.323558)
			(xy 179.697198 -126.407396) (xy 179.701228 -126.492) (xy 189.351187 -126.492) (xy 189.355217 -126.407401)
			(xy 189.367271 -126.323567) (xy 189.387238 -126.241259) (xy 189.414939 -126.161222) (xy 189.450122 -126.08418)
			(xy 189.492469 -126.010831) (xy 189.541596 -125.941839) (xy 189.597059 -125.87783) (xy 189.658355 -125.819383)
			(xy 189.724929 -125.767026) (xy 189.796179 -125.721235) (xy 189.871458 -125.682424) (xy 189.950086 -125.650944)
			(xy 190.03135 -125.627081) (xy 190.114515 -125.61105) (xy 190.198826 -125.602997) (xy 190.241174 -125.602492)
			(xy 190.241682 -125.602492) (xy 190.288014 -125.603107) (xy 190.380171 -125.612776) (xy 190.470825 -125.631969)
			(xy 190.558994 -125.660478) (xy 190.6016 -125.678692) (xy 190.611542 -125.682498) (xy 190.632806 -125.682498)
			(xy 190.642748 -125.678692) (xy 190.685354 -125.660479) (xy 190.773521 -125.631959) (xy 190.864175 -125.612764)
			(xy 190.956334 -125.603101) (xy 191.002666 -125.602492) (xy 191.003174 -125.602492) (xy 191.045524 -125.602979)
			(xy 191.129841 -125.611028) (xy 191.213011 -125.627055) (xy 191.29428 -125.650916) (xy 191.372914 -125.682394)
			(xy 191.448199 -125.721204) (xy 191.519454 -125.766995) (xy 191.586034 -125.819352) (xy 191.647335 -125.877801)
			(xy 191.702802 -125.941813) (xy 191.751934 -126.010807) (xy 191.794285 -126.084159) (xy 191.829471 -126.161204)
			(xy 191.857174 -126.241246) (xy 191.877143 -126.323558) (xy 191.889198 -126.407396) (xy 191.893228 -126.492)
			(xy 191.889198 -126.576604) (xy 191.877143 -126.660442) (xy 191.857174 -126.742754) (xy 191.829471 -126.822796)
			(xy 191.794285 -126.899841) (xy 191.751934 -126.973193) (xy 191.702802 -127.042187) (xy 191.647335 -127.106199)
			(xy 191.586034 -127.164648) (xy 191.519454 -127.217005) (xy 191.448199 -127.262796) (xy 191.372914 -127.301606)
			(xy 191.29428 -127.333084) (xy 191.213011 -127.356945) (xy 191.129841 -127.372972) (xy 191.045524 -127.381021)
			(xy 191.003174 -127.381508) (xy 191.002666 -127.381508) (xy 190.956335 -127.380876) (xy 190.864178 -127.371212)
			(xy 190.773524 -127.352024) (xy 190.685354 -127.32352) (xy 190.642748 -127.305308) (xy 190.632806 -127.301502)
			(xy 190.611542 -127.301502) (xy 190.6016 -127.305308) (xy 190.559001 -127.323539) (xy 190.470832 -127.352054)
			(xy 190.380175 -127.371244) (xy 190.288015 -127.380901) (xy 190.241682 -127.381508) (xy 190.241174 -127.381508)
			(xy 190.198826 -127.381003) (xy 190.114515 -127.37295) (xy 190.03135 -127.356919) (xy 189.950086 -127.333056)
			(xy 189.871458 -127.301576) (xy 189.796179 -127.262765) (xy 189.724929 -127.216974) (xy 189.658355 -127.164617)
			(xy 189.597059 -127.10617) (xy 189.541596 -127.042161) (xy 189.492469 -126.973169) (xy 189.450122 -126.89982)
			(xy 189.414939 -126.822778) (xy 189.387238 -126.742741) (xy 189.367271 -126.660433) (xy 189.355217 -126.576599)
			(xy 189.351187 -126.492) (xy 179.701228 -126.492) (xy 179.697198 -126.576604) (xy 179.685143 -126.660442)
			(xy 179.665174 -126.742754) (xy 179.637471 -126.822796) (xy 179.602285 -126.899841) (xy 179.559934 -126.973193)
			(xy 179.510802 -127.042187) (xy 179.455335 -127.106199) (xy 179.394034 -127.164648) (xy 179.327454 -127.217005)
			(xy 179.256199 -127.262796) (xy 179.180914 -127.301606) (xy 179.10228 -127.333084) (xy 179.021011 -127.356945)
			(xy 178.937841 -127.372972) (xy 178.853524 -127.381021) (xy 178.811174 -127.381508) (xy 178.810666 -127.381508)
			(xy 178.764335 -127.380876) (xy 178.672178 -127.371212) (xy 178.581524 -127.352024) (xy 178.493354 -127.32352)
			(xy 178.450748 -127.305308) (xy 178.440806 -127.301502) (xy 178.419542 -127.301502) (xy 178.4096 -127.305308)
			(xy 178.367001 -127.323539) (xy 178.278832 -127.352054) (xy 178.188175 -127.371244) (xy 178.096015 -127.380901)
			(xy 178.049682 -127.381508) (xy 178.049174 -127.381508) (xy 178.006826 -127.381003) (xy 177.922515 -127.37295)
			(xy 177.83935 -127.356919) (xy 177.758086 -127.333056) (xy 177.679458 -127.301576) (xy 177.604179 -127.262765)
			(xy 177.532929 -127.216974) (xy 177.466355 -127.164617) (xy 177.405059 -127.10617) (xy 177.349596 -127.042161)
			(xy 177.300469 -126.973169) (xy 177.258122 -126.89982) (xy 177.222939 -126.822778) (xy 177.195238 -126.742741)
			(xy 177.175271 -126.660433) (xy 177.163217 -126.576599) (xy 177.159187 -126.492) (xy 167.509228 -126.492)
			(xy 167.505198 -126.576604) (xy 167.493143 -126.660442) (xy 167.473174 -126.742754) (xy 167.445471 -126.822796)
			(xy 167.410285 -126.899841) (xy 167.367934 -126.973193) (xy 167.318802 -127.042187) (xy 167.263335 -127.106199)
			(xy 167.202034 -127.164648) (xy 167.135454 -127.217005) (xy 167.064199 -127.262796) (xy 166.988914 -127.301606)
			(xy 166.91028 -127.333084) (xy 166.829011 -127.356945) (xy 166.745841 -127.372972) (xy 166.661524 -127.381021)
			(xy 166.619174 -127.381508) (xy 166.618666 -127.381508) (xy 166.572335 -127.380876) (xy 166.480178 -127.371212)
			(xy 166.389524 -127.352024) (xy 166.301354 -127.32352) (xy 166.258748 -127.305308) (xy 166.248806 -127.301502)
			(xy 166.227542 -127.301502) (xy 166.2176 -127.305308) (xy 166.175001 -127.323539) (xy 166.086832 -127.352054)
			(xy 165.996175 -127.371244) (xy 165.904015 -127.380901) (xy 165.857682 -127.381508) (xy 165.857174 -127.381508)
			(xy 165.814826 -127.381003) (xy 165.730515 -127.37295) (xy 165.64735 -127.356919) (xy 165.566086 -127.333056)
			(xy 165.487458 -127.301576) (xy 165.412179 -127.262765) (xy 165.340929 -127.216974) (xy 165.274355 -127.164617)
			(xy 165.213059 -127.10617) (xy 165.157596 -127.042161) (xy 165.108469 -126.973169) (xy 165.066122 -126.89982)
			(xy 165.030939 -126.822778) (xy 165.003238 -126.742741) (xy 164.983271 -126.660433) (xy 164.971217 -126.576599)
			(xy 164.967187 -126.492) (xy 151.893013 -126.492) (xy 151.888982 -126.576601) (xy 151.876929 -126.660436)
			(xy 151.856961 -126.742745) (xy 151.829259 -126.822784) (xy 151.794075 -126.899827) (xy 151.751726 -126.973177)
			(xy 151.702597 -127.042169) (xy 151.647132 -127.106179) (xy 151.585834 -127.164627) (xy 151.519258 -127.216983)
			(xy 151.448006 -127.262773) (xy 151.372725 -127.301584) (xy 151.294095 -127.333063) (xy 151.212828 -127.356924)
			(xy 151.129662 -127.372953) (xy 151.045348 -127.381004) (xy 151.003 -127.381508) (xy 151.002492 -127.381508)
			(xy 150.95616 -127.380902) (xy 150.864002 -127.371231) (xy 150.773348 -127.352035) (xy 150.685179 -127.323523)
			(xy 150.642574 -127.305308) (xy 150.632632 -127.301502) (xy 150.611368 -127.301502) (xy 150.601426 -127.305308)
			(xy 150.558823 -127.32353) (xy 150.470656 -127.352048) (xy 150.38 -127.37124) (xy 150.28784 -127.3809)
			(xy 150.241508 -127.381508) (xy 150.241 -127.381508) (xy 150.198652 -127.381004) (xy 150.114338 -127.372953)
			(xy 150.031172 -127.356924) (xy 149.949905 -127.333063) (xy 149.871275 -127.301584) (xy 149.795994 -127.262773)
			(xy 149.724742 -127.216983) (xy 149.658166 -127.164627) (xy 149.596868 -127.106179) (xy 149.541403 -127.042169)
			(xy 149.492274 -126.973177) (xy 149.449925 -126.899827) (xy 149.414741 -126.822784) (xy 149.387039 -126.742745)
			(xy 149.367071 -126.660436) (xy 149.355018 -126.576601) (xy 149.350988 -126.492) (xy 139.701013 -126.492)
			(xy 139.696982 -126.576601) (xy 139.684929 -126.660436) (xy 139.664961 -126.742745) (xy 139.637259 -126.822784)
			(xy 139.602075 -126.899827) (xy 139.559726 -126.973177) (xy 139.510597 -127.042169) (xy 139.455132 -127.106179)
			(xy 139.393834 -127.164627) (xy 139.327258 -127.216983) (xy 139.256006 -127.262773) (xy 139.180725 -127.301584)
			(xy 139.102095 -127.333063) (xy 139.020828 -127.356924) (xy 138.937662 -127.372953) (xy 138.853348 -127.381004)
			(xy 138.811 -127.381508) (xy 138.810492 -127.381508) (xy 138.76416 -127.380902) (xy 138.672002 -127.371231)
			(xy 138.581348 -127.352035) (xy 138.493179 -127.323523) (xy 138.450574 -127.305308) (xy 138.440632 -127.301502)
			(xy 138.419368 -127.301502) (xy 138.409426 -127.305308) (xy 138.366823 -127.32353) (xy 138.278656 -127.352048)
			(xy 138.188 -127.37124) (xy 138.09584 -127.3809) (xy 138.049508 -127.381508) (xy 138.049 -127.381508)
			(xy 138.006652 -127.381004) (xy 137.922338 -127.372953) (xy 137.839172 -127.356924) (xy 137.757905 -127.333063)
			(xy 137.679275 -127.301584) (xy 137.603994 -127.262773) (xy 137.532742 -127.216983) (xy 137.466166 -127.164627)
			(xy 137.404868 -127.106179) (xy 137.349403 -127.042169) (xy 137.300274 -126.973177) (xy 137.257925 -126.899827)
			(xy 137.222741 -126.822784) (xy 137.195039 -126.742745) (xy 137.175071 -126.660436) (xy 137.163018 -126.576601)
			(xy 137.158988 -126.492) (xy 127.509013 -126.492) (xy 127.504982 -126.576601) (xy 127.492929 -126.660436)
			(xy 127.472961 -126.742745) (xy 127.445259 -126.822784) (xy 127.410075 -126.899827) (xy 127.367726 -126.973177)
			(xy 127.318597 -127.042169) (xy 127.263132 -127.106179) (xy 127.201834 -127.164627) (xy 127.135258 -127.216983)
			(xy 127.064006 -127.262773) (xy 126.988725 -127.301584) (xy 126.910095 -127.333063) (xy 126.828828 -127.356924)
			(xy 126.745662 -127.372953) (xy 126.661348 -127.381004) (xy 126.619 -127.381508) (xy 126.618492 -127.381508)
			(xy 126.57216 -127.380902) (xy 126.480002 -127.371231) (xy 126.389348 -127.352035) (xy 126.301179 -127.323523)
			(xy 126.258574 -127.305308) (xy 126.248632 -127.301502) (xy 126.227368 -127.301502) (xy 126.217426 -127.305308)
			(xy 126.174823 -127.32353) (xy 126.086656 -127.352048) (xy 125.996 -127.37124) (xy 125.90384 -127.3809)
			(xy 125.857508 -127.381508) (xy 125.857 -127.381508) (xy 125.814652 -127.381004) (xy 125.730338 -127.372953)
			(xy 125.647172 -127.356924) (xy 125.565905 -127.333063) (xy 125.487275 -127.301584) (xy 125.411994 -127.262773)
			(xy 125.340742 -127.216983) (xy 125.274166 -127.164627) (xy 125.212868 -127.106179) (xy 125.157403 -127.042169)
			(xy 125.108274 -126.973177) (xy 125.065925 -126.899827) (xy 125.030741 -126.822784) (xy 125.003039 -126.742745)
			(xy 124.983071 -126.660436) (xy 124.971018 -126.576601) (xy 124.966988 -126.492) (xy 111.892813 -126.492)
			(xy 111.888783 -126.576599) (xy 111.876729 -126.660433) (xy 111.856762 -126.742741) (xy 111.829061 -126.822778)
			(xy 111.793878 -126.89982) (xy 111.751531 -126.973169) (xy 111.702404 -127.042161) (xy 111.646941 -127.10617)
			(xy 111.585645 -127.164617) (xy 111.519071 -127.216974) (xy 111.447821 -127.262765) (xy 111.372542 -127.301576)
			(xy 111.293914 -127.333056) (xy 111.21265 -127.356919) (xy 111.129485 -127.37295) (xy 111.045174 -127.381003)
			(xy 111.002826 -127.381508) (xy 111.002318 -127.381508) (xy 110.955986 -127.380893) (xy 110.863829 -127.371224)
			(xy 110.773175 -127.352031) (xy 110.685006 -127.323522) (xy 110.6424 -127.305308) (xy 110.632458 -127.301502)
			(xy 110.611194 -127.301502) (xy 110.601252 -127.305308) (xy 110.558646 -127.323521) (xy 110.470479 -127.352041)
			(xy 110.379825 -127.371236) (xy 110.287666 -127.380899) (xy 110.241334 -127.381508) (xy 110.240826 -127.381508)
			(xy 110.198476 -127.381021) (xy 110.114159 -127.372972) (xy 110.030989 -127.356945) (xy 109.94972 -127.333084)
			(xy 109.871086 -127.301606) (xy 109.795801 -127.262796) (xy 109.724546 -127.217005) (xy 109.657966 -127.164648)
			(xy 109.596665 -127.106199) (xy 109.541198 -127.042187) (xy 109.492066 -126.973193) (xy 109.449715 -126.899841)
			(xy 109.414529 -126.822796) (xy 109.386826 -126.742754) (xy 109.366857 -126.660442) (xy 109.354802 -126.576604)
			(xy 109.350772 -126.492) (xy 99.700813 -126.492) (xy 99.696783 -126.576599) (xy 99.684729 -126.660433)
			(xy 99.664762 -126.742741) (xy 99.637061 -126.822778) (xy 99.601878 -126.89982) (xy 99.559531 -126.973169)
			(xy 99.510404 -127.042161) (xy 99.454941 -127.10617) (xy 99.393645 -127.164617) (xy 99.327071 -127.216974)
			(xy 99.255821 -127.262765) (xy 99.180542 -127.301576) (xy 99.101914 -127.333056) (xy 99.02065 -127.356919)
			(xy 98.937485 -127.37295) (xy 98.853174 -127.381003) (xy 98.810826 -127.381508) (xy 98.810318 -127.381508)
			(xy 98.763986 -127.380893) (xy 98.671829 -127.371224) (xy 98.581175 -127.352031) (xy 98.493006 -127.323522)
			(xy 98.4504 -127.305308) (xy 98.440458 -127.301502) (xy 98.419194 -127.301502) (xy 98.409252 -127.305308)
			(xy 98.366646 -127.323521) (xy 98.278479 -127.352041) (xy 98.187825 -127.371236) (xy 98.095666 -127.380899)
			(xy 98.049334 -127.381508) (xy 98.048826 -127.381508) (xy 98.006476 -127.381021) (xy 97.922159 -127.372972)
			(xy 97.838989 -127.356945) (xy 97.75772 -127.333084) (xy 97.679086 -127.301606) (xy 97.603801 -127.262796)
			(xy 97.532546 -127.217005) (xy 97.465966 -127.164648) (xy 97.404665 -127.106199) (xy 97.349198 -127.042187)
			(xy 97.300066 -126.973193) (xy 97.257715 -126.899841) (xy 97.222529 -126.822796) (xy 97.194826 -126.742754)
			(xy 97.174857 -126.660442) (xy 97.162802 -126.576604) (xy 97.158772 -126.492) (xy 87.508813 -126.492)
			(xy 87.504783 -126.576599) (xy 87.492729 -126.660433) (xy 87.472762 -126.742741) (xy 87.445061 -126.822778)
			(xy 87.409878 -126.89982) (xy 87.367531 -126.973169) (xy 87.318404 -127.042161) (xy 87.262941 -127.10617)
			(xy 87.201645 -127.164617) (xy 87.135071 -127.216974) (xy 87.063821 -127.262765) (xy 86.988542 -127.301576)
			(xy 86.909914 -127.333056) (xy 86.82865 -127.356919) (xy 86.745485 -127.37295) (xy 86.661174 -127.381003)
			(xy 86.618826 -127.381508) (xy 86.618318 -127.381508) (xy 86.571986 -127.380893) (xy 86.479829 -127.371224)
			(xy 86.389175 -127.352031) (xy 86.301006 -127.323522) (xy 86.2584 -127.305308) (xy 86.248458 -127.301502)
			(xy 86.227194 -127.301502) (xy 86.217252 -127.305308) (xy 86.174646 -127.323521) (xy 86.086479 -127.352041)
			(xy 85.995825 -127.371236) (xy 85.903666 -127.380899) (xy 85.857334 -127.381508) (xy 85.856826 -127.381508)
			(xy 85.814476 -127.381021) (xy 85.730159 -127.372972) (xy 85.646989 -127.356945) (xy 85.56572 -127.333084)
			(xy 85.487086 -127.301606) (xy 85.411801 -127.262796) (xy 85.340546 -127.217005) (xy 85.273966 -127.164648)
			(xy 85.212665 -127.106199) (xy 85.157198 -127.042187) (xy 85.108066 -126.973193) (xy 85.065715 -126.899841)
			(xy 85.030529 -126.822796) (xy 85.002826 -126.742754) (xy 84.982857 -126.660442) (xy 84.970802 -126.576604)
			(xy 84.966772 -126.492) (xy 71.892913 -126.492) (xy 71.888882 -126.576601) (xy 71.876829 -126.660435)
			(xy 71.856861 -126.742744) (xy 71.82916 -126.822783) (xy 71.793975 -126.899826) (xy 71.751627 -126.973175)
			(xy 71.702499 -127.042167) (xy 71.647034 -127.106177) (xy 71.585737 -127.164624) (xy 71.519161 -127.216981)
			(xy 71.44791 -127.262771) (xy 71.372629 -127.301582) (xy 71.293999 -127.333061) (xy 71.212733 -127.356923)
			(xy 71.129567 -127.372953) (xy 71.045254 -127.381004) (xy 71.002906 -127.381508) (xy 71.002398 -127.381508)
			(xy 70.956066 -127.3809) (xy 70.863908 -127.371229) (xy 70.773254 -127.352034) (xy 70.685085 -127.323523)
			(xy 70.64248 -127.305308) (xy 70.632538 -127.301502) (xy 70.611274 -127.301502) (xy 70.601332 -127.305308)
			(xy 70.558728 -127.323528) (xy 70.470561 -127.352046) (xy 70.379906 -127.371239) (xy 70.287746 -127.3809)
			(xy 70.241414 -127.381508) (xy 70.240906 -127.381508) (xy 70.198557 -127.38102) (xy 70.114241 -127.37297)
			(xy 70.031073 -127.356941) (xy 69.949805 -127.333079) (xy 69.871173 -127.3016) (xy 69.795889 -127.262789)
			(xy 69.724636 -127.216998) (xy 69.658058 -127.16464) (xy 69.596758 -127.106192) (xy 69.541292 -127.042181)
			(xy 69.492162 -126.973187) (xy 69.449812 -126.899836) (xy 69.414627 -126.822791) (xy 69.386925 -126.742751)
			(xy 69.366956 -126.66044) (xy 69.354902 -126.576603) (xy 69.350872 -126.492) (xy 59.700913 -126.492)
			(xy 59.696882 -126.576601) (xy 59.684829 -126.660435) (xy 59.664861 -126.742744) (xy 59.63716 -126.822783)
			(xy 59.601975 -126.899826) (xy 59.559627 -126.973175) (xy 59.510499 -127.042167) (xy 59.455034 -127.106177)
			(xy 59.393737 -127.164624) (xy 59.327161 -127.216981) (xy 59.25591 -127.262771) (xy 59.180629 -127.301582)
			(xy 59.101999 -127.333061) (xy 59.020733 -127.356923) (xy 58.937567 -127.372953) (xy 58.853254 -127.381004)
			(xy 58.810906 -127.381508) (xy 58.810398 -127.381508) (xy 58.764066 -127.3809) (xy 58.671908 -127.371229)
			(xy 58.581254 -127.352034) (xy 58.493085 -127.323523) (xy 58.45048 -127.305308) (xy 58.440538 -127.301502)
			(xy 58.419274 -127.301502) (xy 58.409332 -127.305308) (xy 58.366728 -127.323528) (xy 58.278561 -127.352046)
			(xy 58.187906 -127.371239) (xy 58.095746 -127.3809) (xy 58.049414 -127.381508) (xy 58.048906 -127.381508)
			(xy 58.006557 -127.38102) (xy 57.922241 -127.37297) (xy 57.839073 -127.356941) (xy 57.757805 -127.333079)
			(xy 57.679173 -127.3016) (xy 57.603889 -127.262789) (xy 57.532636 -127.216998) (xy 57.466058 -127.16464)
			(xy 57.404758 -127.106192) (xy 57.349292 -127.042181) (xy 57.300162 -126.973187) (xy 57.257812 -126.899836)
			(xy 57.222627 -126.822791) (xy 57.194925 -126.742751) (xy 57.174956 -126.66044) (xy 57.162902 -126.576603)
			(xy 57.158872 -126.492) (xy 47.508913 -126.492) (xy 47.504882 -126.576601) (xy 47.492829 -126.660435)
			(xy 47.472861 -126.742744) (xy 47.44516 -126.822783) (xy 47.409975 -126.899826) (xy 47.367627 -126.973175)
			(xy 47.318499 -127.042167) (xy 47.263034 -127.106177) (xy 47.201737 -127.164624) (xy 47.135161 -127.216981)
			(xy 47.06391 -127.262771) (xy 46.988629 -127.301582) (xy 46.909999 -127.333061) (xy 46.828733 -127.356923)
			(xy 46.745567 -127.372953) (xy 46.661254 -127.381004) (xy 46.618906 -127.381508) (xy 46.618398 -127.381508)
			(xy 46.572066 -127.3809) (xy 46.479908 -127.371229) (xy 46.389254 -127.352034) (xy 46.301085 -127.323523)
			(xy 46.25848 -127.305308) (xy 46.248538 -127.301502) (xy 46.227274 -127.301502) (xy 46.217332 -127.305308)
			(xy 46.174728 -127.323528) (xy 46.086561 -127.352046) (xy 45.995906 -127.371239) (xy 45.903746 -127.3809)
			(xy 45.857414 -127.381508) (xy 45.856906 -127.381508) (xy 45.814557 -127.38102) (xy 45.730241 -127.37297)
			(xy 45.647073 -127.356941) (xy 45.565805 -127.333079) (xy 45.487173 -127.3016) (xy 45.411889 -127.262789)
			(xy 45.340636 -127.216998) (xy 45.274058 -127.16464) (xy 45.212758 -127.106192) (xy 45.157292 -127.042181)
			(xy 45.108162 -126.973187) (xy 45.065812 -126.899836) (xy 45.030627 -126.822791) (xy 45.002925 -126.742751)
			(xy 44.982956 -126.66044) (xy 44.970902 -126.576603) (xy 44.966872 -126.492) (xy 40.005 -126.492)
			(xy 40.005 -131.572) (xy 44.966872 -131.572) (xy 44.970902 -131.487397) (xy 44.982956 -131.40356)
			(xy 45.002925 -131.321249) (xy 45.030627 -131.241209) (xy 45.065812 -131.164164) (xy 45.108162 -131.090813)
			(xy 45.157292 -131.021819) (xy 45.212758 -130.957808) (xy 45.274058 -130.89936) (xy 45.340636 -130.847002)
			(xy 45.411889 -130.801211) (xy 45.487173 -130.7624) (xy 45.565805 -130.730921) (xy 45.647073 -130.707059)
			(xy 45.730241 -130.69103) (xy 45.814557 -130.68298) (xy 45.856906 -130.682492) (xy 45.857414 -130.682492)
			(xy 45.903746 -130.683096) (xy 45.995904 -130.692768) (xy 46.086558 -130.711964) (xy 46.174727 -130.740477)
			(xy 46.217332 -130.758692) (xy 46.227274 -130.762498) (xy 46.248538 -130.762498) (xy 46.25848 -130.758692)
			(xy 46.301082 -130.740468) (xy 46.38925 -130.711951) (xy 46.479906 -130.692759) (xy 46.572066 -130.6831)
			(xy 46.618398 -130.682492) (xy 46.618906 -130.682492) (xy 46.661254 -130.682996) (xy 46.745567 -130.691047)
			(xy 46.828733 -130.707077) (xy 46.909999 -130.730939) (xy 46.988629 -130.762418) (xy 47.06391 -130.801229)
			(xy 47.135161 -130.847019) (xy 47.201737 -130.899376) (xy 47.263034 -130.957823) (xy 47.318499 -131.021833)
			(xy 47.367627 -131.090825) (xy 47.409975 -131.164174) (xy 47.44516 -131.241217) (xy 47.472861 -131.321256)
			(xy 47.492829 -131.403565) (xy 47.504882 -131.487399) (xy 47.508913 -131.572) (xy 57.158872 -131.572)
			(xy 57.162902 -131.487397) (xy 57.174956 -131.40356) (xy 57.194925 -131.321249) (xy 57.222627 -131.241209)
			(xy 57.257812 -131.164164) (xy 57.300162 -131.090813) (xy 57.349292 -131.021819) (xy 57.404758 -130.957808)
			(xy 57.466058 -130.89936) (xy 57.532636 -130.847002) (xy 57.603889 -130.801211) (xy 57.679173 -130.7624)
			(xy 57.757805 -130.730921) (xy 57.839073 -130.707059) (xy 57.922241 -130.69103) (xy 58.006557 -130.68298)
			(xy 58.048906 -130.682492) (xy 58.049414 -130.682492) (xy 58.095746 -130.683096) (xy 58.187904 -130.692768)
			(xy 58.278558 -130.711964) (xy 58.366727 -130.740477) (xy 58.409332 -130.758692) (xy 58.419274 -130.762498)
			(xy 58.440538 -130.762498) (xy 58.45048 -130.758692) (xy 58.493082 -130.740468) (xy 58.58125 -130.711951)
			(xy 58.671906 -130.692759) (xy 58.764066 -130.6831) (xy 58.810398 -130.682492) (xy 58.810906 -130.682492)
			(xy 58.853254 -130.682996) (xy 58.937567 -130.691047) (xy 59.020733 -130.707077) (xy 59.101999 -130.730939)
			(xy 59.180629 -130.762418) (xy 59.25591 -130.801229) (xy 59.327161 -130.847019) (xy 59.393737 -130.899376)
			(xy 59.455034 -130.957823) (xy 59.510499 -131.021833) (xy 59.559627 -131.090825) (xy 59.601975 -131.164174)
			(xy 59.63716 -131.241217) (xy 59.664861 -131.321256) (xy 59.684829 -131.403565) (xy 59.696882 -131.487399)
			(xy 59.700913 -131.572) (xy 69.350872 -131.572) (xy 69.354902 -131.487397) (xy 69.366956 -131.40356)
			(xy 69.386925 -131.321249) (xy 69.414627 -131.241209) (xy 69.449812 -131.164164) (xy 69.492162 -131.090813)
			(xy 69.541292 -131.021819) (xy 69.596758 -130.957808) (xy 69.658058 -130.89936) (xy 69.724636 -130.847002)
			(xy 69.795889 -130.801211) (xy 69.871173 -130.7624) (xy 69.949805 -130.730921) (xy 70.031073 -130.707059)
			(xy 70.114241 -130.69103) (xy 70.198557 -130.68298) (xy 70.240906 -130.682492) (xy 70.241414 -130.682492)
			(xy 70.287746 -130.683096) (xy 70.379904 -130.692768) (xy 70.470558 -130.711964) (xy 70.558727 -130.740477)
			(xy 70.601332 -130.758692) (xy 70.611274 -130.762498) (xy 70.632538 -130.762498) (xy 70.64248 -130.758692)
			(xy 70.685082 -130.740468) (xy 70.77325 -130.711951) (xy 70.863906 -130.692759) (xy 70.956066 -130.6831)
			(xy 71.002398 -130.682492) (xy 71.002906 -130.682492) (xy 71.045254 -130.682996) (xy 71.129567 -130.691047)
			(xy 71.212733 -130.707077) (xy 71.293999 -130.730939) (xy 71.372629 -130.762418) (xy 71.44791 -130.801229)
			(xy 71.519161 -130.847019) (xy 71.585737 -130.899376) (xy 71.647034 -130.957823) (xy 71.702499 -131.021833)
			(xy 71.751627 -131.090825) (xy 71.793975 -131.164174) (xy 71.82916 -131.241217) (xy 71.856861 -131.321256)
			(xy 71.876829 -131.403565) (xy 71.888882 -131.487399) (xy 71.892913 -131.572) (xy 84.966772 -131.572)
			(xy 84.970802 -131.487396) (xy 84.982857 -131.403558) (xy 85.002826 -131.321246) (xy 85.030529 -131.241204)
			(xy 85.065715 -131.164159) (xy 85.108066 -131.090807) (xy 85.157198 -131.021813) (xy 85.212665 -130.957801)
			(xy 85.273966 -130.899352) (xy 85.340546 -130.846995) (xy 85.411801 -130.801204) (xy 85.487086 -130.762394)
			(xy 85.56572 -130.730916) (xy 85.646989 -130.707055) (xy 85.730159 -130.691028) (xy 85.814476 -130.682979)
			(xy 85.856826 -130.682492) (xy 85.857334 -130.682492) (xy 85.903665 -130.683124) (xy 85.995822 -130.692788)
			(xy 86.086476 -130.711976) (xy 86.174646 -130.74048) (xy 86.217252 -130.758692) (xy 86.227194 -130.762498)
			(xy 86.248458 -130.762498) (xy 86.2584 -130.758692) (xy 86.300999 -130.740461) (xy 86.389168 -130.711946)
			(xy 86.479825 -130.692756) (xy 86.571985 -130.683099) (xy 86.618318 -130.682492) (xy 86.618826 -130.682492)
			(xy 86.661174 -130.682997) (xy 86.745485 -130.69105) (xy 86.82865 -130.707081) (xy 86.909914 -130.730944)
			(xy 86.988542 -130.762424) (xy 87.063821 -130.801235) (xy 87.135071 -130.847026) (xy 87.201645 -130.899383)
			(xy 87.262941 -130.95783) (xy 87.318404 -131.021839) (xy 87.367531 -131.090831) (xy 87.409878 -131.16418)
			(xy 87.445061 -131.241222) (xy 87.472762 -131.321259) (xy 87.492729 -131.403567) (xy 87.504783 -131.487401)
			(xy 87.508813 -131.572) (xy 97.158772 -131.572) (xy 97.162802 -131.487396) (xy 97.174857 -131.403558)
			(xy 97.194826 -131.321246) (xy 97.222529 -131.241204) (xy 97.257715 -131.164159) (xy 97.300066 -131.090807)
			(xy 97.349198 -131.021813) (xy 97.404665 -130.957801) (xy 97.465966 -130.899352) (xy 97.532546 -130.846995)
			(xy 97.603801 -130.801204) (xy 97.679086 -130.762394) (xy 97.75772 -130.730916) (xy 97.838989 -130.707055)
			(xy 97.922159 -130.691028) (xy 98.006476 -130.682979) (xy 98.048826 -130.682492) (xy 98.049334 -130.682492)
			(xy 98.095665 -130.683124) (xy 98.187822 -130.692788) (xy 98.278476 -130.711976) (xy 98.366646 -130.74048)
			(xy 98.409252 -130.758692) (xy 98.419194 -130.762498) (xy 98.440458 -130.762498) (xy 98.4504 -130.758692)
			(xy 98.492999 -130.740461) (xy 98.581168 -130.711946) (xy 98.671825 -130.692756) (xy 98.763985 -130.683099)
			(xy 98.810318 -130.682492) (xy 98.810826 -130.682492) (xy 98.853174 -130.682997) (xy 98.937485 -130.69105)
			(xy 99.02065 -130.707081) (xy 99.101914 -130.730944) (xy 99.180542 -130.762424) (xy 99.255821 -130.801235)
			(xy 99.327071 -130.847026) (xy 99.393645 -130.899383) (xy 99.454941 -130.95783) (xy 99.510404 -131.021839)
			(xy 99.559531 -131.090831) (xy 99.601878 -131.16418) (xy 99.637061 -131.241222) (xy 99.664762 -131.321259)
			(xy 99.684729 -131.403567) (xy 99.696783 -131.487401) (xy 99.700813 -131.572) (xy 109.350772 -131.572)
			(xy 109.354802 -131.487396) (xy 109.366857 -131.403558) (xy 109.386826 -131.321246) (xy 109.414529 -131.241204)
			(xy 109.449715 -131.164159) (xy 109.492066 -131.090807) (xy 109.541198 -131.021813) (xy 109.596665 -130.957801)
			(xy 109.657966 -130.899352) (xy 109.724546 -130.846995) (xy 109.795801 -130.801204) (xy 109.871086 -130.762394)
			(xy 109.94972 -130.730916) (xy 110.030989 -130.707055) (xy 110.114159 -130.691028) (xy 110.198476 -130.682979)
			(xy 110.240826 -130.682492) (xy 110.241334 -130.682492) (xy 110.287665 -130.683124) (xy 110.379822 -130.692788)
			(xy 110.470476 -130.711976) (xy 110.558646 -130.74048) (xy 110.601252 -130.758692) (xy 110.611194 -130.762498)
			(xy 110.632458 -130.762498) (xy 110.6424 -130.758692) (xy 110.684999 -130.740461) (xy 110.773168 -130.711946)
			(xy 110.863825 -130.692756) (xy 110.955985 -130.683099) (xy 111.002318 -130.682492) (xy 111.002826 -130.682492)
			(xy 111.045174 -130.682997) (xy 111.129485 -130.69105) (xy 111.21265 -130.707081) (xy 111.293914 -130.730944)
			(xy 111.372542 -130.762424) (xy 111.447821 -130.801235) (xy 111.519071 -130.847026) (xy 111.585645 -130.899383)
			(xy 111.646941 -130.95783) (xy 111.702404 -131.021839) (xy 111.751531 -131.090831) (xy 111.793878 -131.16418)
			(xy 111.829061 -131.241222) (xy 111.856762 -131.321259) (xy 111.876729 -131.403567) (xy 111.888783 -131.487401)
			(xy 111.892813 -131.572) (xy 124.966988 -131.572) (xy 124.971018 -131.487399) (xy 124.983071 -131.403564)
			(xy 125.003039 -131.321255) (xy 125.030741 -131.241216) (xy 125.065925 -131.164173) (xy 125.108274 -131.090823)
			(xy 125.157403 -131.021831) (xy 125.212868 -130.957821) (xy 125.274166 -130.899373) (xy 125.340742 -130.847017)
			(xy 125.411994 -130.801227) (xy 125.487275 -130.762416) (xy 125.565905 -130.730937) (xy 125.647172 -130.707076)
			(xy 125.730338 -130.691047) (xy 125.814652 -130.682996) (xy 125.857 -130.682492) (xy 125.857508 -130.682492)
			(xy 125.90384 -130.683098) (xy 125.995998 -130.692769) (xy 126.086652 -130.711965) (xy 126.174821 -130.740477)
			(xy 126.217426 -130.758692) (xy 126.227368 -130.762498) (xy 126.248632 -130.762498) (xy 126.258574 -130.758692)
			(xy 126.301177 -130.74047) (xy 126.389344 -130.711952) (xy 126.48 -130.69276) (xy 126.57216 -130.6831)
			(xy 126.618492 -130.682492) (xy 126.619 -130.682492) (xy 126.661348 -130.682996) (xy 126.745662 -130.691047)
			(xy 126.828828 -130.707076) (xy 126.910095 -130.730937) (xy 126.988725 -130.762416) (xy 127.064006 -130.801227)
			(xy 127.135258 -130.847017) (xy 127.201834 -130.899373) (xy 127.263132 -130.957821) (xy 127.318597 -131.021831)
			(xy 127.367726 -131.090823) (xy 127.410075 -131.164173) (xy 127.445259 -131.241216) (xy 127.472961 -131.321255)
			(xy 127.492929 -131.403564) (xy 127.504982 -131.487399) (xy 127.509013 -131.572) (xy 137.158988 -131.572)
			(xy 137.163018 -131.487399) (xy 137.175071 -131.403564) (xy 137.195039 -131.321255) (xy 137.222741 -131.241216)
			(xy 137.257925 -131.164173) (xy 137.300274 -131.090823) (xy 137.349403 -131.021831) (xy 137.404868 -130.957821)
			(xy 137.466166 -130.899373) (xy 137.532742 -130.847017) (xy 137.603994 -130.801227) (xy 137.679275 -130.762416)
			(xy 137.757905 -130.730937) (xy 137.839172 -130.707076) (xy 137.922338 -130.691047) (xy 138.006652 -130.682996)
			(xy 138.049 -130.682492) (xy 138.049508 -130.682492) (xy 138.09584 -130.683098) (xy 138.187998 -130.692769)
			(xy 138.278652 -130.711965) (xy 138.366821 -130.740477) (xy 138.409426 -130.758692) (xy 138.419368 -130.762498)
			(xy 138.440632 -130.762498) (xy 138.450574 -130.758692) (xy 138.493177 -130.74047) (xy 138.581344 -130.711952)
			(xy 138.672 -130.69276) (xy 138.76416 -130.6831) (xy 138.810492 -130.682492) (xy 138.811 -130.682492)
			(xy 138.853348 -130.682996) (xy 138.937662 -130.691047) (xy 139.020828 -130.707076) (xy 139.102095 -130.730937)
			(xy 139.180725 -130.762416) (xy 139.256006 -130.801227) (xy 139.327258 -130.847017) (xy 139.393834 -130.899373)
			(xy 139.455132 -130.957821) (xy 139.510597 -131.021831) (xy 139.559726 -131.090823) (xy 139.602075 -131.164173)
			(xy 139.637259 -131.241216) (xy 139.664961 -131.321255) (xy 139.684929 -131.403564) (xy 139.696982 -131.487399)
			(xy 139.701013 -131.572) (xy 149.350988 -131.572) (xy 149.355018 -131.487399) (xy 149.367071 -131.403564)
			(xy 149.387039 -131.321255) (xy 149.414741 -131.241216) (xy 149.449925 -131.164173) (xy 149.492274 -131.090823)
			(xy 149.541403 -131.021831) (xy 149.596868 -130.957821) (xy 149.658166 -130.899373) (xy 149.724742 -130.847017)
			(xy 149.795994 -130.801227) (xy 149.871275 -130.762416) (xy 149.949905 -130.730937) (xy 150.031172 -130.707076)
			(xy 150.114338 -130.691047) (xy 150.198652 -130.682996) (xy 150.241 -130.682492) (xy 150.241508 -130.682492)
			(xy 150.28784 -130.683098) (xy 150.379998 -130.692769) (xy 150.470652 -130.711965) (xy 150.558821 -130.740477)
			(xy 150.601426 -130.758692) (xy 150.611368 -130.762498) (xy 150.632632 -130.762498) (xy 150.642574 -130.758692)
			(xy 150.685177 -130.74047) (xy 150.773344 -130.711952) (xy 150.864 -130.69276) (xy 150.95616 -130.6831)
			(xy 151.002492 -130.682492) (xy 151.003 -130.682492) (xy 151.045348 -130.682996) (xy 151.129662 -130.691047)
			(xy 151.212828 -130.707076) (xy 151.294095 -130.730937) (xy 151.372725 -130.762416) (xy 151.448006 -130.801227)
			(xy 151.519258 -130.847017) (xy 151.585834 -130.899373) (xy 151.647132 -130.957821) (xy 151.702597 -131.021831)
			(xy 151.751726 -131.090823) (xy 151.794075 -131.164173) (xy 151.829259 -131.241216) (xy 151.856961 -131.321255)
			(xy 151.876929 -131.403564) (xy 151.888982 -131.487399) (xy 151.893013 -131.572) (xy 164.967187 -131.572)
			(xy 164.971217 -131.487401) (xy 164.983271 -131.403567) (xy 165.003238 -131.321259) (xy 165.030939 -131.241222)
			(xy 165.066122 -131.16418) (xy 165.108469 -131.090831) (xy 165.157596 -131.021839) (xy 165.213059 -130.95783)
			(xy 165.274355 -130.899383) (xy 165.340929 -130.847026) (xy 165.412179 -130.801235) (xy 165.487458 -130.762424)
			(xy 165.566086 -130.730944) (xy 165.64735 -130.707081) (xy 165.730515 -130.69105) (xy 165.814826 -130.682997)
			(xy 165.857174 -130.682492) (xy 165.857682 -130.682492) (xy 165.904014 -130.683107) (xy 165.996171 -130.692776)
			(xy 166.086825 -130.711969) (xy 166.174994 -130.740478) (xy 166.2176 -130.758692) (xy 166.227542 -130.762498)
			(xy 166.248806 -130.762498) (xy 166.258748 -130.758692) (xy 166.301354 -130.740479) (xy 166.389521 -130.711959)
			(xy 166.480175 -130.692764) (xy 166.572334 -130.683101) (xy 166.618666 -130.682492) (xy 166.619174 -130.682492)
			(xy 166.661524 -130.682979) (xy 166.745841 -130.691028) (xy 166.829011 -130.707055) (xy 166.91028 -130.730916)
			(xy 166.988914 -130.762394) (xy 167.064199 -130.801204) (xy 167.135454 -130.846995) (xy 167.202034 -130.899352)
			(xy 167.263335 -130.957801) (xy 167.318802 -131.021813) (xy 167.367934 -131.090807) (xy 167.410285 -131.164159)
			(xy 167.445471 -131.241204) (xy 167.473174 -131.321246) (xy 167.493143 -131.403558) (xy 167.505198 -131.487396)
			(xy 167.509228 -131.572) (xy 177.159187 -131.572) (xy 177.163217 -131.487401) (xy 177.175271 -131.403567)
			(xy 177.195238 -131.321259) (xy 177.222939 -131.241222) (xy 177.258122 -131.16418) (xy 177.300469 -131.090831)
			(xy 177.349596 -131.021839) (xy 177.405059 -130.95783) (xy 177.466355 -130.899383) (xy 177.532929 -130.847026)
			(xy 177.604179 -130.801235) (xy 177.679458 -130.762424) (xy 177.758086 -130.730944) (xy 177.83935 -130.707081)
			(xy 177.922515 -130.69105) (xy 178.006826 -130.682997) (xy 178.049174 -130.682492) (xy 178.049682 -130.682492)
			(xy 178.096014 -130.683107) (xy 178.188171 -130.692776) (xy 178.278825 -130.711969) (xy 178.366994 -130.740478)
			(xy 178.4096 -130.758692) (xy 178.419542 -130.762498) (xy 178.440806 -130.762498) (xy 178.450748 -130.758692)
			(xy 178.493354 -130.740479) (xy 178.581521 -130.711959) (xy 178.672175 -130.692764) (xy 178.764334 -130.683101)
			(xy 178.810666 -130.682492) (xy 178.811174 -130.682492) (xy 178.853524 -130.682979) (xy 178.937841 -130.691028)
			(xy 179.021011 -130.707055) (xy 179.10228 -130.730916) (xy 179.180914 -130.762394) (xy 179.256199 -130.801204)
			(xy 179.327454 -130.846995) (xy 179.394034 -130.899352) (xy 179.455335 -130.957801) (xy 179.510802 -131.021813)
			(xy 179.559934 -131.090807) (xy 179.602285 -131.164159) (xy 179.637471 -131.241204) (xy 179.665174 -131.321246)
			(xy 179.685143 -131.403558) (xy 179.697198 -131.487396) (xy 179.701228 -131.572) (xy 189.351187 -131.572)
			(xy 189.355217 -131.487401) (xy 189.367271 -131.403567) (xy 189.387238 -131.321259) (xy 189.414939 -131.241222)
			(xy 189.450122 -131.16418) (xy 189.492469 -131.090831) (xy 189.541596 -131.021839) (xy 189.597059 -130.95783)
			(xy 189.658355 -130.899383) (xy 189.724929 -130.847026) (xy 189.796179 -130.801235) (xy 189.871458 -130.762424)
			(xy 189.950086 -130.730944) (xy 190.03135 -130.707081) (xy 190.114515 -130.69105) (xy 190.198826 -130.682997)
			(xy 190.241174 -130.682492) (xy 190.241682 -130.682492) (xy 190.288014 -130.683107) (xy 190.380171 -130.692776)
			(xy 190.470825 -130.711969) (xy 190.558994 -130.740478) (xy 190.6016 -130.758692) (xy 190.611542 -130.762498)
			(xy 190.632806 -130.762498) (xy 190.642748 -130.758692) (xy 190.685354 -130.740479) (xy 190.773521 -130.711959)
			(xy 190.864175 -130.692764) (xy 190.956334 -130.683101) (xy 191.002666 -130.682492) (xy 191.003174 -130.682492)
			(xy 191.045524 -130.682979) (xy 191.129841 -130.691028) (xy 191.213011 -130.707055) (xy 191.29428 -130.730916)
			(xy 191.372914 -130.762394) (xy 191.448199 -130.801204) (xy 191.519454 -130.846995) (xy 191.586034 -130.899352)
			(xy 191.647335 -130.957801) (xy 191.702802 -131.021813) (xy 191.751934 -131.090807) (xy 191.794285 -131.164159)
			(xy 191.829471 -131.241204) (xy 191.857174 -131.321246) (xy 191.877143 -131.403558) (xy 191.889198 -131.487396)
			(xy 191.893228 -131.572) (xy 191.889198 -131.656604) (xy 191.877143 -131.740442) (xy 191.857174 -131.822754)
			(xy 191.829471 -131.902796) (xy 191.794285 -131.979841) (xy 191.751934 -132.053193) (xy 191.702802 -132.122187)
			(xy 191.647335 -132.186199) (xy 191.586034 -132.244648) (xy 191.519454 -132.297005) (xy 191.448199 -132.342796)
			(xy 191.372914 -132.381606) (xy 191.29428 -132.413084) (xy 191.213011 -132.436945) (xy 191.129841 -132.452972)
			(xy 191.045524 -132.461021) (xy 191.003174 -132.461508) (xy 191.002666 -132.461508) (xy 190.956335 -132.460876)
			(xy 190.864178 -132.451212) (xy 190.773524 -132.432024) (xy 190.685354 -132.40352) (xy 190.642748 -132.385308)
			(xy 190.632806 -132.381502) (xy 190.611542 -132.381502) (xy 190.6016 -132.385308) (xy 190.559001 -132.403539)
			(xy 190.470832 -132.432054) (xy 190.380175 -132.451244) (xy 190.288015 -132.460901) (xy 190.241682 -132.461508)
			(xy 190.241174 -132.461508) (xy 190.198826 -132.461003) (xy 190.114515 -132.45295) (xy 190.03135 -132.436919)
			(xy 189.950086 -132.413056) (xy 189.871458 -132.381576) (xy 189.796179 -132.342765) (xy 189.724929 -132.296974)
			(xy 189.658355 -132.244617) (xy 189.597059 -132.18617) (xy 189.541596 -132.122161) (xy 189.492469 -132.053169)
			(xy 189.450122 -131.97982) (xy 189.414939 -131.902778) (xy 189.387238 -131.822741) (xy 189.367271 -131.740433)
			(xy 189.355217 -131.656599) (xy 189.351187 -131.572) (xy 179.701228 -131.572) (xy 179.697198 -131.656604)
			(xy 179.685143 -131.740442) (xy 179.665174 -131.822754) (xy 179.637471 -131.902796) (xy 179.602285 -131.979841)
			(xy 179.559934 -132.053193) (xy 179.510802 -132.122187) (xy 179.455335 -132.186199) (xy 179.394034 -132.244648)
			(xy 179.327454 -132.297005) (xy 179.256199 -132.342796) (xy 179.180914 -132.381606) (xy 179.10228 -132.413084)
			(xy 179.021011 -132.436945) (xy 178.937841 -132.452972) (xy 178.853524 -132.461021) (xy 178.811174 -132.461508)
			(xy 178.810666 -132.461508) (xy 178.764335 -132.460876) (xy 178.672178 -132.451212) (xy 178.581524 -132.432024)
			(xy 178.493354 -132.40352) (xy 178.450748 -132.385308) (xy 178.440806 -132.381502) (xy 178.419542 -132.381502)
			(xy 178.4096 -132.385308) (xy 178.367001 -132.403539) (xy 178.278832 -132.432054) (xy 178.188175 -132.451244)
			(xy 178.096015 -132.460901) (xy 178.049682 -132.461508) (xy 178.049174 -132.461508) (xy 178.006826 -132.461003)
			(xy 177.922515 -132.45295) (xy 177.83935 -132.436919) (xy 177.758086 -132.413056) (xy 177.679458 -132.381576)
			(xy 177.604179 -132.342765) (xy 177.532929 -132.296974) (xy 177.466355 -132.244617) (xy 177.405059 -132.18617)
			(xy 177.349596 -132.122161) (xy 177.300469 -132.053169) (xy 177.258122 -131.97982) (xy 177.222939 -131.902778)
			(xy 177.195238 -131.822741) (xy 177.175271 -131.740433) (xy 177.163217 -131.656599) (xy 177.159187 -131.572)
			(xy 167.509228 -131.572) (xy 167.505198 -131.656604) (xy 167.493143 -131.740442) (xy 167.473174 -131.822754)
			(xy 167.445471 -131.902796) (xy 167.410285 -131.979841) (xy 167.367934 -132.053193) (xy 167.318802 -132.122187)
			(xy 167.263335 -132.186199) (xy 167.202034 -132.244648) (xy 167.135454 -132.297005) (xy 167.064199 -132.342796)
			(xy 166.988914 -132.381606) (xy 166.91028 -132.413084) (xy 166.829011 -132.436945) (xy 166.745841 -132.452972)
			(xy 166.661524 -132.461021) (xy 166.619174 -132.461508) (xy 166.618666 -132.461508) (xy 166.572335 -132.460876)
			(xy 166.480178 -132.451212) (xy 166.389524 -132.432024) (xy 166.301354 -132.40352) (xy 166.258748 -132.385308)
			(xy 166.248806 -132.381502) (xy 166.227542 -132.381502) (xy 166.2176 -132.385308) (xy 166.175001 -132.403539)
			(xy 166.086832 -132.432054) (xy 165.996175 -132.451244) (xy 165.904015 -132.460901) (xy 165.857682 -132.461508)
			(xy 165.857174 -132.461508) (xy 165.814826 -132.461003) (xy 165.730515 -132.45295) (xy 165.64735 -132.436919)
			(xy 165.566086 -132.413056) (xy 165.487458 -132.381576) (xy 165.412179 -132.342765) (xy 165.340929 -132.296974)
			(xy 165.274355 -132.244617) (xy 165.213059 -132.18617) (xy 165.157596 -132.122161) (xy 165.108469 -132.053169)
			(xy 165.066122 -131.97982) (xy 165.030939 -131.902778) (xy 165.003238 -131.822741) (xy 164.983271 -131.740433)
			(xy 164.971217 -131.656599) (xy 164.967187 -131.572) (xy 151.893013 -131.572) (xy 151.888982 -131.656601)
			(xy 151.876929 -131.740436) (xy 151.856961 -131.822745) (xy 151.829259 -131.902784) (xy 151.794075 -131.979827)
			(xy 151.751726 -132.053177) (xy 151.702597 -132.122169) (xy 151.647132 -132.186179) (xy 151.585834 -132.244627)
			(xy 151.519258 -132.296983) (xy 151.448006 -132.342773) (xy 151.372725 -132.381584) (xy 151.294095 -132.413063)
			(xy 151.212828 -132.436924) (xy 151.129662 -132.452953) (xy 151.045348 -132.461004) (xy 151.003 -132.461508)
			(xy 151.002492 -132.461508) (xy 150.95616 -132.460902) (xy 150.864002 -132.451231) (xy 150.773348 -132.432035)
			(xy 150.685179 -132.403523) (xy 150.642574 -132.385308) (xy 150.632632 -132.381502) (xy 150.611368 -132.381502)
			(xy 150.601426 -132.385308) (xy 150.558823 -132.40353) (xy 150.470656 -132.432048) (xy 150.38 -132.45124)
			(xy 150.28784 -132.4609) (xy 150.241508 -132.461508) (xy 150.241 -132.461508) (xy 150.198652 -132.461004)
			(xy 150.114338 -132.452953) (xy 150.031172 -132.436924) (xy 149.949905 -132.413063) (xy 149.871275 -132.381584)
			(xy 149.795994 -132.342773) (xy 149.724742 -132.296983) (xy 149.658166 -132.244627) (xy 149.596868 -132.186179)
			(xy 149.541403 -132.122169) (xy 149.492274 -132.053177) (xy 149.449925 -131.979827) (xy 149.414741 -131.902784)
			(xy 149.387039 -131.822745) (xy 149.367071 -131.740436) (xy 149.355018 -131.656601) (xy 149.350988 -131.572)
			(xy 139.701013 -131.572) (xy 139.696982 -131.656601) (xy 139.684929 -131.740436) (xy 139.664961 -131.822745)
			(xy 139.637259 -131.902784) (xy 139.602075 -131.979827) (xy 139.559726 -132.053177) (xy 139.510597 -132.122169)
			(xy 139.455132 -132.186179) (xy 139.393834 -132.244627) (xy 139.327258 -132.296983) (xy 139.256006 -132.342773)
			(xy 139.180725 -132.381584) (xy 139.102095 -132.413063) (xy 139.020828 -132.436924) (xy 138.937662 -132.452953)
			(xy 138.853348 -132.461004) (xy 138.811 -132.461508) (xy 138.810492 -132.461508) (xy 138.76416 -132.460902)
			(xy 138.672002 -132.451231) (xy 138.581348 -132.432035) (xy 138.493179 -132.403523) (xy 138.450574 -132.385308)
			(xy 138.440632 -132.381502) (xy 138.419368 -132.381502) (xy 138.409426 -132.385308) (xy 138.366823 -132.40353)
			(xy 138.278656 -132.432048) (xy 138.188 -132.45124) (xy 138.09584 -132.4609) (xy 138.049508 -132.461508)
			(xy 138.049 -132.461508) (xy 138.006652 -132.461004) (xy 137.922338 -132.452953) (xy 137.839172 -132.436924)
			(xy 137.757905 -132.413063) (xy 137.679275 -132.381584) (xy 137.603994 -132.342773) (xy 137.532742 -132.296983)
			(xy 137.466166 -132.244627) (xy 137.404868 -132.186179) (xy 137.349403 -132.122169) (xy 137.300274 -132.053177)
			(xy 137.257925 -131.979827) (xy 137.222741 -131.902784) (xy 137.195039 -131.822745) (xy 137.175071 -131.740436)
			(xy 137.163018 -131.656601) (xy 137.158988 -131.572) (xy 127.509013 -131.572) (xy 127.504982 -131.656601)
			(xy 127.492929 -131.740436) (xy 127.472961 -131.822745) (xy 127.445259 -131.902784) (xy 127.410075 -131.979827)
			(xy 127.367726 -132.053177) (xy 127.318597 -132.122169) (xy 127.263132 -132.186179) (xy 127.201834 -132.244627)
			(xy 127.135258 -132.296983) (xy 127.064006 -132.342773) (xy 126.988725 -132.381584) (xy 126.910095 -132.413063)
			(xy 126.828828 -132.436924) (xy 126.745662 -132.452953) (xy 126.661348 -132.461004) (xy 126.619 -132.461508)
			(xy 126.618492 -132.461508) (xy 126.57216 -132.460902) (xy 126.480002 -132.451231) (xy 126.389348 -132.432035)
			(xy 126.301179 -132.403523) (xy 126.258574 -132.385308) (xy 126.248632 -132.381502) (xy 126.227368 -132.381502)
			(xy 126.217426 -132.385308) (xy 126.174823 -132.40353) (xy 126.086656 -132.432048) (xy 125.996 -132.45124)
			(xy 125.90384 -132.4609) (xy 125.857508 -132.461508) (xy 125.857 -132.461508) (xy 125.814652 -132.461004)
			(xy 125.730338 -132.452953) (xy 125.647172 -132.436924) (xy 125.565905 -132.413063) (xy 125.487275 -132.381584)
			(xy 125.411994 -132.342773) (xy 125.340742 -132.296983) (xy 125.274166 -132.244627) (xy 125.212868 -132.186179)
			(xy 125.157403 -132.122169) (xy 125.108274 -132.053177) (xy 125.065925 -131.979827) (xy 125.030741 -131.902784)
			(xy 125.003039 -131.822745) (xy 124.983071 -131.740436) (xy 124.971018 -131.656601) (xy 124.966988 -131.572)
			(xy 111.892813 -131.572) (xy 111.888783 -131.656599) (xy 111.876729 -131.740433) (xy 111.856762 -131.822741)
			(xy 111.829061 -131.902778) (xy 111.793878 -131.97982) (xy 111.751531 -132.053169) (xy 111.702404 -132.122161)
			(xy 111.646941 -132.18617) (xy 111.585645 -132.244617) (xy 111.519071 -132.296974) (xy 111.447821 -132.342765)
			(xy 111.372542 -132.381576) (xy 111.293914 -132.413056) (xy 111.21265 -132.436919) (xy 111.129485 -132.45295)
			(xy 111.045174 -132.461003) (xy 111.002826 -132.461508) (xy 111.002318 -132.461508) (xy 110.955986 -132.460893)
			(xy 110.863829 -132.451224) (xy 110.773175 -132.432031) (xy 110.685006 -132.403522) (xy 110.6424 -132.385308)
			(xy 110.632458 -132.381502) (xy 110.611194 -132.381502) (xy 110.601252 -132.385308) (xy 110.558646 -132.403521)
			(xy 110.470479 -132.432041) (xy 110.379825 -132.451236) (xy 110.287666 -132.460899) (xy 110.241334 -132.461508)
			(xy 110.240826 -132.461508) (xy 110.198476 -132.461021) (xy 110.114159 -132.452972) (xy 110.030989 -132.436945)
			(xy 109.94972 -132.413084) (xy 109.871086 -132.381606) (xy 109.795801 -132.342796) (xy 109.724546 -132.297005)
			(xy 109.657966 -132.244648) (xy 109.596665 -132.186199) (xy 109.541198 -132.122187) (xy 109.492066 -132.053193)
			(xy 109.449715 -131.979841) (xy 109.414529 -131.902796) (xy 109.386826 -131.822754) (xy 109.366857 -131.740442)
			(xy 109.354802 -131.656604) (xy 109.350772 -131.572) (xy 99.700813 -131.572) (xy 99.696783 -131.656599)
			(xy 99.684729 -131.740433) (xy 99.664762 -131.822741) (xy 99.637061 -131.902778) (xy 99.601878 -131.97982)
			(xy 99.559531 -132.053169) (xy 99.510404 -132.122161) (xy 99.454941 -132.18617) (xy 99.393645 -132.244617)
			(xy 99.327071 -132.296974) (xy 99.255821 -132.342765) (xy 99.180542 -132.381576) (xy 99.101914 -132.413056)
			(xy 99.02065 -132.436919) (xy 98.937485 -132.45295) (xy 98.853174 -132.461003) (xy 98.810826 -132.461508)
			(xy 98.810318 -132.461508) (xy 98.763986 -132.460893) (xy 98.671829 -132.451224) (xy 98.581175 -132.432031)
			(xy 98.493006 -132.403522) (xy 98.4504 -132.385308) (xy 98.440458 -132.381502) (xy 98.419194 -132.381502)
			(xy 98.409252 -132.385308) (xy 98.366646 -132.403521) (xy 98.278479 -132.432041) (xy 98.187825 -132.451236)
			(xy 98.095666 -132.460899) (xy 98.049334 -132.461508) (xy 98.048826 -132.461508) (xy 98.006476 -132.461021)
			(xy 97.922159 -132.452972) (xy 97.838989 -132.436945) (xy 97.75772 -132.413084) (xy 97.679086 -132.381606)
			(xy 97.603801 -132.342796) (xy 97.532546 -132.297005) (xy 97.465966 -132.244648) (xy 97.404665 -132.186199)
			(xy 97.349198 -132.122187) (xy 97.300066 -132.053193) (xy 97.257715 -131.979841) (xy 97.222529 -131.902796)
			(xy 97.194826 -131.822754) (xy 97.174857 -131.740442) (xy 97.162802 -131.656604) (xy 97.158772 -131.572)
			(xy 87.508813 -131.572) (xy 87.504783 -131.656599) (xy 87.492729 -131.740433) (xy 87.472762 -131.822741)
			(xy 87.445061 -131.902778) (xy 87.409878 -131.97982) (xy 87.367531 -132.053169) (xy 87.318404 -132.122161)
			(xy 87.262941 -132.18617) (xy 87.201645 -132.244617) (xy 87.135071 -132.296974) (xy 87.063821 -132.342765)
			(xy 86.988542 -132.381576) (xy 86.909914 -132.413056) (xy 86.82865 -132.436919) (xy 86.745485 -132.45295)
			(xy 86.661174 -132.461003) (xy 86.618826 -132.461508) (xy 86.618318 -132.461508) (xy 86.571986 -132.460893)
			(xy 86.479829 -132.451224) (xy 86.389175 -132.432031) (xy 86.301006 -132.403522) (xy 86.2584 -132.385308)
			(xy 86.248458 -132.381502) (xy 86.227194 -132.381502) (xy 86.217252 -132.385308) (xy 86.174646 -132.403521)
			(xy 86.086479 -132.432041) (xy 85.995825 -132.451236) (xy 85.903666 -132.460899) (xy 85.857334 -132.461508)
			(xy 85.856826 -132.461508) (xy 85.814476 -132.461021) (xy 85.730159 -132.452972) (xy 85.646989 -132.436945)
			(xy 85.56572 -132.413084) (xy 85.487086 -132.381606) (xy 85.411801 -132.342796) (xy 85.340546 -132.297005)
			(xy 85.273966 -132.244648) (xy 85.212665 -132.186199) (xy 85.157198 -132.122187) (xy 85.108066 -132.053193)
			(xy 85.065715 -131.979841) (xy 85.030529 -131.902796) (xy 85.002826 -131.822754) (xy 84.982857 -131.740442)
			(xy 84.970802 -131.656604) (xy 84.966772 -131.572) (xy 71.892913 -131.572) (xy 71.888882 -131.656601)
			(xy 71.876829 -131.740435) (xy 71.856861 -131.822744) (xy 71.82916 -131.902783) (xy 71.793975 -131.979826)
			(xy 71.751627 -132.053175) (xy 71.702499 -132.122167) (xy 71.647034 -132.186177) (xy 71.585737 -132.244624)
			(xy 71.519161 -132.296981) (xy 71.44791 -132.342771) (xy 71.372629 -132.381582) (xy 71.293999 -132.413061)
			(xy 71.212733 -132.436923) (xy 71.129567 -132.452953) (xy 71.045254 -132.461004) (xy 71.002906 -132.461508)
			(xy 71.002398 -132.461508) (xy 70.956066 -132.4609) (xy 70.863908 -132.451229) (xy 70.773254 -132.432034)
			(xy 70.685085 -132.403523) (xy 70.64248 -132.385308) (xy 70.632538 -132.381502) (xy 70.611274 -132.381502)
			(xy 70.601332 -132.385308) (xy 70.558728 -132.403528) (xy 70.470561 -132.432046) (xy 70.379906 -132.451239)
			(xy 70.287746 -132.4609) (xy 70.241414 -132.461508) (xy 70.240906 -132.461508) (xy 70.198557 -132.46102)
			(xy 70.114241 -132.45297) (xy 70.031073 -132.436941) (xy 69.949805 -132.413079) (xy 69.871173 -132.3816)
			(xy 69.795889 -132.342789) (xy 69.724636 -132.296998) (xy 69.658058 -132.24464) (xy 69.596758 -132.186192)
			(xy 69.541292 -132.122181) (xy 69.492162 -132.053187) (xy 69.449812 -131.979836) (xy 69.414627 -131.902791)
			(xy 69.386925 -131.822751) (xy 69.366956 -131.74044) (xy 69.354902 -131.656603) (xy 69.350872 -131.572)
			(xy 59.700913 -131.572) (xy 59.696882 -131.656601) (xy 59.684829 -131.740435) (xy 59.664861 -131.822744)
			(xy 59.63716 -131.902783) (xy 59.601975 -131.979826) (xy 59.559627 -132.053175) (xy 59.510499 -132.122167)
			(xy 59.455034 -132.186177) (xy 59.393737 -132.244624) (xy 59.327161 -132.296981) (xy 59.25591 -132.342771)
			(xy 59.180629 -132.381582) (xy 59.101999 -132.413061) (xy 59.020733 -132.436923) (xy 58.937567 -132.452953)
			(xy 58.853254 -132.461004) (xy 58.810906 -132.461508) (xy 58.810398 -132.461508) (xy 58.764066 -132.4609)
			(xy 58.671908 -132.451229) (xy 58.581254 -132.432034) (xy 58.493085 -132.403523) (xy 58.45048 -132.385308)
			(xy 58.440538 -132.381502) (xy 58.419274 -132.381502) (xy 58.409332 -132.385308) (xy 58.366728 -132.403528)
			(xy 58.278561 -132.432046) (xy 58.187906 -132.451239) (xy 58.095746 -132.4609) (xy 58.049414 -132.461508)
			(xy 58.048906 -132.461508) (xy 58.006557 -132.46102) (xy 57.922241 -132.45297) (xy 57.839073 -132.436941)
			(xy 57.757805 -132.413079) (xy 57.679173 -132.3816) (xy 57.603889 -132.342789) (xy 57.532636 -132.296998)
			(xy 57.466058 -132.24464) (xy 57.404758 -132.186192) (xy 57.349292 -132.122181) (xy 57.300162 -132.053187)
			(xy 57.257812 -131.979836) (xy 57.222627 -131.902791) (xy 57.194925 -131.822751) (xy 57.174956 -131.74044)
			(xy 57.162902 -131.656603) (xy 57.158872 -131.572) (xy 47.508913 -131.572) (xy 47.504882 -131.656601)
			(xy 47.492829 -131.740435) (xy 47.472861 -131.822744) (xy 47.44516 -131.902783) (xy 47.409975 -131.979826)
			(xy 47.367627 -132.053175) (xy 47.318499 -132.122167) (xy 47.263034 -132.186177) (xy 47.201737 -132.244624)
			(xy 47.135161 -132.296981) (xy 47.06391 -132.342771) (xy 46.988629 -132.381582) (xy 46.909999 -132.413061)
			(xy 46.828733 -132.436923) (xy 46.745567 -132.452953) (xy 46.661254 -132.461004) (xy 46.618906 -132.461508)
			(xy 46.618398 -132.461508) (xy 46.572066 -132.4609) (xy 46.479908 -132.451229) (xy 46.389254 -132.432034)
			(xy 46.301085 -132.403523) (xy 46.25848 -132.385308) (xy 46.248538 -132.381502) (xy 46.227274 -132.381502)
			(xy 46.217332 -132.385308) (xy 46.174728 -132.403528) (xy 46.086561 -132.432046) (xy 45.995906 -132.451239)
			(xy 45.903746 -132.4609) (xy 45.857414 -132.461508) (xy 45.856906 -132.461508) (xy 45.814557 -132.46102)
			(xy 45.730241 -132.45297) (xy 45.647073 -132.436941) (xy 45.565805 -132.413079) (xy 45.487173 -132.3816)
			(xy 45.411889 -132.342789) (xy 45.340636 -132.296998) (xy 45.274058 -132.24464) (xy 45.212758 -132.186192)
			(xy 45.157292 -132.122181) (xy 45.108162 -132.053187) (xy 45.065812 -131.979836) (xy 45.030627 -131.902791)
			(xy 45.002925 -131.822751) (xy 44.982956 -131.74044) (xy 44.970902 -131.656603) (xy 44.966872 -131.572)
			(xy 40.005 -131.572) (xy 40.005 -136.959232) (xy 45.624232 -136.959232) (xy 45.624232 -136.852768)
			(xy 45.632188 -136.746601) (xy 45.648055 -136.641325) (xy 45.671746 -136.53753) (xy 45.703127 -136.435795)
			(xy 45.742023 -136.33669) (xy 45.788216 -136.240768) (xy 45.841449 -136.148567) (xy 45.901422 -136.060602)
			(xy 45.967802 -135.977365) (xy 46.040216 -135.89932) (xy 46.118261 -135.826906) (xy 46.201498 -135.760526)
			(xy 46.289463 -135.700553) (xy 46.381664 -135.64732) (xy 46.477586 -135.601127) (xy 46.576691 -135.562231)
			(xy 46.678426 -135.53085) (xy 46.782221 -135.507159) (xy 46.887497 -135.491292) (xy 46.993664 -135.483336)
			(xy 47.100128 -135.483336) (xy 47.206295 -135.491292) (xy 47.311571 -135.507159) (xy 47.415366 -135.53085)
			(xy 47.517101 -135.562231) (xy 47.616206 -135.601127) (xy 47.712128 -135.64732) (xy 47.804329 -135.700553)
			(xy 47.892294 -135.760526) (xy 47.975531 -135.826906) (xy 48.053576 -135.89932) (xy 48.12599 -135.977365)
			(xy 48.19237 -136.060602) (xy 48.252343 -136.148567) (xy 48.305576 -136.240768) (xy 48.351769 -136.33669)
			(xy 48.390665 -136.435795) (xy 48.422046 -136.53753) (xy 48.445737 -136.641325) (xy 48.461604 -136.746601)
			(xy 48.46956 -136.852768) (xy 48.470058 -136.906) (xy 48.46956 -136.959232) (xy 57.816232 -136.959232)
			(xy 57.816232 -136.852768) (xy 57.824188 -136.746601) (xy 57.840055 -136.641325) (xy 57.863746 -136.53753)
			(xy 57.895127 -136.435795) (xy 57.934023 -136.33669) (xy 57.980216 -136.240768) (xy 58.033449 -136.148567)
			(xy 58.093422 -136.060602) (xy 58.159802 -135.977365) (xy 58.232216 -135.89932) (xy 58.310261 -135.826906)
			(xy 58.393498 -135.760526) (xy 58.481463 -135.700553) (xy 58.573664 -135.64732) (xy 58.669586 -135.601127)
			(xy 58.768691 -135.562231) (xy 58.870426 -135.53085) (xy 58.974221 -135.507159) (xy 59.079497 -135.491292)
			(xy 59.185664 -135.483336) (xy 59.292128 -135.483336) (xy 59.398295 -135.491292) (xy 59.503571 -135.507159)
			(xy 59.607366 -135.53085) (xy 59.709101 -135.562231) (xy 59.808206 -135.601127) (xy 59.904128 -135.64732)
			(xy 59.996329 -135.700553) (xy 60.084294 -135.760526) (xy 60.167531 -135.826906) (xy 60.245576 -135.89932)
			(xy 60.31799 -135.977365) (xy 60.38437 -136.060602) (xy 60.444343 -136.148567) (xy 60.497576 -136.240768)
			(xy 60.543769 -136.33669) (xy 60.582665 -136.435795) (xy 60.614046 -136.53753) (xy 60.637737 -136.641325)
			(xy 60.653604 -136.746601) (xy 60.66156 -136.852768) (xy 60.662058 -136.906) (xy 60.66156 -136.959232)
			(xy 70.008232 -136.959232) (xy 70.008232 -136.852768) (xy 70.016188 -136.746601) (xy 70.032055 -136.641325)
			(xy 70.055746 -136.53753) (xy 70.087127 -136.435795) (xy 70.126023 -136.33669) (xy 70.172216 -136.240768)
			(xy 70.225449 -136.148567) (xy 70.285422 -136.060602) (xy 70.351802 -135.977365) (xy 70.424216 -135.89932)
			(xy 70.502261 -135.826906) (xy 70.585498 -135.760526) (xy 70.673463 -135.700553) (xy 70.765664 -135.64732)
			(xy 70.861586 -135.601127) (xy 70.960691 -135.562231) (xy 71.062426 -135.53085) (xy 71.166221 -135.507159)
			(xy 71.271497 -135.491292) (xy 71.377664 -135.483336) (xy 71.484128 -135.483336) (xy 71.590295 -135.491292)
			(xy 71.695571 -135.507159) (xy 71.799366 -135.53085) (xy 71.901101 -135.562231) (xy 72.000206 -135.601127)
			(xy 72.096128 -135.64732) (xy 72.188329 -135.700553) (xy 72.276294 -135.760526) (xy 72.359531 -135.826906)
			(xy 72.437576 -135.89932) (xy 72.50999 -135.977365) (xy 72.57637 -136.060602) (xy 72.636343 -136.148567)
			(xy 72.689576 -136.240768) (xy 72.735769 -136.33669) (xy 72.774665 -136.435795) (xy 72.806046 -136.53753)
			(xy 72.829737 -136.641325) (xy 72.845604 -136.746601) (xy 72.85356 -136.852768) (xy 72.854058 -136.906)
			(xy 72.85356 -136.959232) (xy 85.624152 -136.959232) (xy 85.624152 -136.852768) (xy 85.632108 -136.746601)
			(xy 85.647975 -136.641325) (xy 85.671666 -136.53753) (xy 85.703047 -136.435795) (xy 85.741943 -136.33669)
			(xy 85.788136 -136.240768) (xy 85.841369 -136.148567) (xy 85.901342 -136.060602) (xy 85.967722 -135.977365)
			(xy 86.040136 -135.89932) (xy 86.118181 -135.826906) (xy 86.201418 -135.760526) (xy 86.289383 -135.700553)
			(xy 86.381584 -135.64732) (xy 86.477506 -135.601127) (xy 86.576611 -135.562231) (xy 86.678346 -135.53085)
			(xy 86.782141 -135.507159) (xy 86.887417 -135.491292) (xy 86.993584 -135.483336) (xy 87.100048 -135.483336)
			(xy 87.206215 -135.491292) (xy 87.311491 -135.507159) (xy 87.415286 -135.53085) (xy 87.517021 -135.562231)
			(xy 87.616126 -135.601127) (xy 87.712048 -135.64732) (xy 87.804249 -135.700553) (xy 87.892214 -135.760526)
			(xy 87.975451 -135.826906) (xy 88.053496 -135.89932) (xy 88.12591 -135.977365) (xy 88.19229 -136.060602)
			(xy 88.252263 -136.148567) (xy 88.305496 -136.240768) (xy 88.351689 -136.33669) (xy 88.390585 -136.435795)
			(xy 88.421966 -136.53753) (xy 88.445657 -136.641325) (xy 88.461524 -136.746601) (xy 88.46948 -136.852768)
			(xy 88.469978 -136.906) (xy 88.46948 -136.959232) (xy 97.816152 -136.959232) (xy 97.816152 -136.852768)
			(xy 97.824108 -136.746601) (xy 97.839975 -136.641325) (xy 97.863666 -136.53753) (xy 97.895047 -136.435795)
			(xy 97.933943 -136.33669) (xy 97.980136 -136.240768) (xy 98.033369 -136.148567) (xy 98.093342 -136.060602)
			(xy 98.159722 -135.977365) (xy 98.232136 -135.89932) (xy 98.310181 -135.826906) (xy 98.393418 -135.760526)
			(xy 98.481383 -135.700553) (xy 98.573584 -135.64732) (xy 98.669506 -135.601127) (xy 98.768611 -135.562231)
			(xy 98.870346 -135.53085) (xy 98.974141 -135.507159) (xy 99.079417 -135.491292) (xy 99.185584 -135.483336)
			(xy 99.292048 -135.483336) (xy 99.398215 -135.491292) (xy 99.503491 -135.507159) (xy 99.607286 -135.53085)
			(xy 99.709021 -135.562231) (xy 99.808126 -135.601127) (xy 99.904048 -135.64732) (xy 99.996249 -135.700553)
			(xy 100.084214 -135.760526) (xy 100.167451 -135.826906) (xy 100.245496 -135.89932) (xy 100.31791 -135.977365)
			(xy 100.38429 -136.060602) (xy 100.444263 -136.148567) (xy 100.497496 -136.240768) (xy 100.543689 -136.33669)
			(xy 100.582585 -136.435795) (xy 100.613966 -136.53753) (xy 100.637657 -136.641325) (xy 100.653524 -136.746601)
			(xy 100.66148 -136.852768) (xy 100.661978 -136.906) (xy 100.66148 -136.959232) (xy 110.008152 -136.959232)
			(xy 110.008152 -136.852768) (xy 110.016108 -136.746601) (xy 110.031975 -136.641325) (xy 110.055666 -136.53753)
			(xy 110.087047 -136.435795) (xy 110.125943 -136.33669) (xy 110.172136 -136.240768) (xy 110.225369 -136.148567)
			(xy 110.285342 -136.060602) (xy 110.351722 -135.977365) (xy 110.424136 -135.89932) (xy 110.502181 -135.826906)
			(xy 110.585418 -135.760526) (xy 110.673383 -135.700553) (xy 110.765584 -135.64732) (xy 110.861506 -135.601127)
			(xy 110.960611 -135.562231) (xy 111.062346 -135.53085) (xy 111.166141 -135.507159) (xy 111.271417 -135.491292)
			(xy 111.377584 -135.483336) (xy 111.484048 -135.483336) (xy 111.590215 -135.491292) (xy 111.695491 -135.507159)
			(xy 111.799286 -135.53085) (xy 111.901021 -135.562231) (xy 112.000126 -135.601127) (xy 112.096048 -135.64732)
			(xy 112.188249 -135.700553) (xy 112.276214 -135.760526) (xy 112.359451 -135.826906) (xy 112.437496 -135.89932)
			(xy 112.50991 -135.977365) (xy 112.57629 -136.060602) (xy 112.636263 -136.148567) (xy 112.689496 -136.240768)
			(xy 112.735689 -136.33669) (xy 112.774585 -136.435795) (xy 112.805966 -136.53753) (xy 112.829657 -136.641325)
			(xy 112.845524 -136.746601) (xy 112.85348 -136.852768) (xy 112.853978 -136.906) (xy 112.85348 -136.959232)
			(xy 125.624326 -136.959232) (xy 125.624326 -136.852768) (xy 125.632282 -136.746601) (xy 125.648149 -136.641325)
			(xy 125.67184 -136.53753) (xy 125.703221 -136.435795) (xy 125.742117 -136.33669) (xy 125.78831 -136.240768)
			(xy 125.841543 -136.148567) (xy 125.901516 -136.060602) (xy 125.967896 -135.977365) (xy 126.04031 -135.89932)
			(xy 126.118355 -135.826906) (xy 126.201592 -135.760526) (xy 126.289557 -135.700553) (xy 126.381758 -135.64732)
			(xy 126.47768 -135.601127) (xy 126.576785 -135.562231) (xy 126.67852 -135.53085) (xy 126.782315 -135.507159)
			(xy 126.887591 -135.491292) (xy 126.993758 -135.483336) (xy 127.100222 -135.483336) (xy 127.206389 -135.491292)
			(xy 127.311665 -135.507159) (xy 127.41546 -135.53085) (xy 127.517195 -135.562231) (xy 127.6163 -135.601127)
			(xy 127.712222 -135.64732) (xy 127.804423 -135.700553) (xy 127.892388 -135.760526) (xy 127.975625 -135.826906)
			(xy 128.05367 -135.89932) (xy 128.126084 -135.977365) (xy 128.192464 -136.060602) (xy 128.252437 -136.148567)
			(xy 128.30567 -136.240768) (xy 128.351863 -136.33669) (xy 128.390759 -136.435795) (xy 128.42214 -136.53753)
			(xy 128.445831 -136.641325) (xy 128.461698 -136.746601) (xy 128.469654 -136.852768) (xy 128.470152 -136.906)
			(xy 128.469654 -136.959232) (xy 137.816326 -136.959232) (xy 137.816326 -136.852768) (xy 137.824282 -136.746601)
			(xy 137.840149 -136.641325) (xy 137.86384 -136.53753) (xy 137.895221 -136.435795) (xy 137.934117 -136.33669)
			(xy 137.98031 -136.240768) (xy 138.033543 -136.148567) (xy 138.093516 -136.060602) (xy 138.159896 -135.977365)
			(xy 138.23231 -135.89932) (xy 138.310355 -135.826906) (xy 138.393592 -135.760526) (xy 138.481557 -135.700553)
			(xy 138.573758 -135.64732) (xy 138.66968 -135.601127) (xy 138.768785 -135.562231) (xy 138.87052 -135.53085)
			(xy 138.974315 -135.507159) (xy 139.079591 -135.491292) (xy 139.185758 -135.483336) (xy 139.292222 -135.483336)
			(xy 139.398389 -135.491292) (xy 139.503665 -135.507159) (xy 139.60746 -135.53085) (xy 139.709195 -135.562231)
			(xy 139.8083 -135.601127) (xy 139.904222 -135.64732) (xy 139.996423 -135.700553) (xy 140.084388 -135.760526)
			(xy 140.167625 -135.826906) (xy 140.24567 -135.89932) (xy 140.318084 -135.977365) (xy 140.384464 -136.060602)
			(xy 140.444437 -136.148567) (xy 140.49767 -136.240768) (xy 140.543863 -136.33669) (xy 140.582759 -136.435795)
			(xy 140.61414 -136.53753) (xy 140.637831 -136.641325) (xy 140.653698 -136.746601) (xy 140.661654 -136.852768)
			(xy 140.662152 -136.906) (xy 140.661654 -136.959232) (xy 150.008326 -136.959232) (xy 150.008326 -136.852768)
			(xy 150.016282 -136.746601) (xy 150.032149 -136.641325) (xy 150.05584 -136.53753) (xy 150.087221 -136.435795)
			(xy 150.126117 -136.33669) (xy 150.17231 -136.240768) (xy 150.225543 -136.148567) (xy 150.285516 -136.060602)
			(xy 150.351896 -135.977365) (xy 150.42431 -135.89932) (xy 150.502355 -135.826906) (xy 150.585592 -135.760526)
			(xy 150.673557 -135.700553) (xy 150.765758 -135.64732) (xy 150.86168 -135.601127) (xy 150.960785 -135.562231)
			(xy 151.06252 -135.53085) (xy 151.166315 -135.507159) (xy 151.271591 -135.491292) (xy 151.377758 -135.483336)
			(xy 151.484222 -135.483336) (xy 151.590389 -135.491292) (xy 151.695665 -135.507159) (xy 151.79946 -135.53085)
			(xy 151.901195 -135.562231) (xy 152.0003 -135.601127) (xy 152.096222 -135.64732) (xy 152.188423 -135.700553)
			(xy 152.276388 -135.760526) (xy 152.359625 -135.826906) (xy 152.43767 -135.89932) (xy 152.510084 -135.977365)
			(xy 152.576464 -136.060602) (xy 152.636437 -136.148567) (xy 152.68967 -136.240768) (xy 152.735863 -136.33669)
			(xy 152.774759 -136.435795) (xy 152.80614 -136.53753) (xy 152.829831 -136.641325) (xy 152.845698 -136.746601)
			(xy 152.853654 -136.852768) (xy 152.854152 -136.906) (xy 152.853654 -136.959232) (xy 165.6245 -136.959232)
			(xy 165.6245 -136.852768) (xy 165.632456 -136.746601) (xy 165.648323 -136.641325) (xy 165.672014 -136.53753)
			(xy 165.703395 -136.435795) (xy 165.742291 -136.33669) (xy 165.788484 -136.240768) (xy 165.841717 -136.148567)
			(xy 165.90169 -136.060602) (xy 165.96807 -135.977365) (xy 166.040484 -135.89932) (xy 166.118529 -135.826906)
			(xy 166.201766 -135.760526) (xy 166.289731 -135.700553) (xy 166.381932 -135.64732) (xy 166.477854 -135.601127)
			(xy 166.576959 -135.562231) (xy 166.678694 -135.53085) (xy 166.782489 -135.507159) (xy 166.887765 -135.491292)
			(xy 166.993932 -135.483336) (xy 167.100396 -135.483336) (xy 167.206563 -135.491292) (xy 167.311839 -135.507159)
			(xy 167.415634 -135.53085) (xy 167.517369 -135.562231) (xy 167.616474 -135.601127) (xy 167.712396 -135.64732)
			(xy 167.804597 -135.700553) (xy 167.892562 -135.760526) (xy 167.975799 -135.826906) (xy 168.053844 -135.89932)
			(xy 168.126258 -135.977365) (xy 168.192638 -136.060602) (xy 168.252611 -136.148567) (xy 168.305844 -136.240768)
			(xy 168.352037 -136.33669) (xy 168.390933 -136.435795) (xy 168.422314 -136.53753) (xy 168.446005 -136.641325)
			(xy 168.461872 -136.746601) (xy 168.469828 -136.852768) (xy 168.470326 -136.906) (xy 168.469828 -136.959232)
			(xy 177.8165 -136.959232) (xy 177.8165 -136.852768) (xy 177.824456 -136.746601) (xy 177.840323 -136.641325)
			(xy 177.864014 -136.53753) (xy 177.895395 -136.435795) (xy 177.934291 -136.33669) (xy 177.980484 -136.240768)
			(xy 178.033717 -136.148567) (xy 178.09369 -136.060602) (xy 178.16007 -135.977365) (xy 178.232484 -135.89932)
			(xy 178.310529 -135.826906) (xy 178.393766 -135.760526) (xy 178.481731 -135.700553) (xy 178.573932 -135.64732)
			(xy 178.669854 -135.601127) (xy 178.768959 -135.562231) (xy 178.870694 -135.53085) (xy 178.974489 -135.507159)
			(xy 179.079765 -135.491292) (xy 179.185932 -135.483336) (xy 179.292396 -135.483336) (xy 179.398563 -135.491292)
			(xy 179.503839 -135.507159) (xy 179.607634 -135.53085) (xy 179.709369 -135.562231) (xy 179.808474 -135.601127)
			(xy 179.904396 -135.64732) (xy 179.996597 -135.700553) (xy 180.084562 -135.760526) (xy 180.167799 -135.826906)
			(xy 180.245844 -135.89932) (xy 180.318258 -135.977365) (xy 180.384638 -136.060602) (xy 180.444611 -136.148567)
			(xy 180.497844 -136.240768) (xy 180.544037 -136.33669) (xy 180.582933 -136.435795) (xy 180.614314 -136.53753)
			(xy 180.638005 -136.641325) (xy 180.653872 -136.746601) (xy 180.661828 -136.852768) (xy 180.662326 -136.906)
			(xy 180.661828 -136.959232) (xy 190.0085 -136.959232) (xy 190.0085 -136.852768) (xy 190.016456 -136.746601)
			(xy 190.032323 -136.641325) (xy 190.056014 -136.53753) (xy 190.087395 -136.435795) (xy 190.126291 -136.33669)
			(xy 190.172484 -136.240768) (xy 190.225717 -136.148567) (xy 190.28569 -136.060602) (xy 190.35207 -135.977365)
			(xy 190.424484 -135.89932) (xy 190.502529 -135.826906) (xy 190.585766 -135.760526) (xy 190.673731 -135.700553)
			(xy 190.765932 -135.64732) (xy 190.861854 -135.601127) (xy 190.960959 -135.562231) (xy 191.062694 -135.53085)
			(xy 191.166489 -135.507159) (xy 191.271765 -135.491292) (xy 191.377932 -135.483336) (xy 191.484396 -135.483336)
			(xy 191.590563 -135.491292) (xy 191.695839 -135.507159) (xy 191.799634 -135.53085) (xy 191.901369 -135.562231)
			(xy 192.000474 -135.601127) (xy 192.096396 -135.64732) (xy 192.188597 -135.700553) (xy 192.276562 -135.760526)
			(xy 192.359799 -135.826906) (xy 192.437844 -135.89932) (xy 192.510258 -135.977365) (xy 192.576638 -136.060602)
			(xy 192.636611 -136.148567) (xy 192.689844 -136.240768) (xy 192.736037 -136.33669) (xy 192.774933 -136.435795)
			(xy 192.806314 -136.53753) (xy 192.830005 -136.641325) (xy 192.845872 -136.746601) (xy 192.853828 -136.852768)
			(xy 192.854326 -136.906) (xy 192.853828 -136.959232) (xy 192.845872 -137.065399) (xy 192.830005 -137.170675)
			(xy 192.806314 -137.27447) (xy 192.774933 -137.376205) (xy 192.736037 -137.47531) (xy 192.689844 -137.571232)
			(xy 192.636611 -137.663433) (xy 192.576638 -137.751398) (xy 192.510258 -137.834635) (xy 192.437844 -137.91268)
			(xy 192.359799 -137.985094) (xy 192.276562 -138.051474) (xy 192.188597 -138.111447) (xy 192.096396 -138.16468)
			(xy 192.000474 -138.210873) (xy 191.901369 -138.249769) (xy 191.799634 -138.28115) (xy 191.695839 -138.304841)
			(xy 191.590563 -138.320708) (xy 191.484396 -138.328664) (xy 191.377932 -138.328664) (xy 191.271765 -138.320708)
			(xy 191.166489 -138.304841) (xy 191.062694 -138.28115) (xy 190.960959 -138.249769) (xy 190.861854 -138.210873)
			(xy 190.765932 -138.16468) (xy 190.673731 -138.111447) (xy 190.585766 -138.051474) (xy 190.502529 -137.985094)
			(xy 190.424484 -137.91268) (xy 190.35207 -137.834635) (xy 190.28569 -137.751398) (xy 190.225717 -137.663433)
			(xy 190.172484 -137.571232) (xy 190.126291 -137.47531) (xy 190.087395 -137.376205) (xy 190.056014 -137.27447)
			(xy 190.032323 -137.170675) (xy 190.016456 -137.065399) (xy 190.0085 -136.959232) (xy 180.661828 -136.959232)
			(xy 180.653872 -137.065399) (xy 180.638005 -137.170675) (xy 180.614314 -137.27447) (xy 180.582933 -137.376205)
			(xy 180.544037 -137.47531) (xy 180.497844 -137.571232) (xy 180.444611 -137.663433) (xy 180.384638 -137.751398)
			(xy 180.318258 -137.834635) (xy 180.245844 -137.91268) (xy 180.167799 -137.985094) (xy 180.084562 -138.051474)
			(xy 179.996597 -138.111447) (xy 179.904396 -138.16468) (xy 179.808474 -138.210873) (xy 179.709369 -138.249769)
			(xy 179.607634 -138.28115) (xy 179.503839 -138.304841) (xy 179.398563 -138.320708) (xy 179.292396 -138.328664)
			(xy 179.185932 -138.328664) (xy 179.079765 -138.320708) (xy 178.974489 -138.304841) (xy 178.870694 -138.28115)
			(xy 178.768959 -138.249769) (xy 178.669854 -138.210873) (xy 178.573932 -138.16468) (xy 178.481731 -138.111447)
			(xy 178.393766 -138.051474) (xy 178.310529 -137.985094) (xy 178.232484 -137.91268) (xy 178.16007 -137.834635)
			(xy 178.09369 -137.751398) (xy 178.033717 -137.663433) (xy 177.980484 -137.571232) (xy 177.934291 -137.47531)
			(xy 177.895395 -137.376205) (xy 177.864014 -137.27447) (xy 177.840323 -137.170675) (xy 177.824456 -137.065399)
			(xy 177.8165 -136.959232) (xy 168.469828 -136.959232) (xy 168.461872 -137.065399) (xy 168.446005 -137.170675)
			(xy 168.422314 -137.27447) (xy 168.390933 -137.376205) (xy 168.352037 -137.47531) (xy 168.305844 -137.571232)
			(xy 168.252611 -137.663433) (xy 168.192638 -137.751398) (xy 168.126258 -137.834635) (xy 168.053844 -137.91268)
			(xy 167.975799 -137.985094) (xy 167.892562 -138.051474) (xy 167.804597 -138.111447) (xy 167.712396 -138.16468)
			(xy 167.616474 -138.210873) (xy 167.517369 -138.249769) (xy 167.415634 -138.28115) (xy 167.311839 -138.304841)
			(xy 167.206563 -138.320708) (xy 167.100396 -138.328664) (xy 166.993932 -138.328664) (xy 166.887765 -138.320708)
			(xy 166.782489 -138.304841) (xy 166.678694 -138.28115) (xy 166.576959 -138.249769) (xy 166.477854 -138.210873)
			(xy 166.381932 -138.16468) (xy 166.289731 -138.111447) (xy 166.201766 -138.051474) (xy 166.118529 -137.985094)
			(xy 166.040484 -137.91268) (xy 165.96807 -137.834635) (xy 165.90169 -137.751398) (xy 165.841717 -137.663433)
			(xy 165.788484 -137.571232) (xy 165.742291 -137.47531) (xy 165.703395 -137.376205) (xy 165.672014 -137.27447)
			(xy 165.648323 -137.170675) (xy 165.632456 -137.065399) (xy 165.6245 -136.959232) (xy 152.853654 -136.959232)
			(xy 152.845698 -137.065399) (xy 152.829831 -137.170675) (xy 152.80614 -137.27447) (xy 152.774759 -137.376205)
			(xy 152.735863 -137.47531) (xy 152.68967 -137.571232) (xy 152.636437 -137.663433) (xy 152.576464 -137.751398)
			(xy 152.510084 -137.834635) (xy 152.43767 -137.91268) (xy 152.359625 -137.985094) (xy 152.276388 -138.051474)
			(xy 152.188423 -138.111447) (xy 152.096222 -138.16468) (xy 152.0003 -138.210873) (xy 151.901195 -138.249769)
			(xy 151.79946 -138.28115) (xy 151.695665 -138.304841) (xy 151.590389 -138.320708) (xy 151.484222 -138.328664)
			(xy 151.377758 -138.328664) (xy 151.271591 -138.320708) (xy 151.166315 -138.304841) (xy 151.06252 -138.28115)
			(xy 150.960785 -138.249769) (xy 150.86168 -138.210873) (xy 150.765758 -138.16468) (xy 150.673557 -138.111447)
			(xy 150.585592 -138.051474) (xy 150.502355 -137.985094) (xy 150.42431 -137.91268) (xy 150.351896 -137.834635)
			(xy 150.285516 -137.751398) (xy 150.225543 -137.663433) (xy 150.17231 -137.571232) (xy 150.126117 -137.47531)
			(xy 150.087221 -137.376205) (xy 150.05584 -137.27447) (xy 150.032149 -137.170675) (xy 150.016282 -137.065399)
			(xy 150.008326 -136.959232) (xy 140.661654 -136.959232) (xy 140.653698 -137.065399) (xy 140.637831 -137.170675)
			(xy 140.61414 -137.27447) (xy 140.582759 -137.376205) (xy 140.543863 -137.47531) (xy 140.49767 -137.571232)
			(xy 140.444437 -137.663433) (xy 140.384464 -137.751398) (xy 140.318084 -137.834635) (xy 140.24567 -137.91268)
			(xy 140.167625 -137.985094) (xy 140.084388 -138.051474) (xy 139.996423 -138.111447) (xy 139.904222 -138.16468)
			(xy 139.8083 -138.210873) (xy 139.709195 -138.249769) (xy 139.60746 -138.28115) (xy 139.503665 -138.304841)
			(xy 139.398389 -138.320708) (xy 139.292222 -138.328664) (xy 139.185758 -138.328664) (xy 139.079591 -138.320708)
			(xy 138.974315 -138.304841) (xy 138.87052 -138.28115) (xy 138.768785 -138.249769) (xy 138.66968 -138.210873)
			(xy 138.573758 -138.16468) (xy 138.481557 -138.111447) (xy 138.393592 -138.051474) (xy 138.310355 -137.985094)
			(xy 138.23231 -137.91268) (xy 138.159896 -137.834635) (xy 138.093516 -137.751398) (xy 138.033543 -137.663433)
			(xy 137.98031 -137.571232) (xy 137.934117 -137.47531) (xy 137.895221 -137.376205) (xy 137.86384 -137.27447)
			(xy 137.840149 -137.170675) (xy 137.824282 -137.065399) (xy 137.816326 -136.959232) (xy 128.469654 -136.959232)
			(xy 128.461698 -137.065399) (xy 128.445831 -137.170675) (xy 128.42214 -137.27447) (xy 128.390759 -137.376205)
			(xy 128.351863 -137.47531) (xy 128.30567 -137.571232) (xy 128.252437 -137.663433) (xy 128.192464 -137.751398)
			(xy 128.126084 -137.834635) (xy 128.05367 -137.91268) (xy 127.975625 -137.985094) (xy 127.892388 -138.051474)
			(xy 127.804423 -138.111447) (xy 127.712222 -138.16468) (xy 127.6163 -138.210873) (xy 127.517195 -138.249769)
			(xy 127.41546 -138.28115) (xy 127.311665 -138.304841) (xy 127.206389 -138.320708) (xy 127.100222 -138.328664)
			(xy 126.993758 -138.328664) (xy 126.887591 -138.320708) (xy 126.782315 -138.304841) (xy 126.67852 -138.28115)
			(xy 126.576785 -138.249769) (xy 126.47768 -138.210873) (xy 126.381758 -138.16468) (xy 126.289557 -138.111447)
			(xy 126.201592 -138.051474) (xy 126.118355 -137.985094) (xy 126.04031 -137.91268) (xy 125.967896 -137.834635)
			(xy 125.901516 -137.751398) (xy 125.841543 -137.663433) (xy 125.78831 -137.571232) (xy 125.742117 -137.47531)
			(xy 125.703221 -137.376205) (xy 125.67184 -137.27447) (xy 125.648149 -137.170675) (xy 125.632282 -137.065399)
			(xy 125.624326 -136.959232) (xy 112.85348 -136.959232) (xy 112.845524 -137.065399) (xy 112.829657 -137.170675)
			(xy 112.805966 -137.27447) (xy 112.774585 -137.376205) (xy 112.735689 -137.47531) (xy 112.689496 -137.571232)
			(xy 112.636263 -137.663433) (xy 112.57629 -137.751398) (xy 112.50991 -137.834635) (xy 112.437496 -137.91268)
			(xy 112.359451 -137.985094) (xy 112.276214 -138.051474) (xy 112.188249 -138.111447) (xy 112.096048 -138.16468)
			(xy 112.000126 -138.210873) (xy 111.901021 -138.249769) (xy 111.799286 -138.28115) (xy 111.695491 -138.304841)
			(xy 111.590215 -138.320708) (xy 111.484048 -138.328664) (xy 111.377584 -138.328664) (xy 111.271417 -138.320708)
			(xy 111.166141 -138.304841) (xy 111.062346 -138.28115) (xy 110.960611 -138.249769) (xy 110.861506 -138.210873)
			(xy 110.765584 -138.16468) (xy 110.673383 -138.111447) (xy 110.585418 -138.051474) (xy 110.502181 -137.985094)
			(xy 110.424136 -137.91268) (xy 110.351722 -137.834635) (xy 110.285342 -137.751398) (xy 110.225369 -137.663433)
			(xy 110.172136 -137.571232) (xy 110.125943 -137.47531) (xy 110.087047 -137.376205) (xy 110.055666 -137.27447)
			(xy 110.031975 -137.170675) (xy 110.016108 -137.065399) (xy 110.008152 -136.959232) (xy 100.66148 -136.959232)
			(xy 100.653524 -137.065399) (xy 100.637657 -137.170675) (xy 100.613966 -137.27447) (xy 100.582585 -137.376205)
			(xy 100.543689 -137.47531) (xy 100.497496 -137.571232) (xy 100.444263 -137.663433) (xy 100.38429 -137.751398)
			(xy 100.31791 -137.834635) (xy 100.245496 -137.91268) (xy 100.167451 -137.985094) (xy 100.084214 -138.051474)
			(xy 99.996249 -138.111447) (xy 99.904048 -138.16468) (xy 99.808126 -138.210873) (xy 99.709021 -138.249769)
			(xy 99.607286 -138.28115) (xy 99.503491 -138.304841) (xy 99.398215 -138.320708) (xy 99.292048 -138.328664)
			(xy 99.185584 -138.328664) (xy 99.079417 -138.320708) (xy 98.974141 -138.304841) (xy 98.870346 -138.28115)
			(xy 98.768611 -138.249769) (xy 98.669506 -138.210873) (xy 98.573584 -138.16468) (xy 98.481383 -138.111447)
			(xy 98.393418 -138.051474) (xy 98.310181 -137.985094) (xy 98.232136 -137.91268) (xy 98.159722 -137.834635)
			(xy 98.093342 -137.751398) (xy 98.033369 -137.663433) (xy 97.980136 -137.571232) (xy 97.933943 -137.47531)
			(xy 97.895047 -137.376205) (xy 97.863666 -137.27447) (xy 97.839975 -137.170675) (xy 97.824108 -137.065399)
			(xy 97.816152 -136.959232) (xy 88.46948 -136.959232) (xy 88.461524 -137.065399) (xy 88.445657 -137.170675)
			(xy 88.421966 -137.27447) (xy 88.390585 -137.376205) (xy 88.351689 -137.47531) (xy 88.305496 -137.571232)
			(xy 88.252263 -137.663433) (xy 88.19229 -137.751398) (xy 88.12591 -137.834635) (xy 88.053496 -137.91268)
			(xy 87.975451 -137.985094) (xy 87.892214 -138.051474) (xy 87.804249 -138.111447) (xy 87.712048 -138.16468)
			(xy 87.616126 -138.210873) (xy 87.517021 -138.249769) (xy 87.415286 -138.28115) (xy 87.311491 -138.304841)
			(xy 87.206215 -138.320708) (xy 87.100048 -138.328664) (xy 86.993584 -138.328664) (xy 86.887417 -138.320708)
			(xy 86.782141 -138.304841) (xy 86.678346 -138.28115) (xy 86.576611 -138.249769) (xy 86.477506 -138.210873)
			(xy 86.381584 -138.16468) (xy 86.289383 -138.111447) (xy 86.201418 -138.051474) (xy 86.118181 -137.985094)
			(xy 86.040136 -137.91268) (xy 85.967722 -137.834635) (xy 85.901342 -137.751398) (xy 85.841369 -137.663433)
			(xy 85.788136 -137.571232) (xy 85.741943 -137.47531) (xy 85.703047 -137.376205) (xy 85.671666 -137.27447)
			(xy 85.647975 -137.170675) (xy 85.632108 -137.065399) (xy 85.624152 -136.959232) (xy 72.85356 -136.959232)
			(xy 72.845604 -137.065399) (xy 72.829737 -137.170675) (xy 72.806046 -137.27447) (xy 72.774665 -137.376205)
			(xy 72.735769 -137.47531) (xy 72.689576 -137.571232) (xy 72.636343 -137.663433) (xy 72.57637 -137.751398)
			(xy 72.50999 -137.834635) (xy 72.437576 -137.91268) (xy 72.359531 -137.985094) (xy 72.276294 -138.051474)
			(xy 72.188329 -138.111447) (xy 72.096128 -138.16468) (xy 72.000206 -138.210873) (xy 71.901101 -138.249769)
			(xy 71.799366 -138.28115) (xy 71.695571 -138.304841) (xy 71.590295 -138.320708) (xy 71.484128 -138.328664)
			(xy 71.377664 -138.328664) (xy 71.271497 -138.320708) (xy 71.166221 -138.304841) (xy 71.062426 -138.28115)
			(xy 70.960691 -138.249769) (xy 70.861586 -138.210873) (xy 70.765664 -138.16468) (xy 70.673463 -138.111447)
			(xy 70.585498 -138.051474) (xy 70.502261 -137.985094) (xy 70.424216 -137.91268) (xy 70.351802 -137.834635)
			(xy 70.285422 -137.751398) (xy 70.225449 -137.663433) (xy 70.172216 -137.571232) (xy 70.126023 -137.47531)
			(xy 70.087127 -137.376205) (xy 70.055746 -137.27447) (xy 70.032055 -137.170675) (xy 70.016188 -137.065399)
			(xy 70.008232 -136.959232) (xy 60.66156 -136.959232) (xy 60.653604 -137.065399) (xy 60.637737 -137.170675)
			(xy 60.614046 -137.27447) (xy 60.582665 -137.376205) (xy 60.543769 -137.47531) (xy 60.497576 -137.571232)
			(xy 60.444343 -137.663433) (xy 60.38437 -137.751398) (xy 60.31799 -137.834635) (xy 60.245576 -137.91268)
			(xy 60.167531 -137.985094) (xy 60.084294 -138.051474) (xy 59.996329 -138.111447) (xy 59.904128 -138.16468)
			(xy 59.808206 -138.210873) (xy 59.709101 -138.249769) (xy 59.607366 -138.28115) (xy 59.503571 -138.304841)
			(xy 59.398295 -138.320708) (xy 59.292128 -138.328664) (xy 59.185664 -138.328664) (xy 59.079497 -138.320708)
			(xy 58.974221 -138.304841) (xy 58.870426 -138.28115) (xy 58.768691 -138.249769) (xy 58.669586 -138.210873)
			(xy 58.573664 -138.16468) (xy 58.481463 -138.111447) (xy 58.393498 -138.051474) (xy 58.310261 -137.985094)
			(xy 58.232216 -137.91268) (xy 58.159802 -137.834635) (xy 58.093422 -137.751398) (xy 58.033449 -137.663433)
			(xy 57.980216 -137.571232) (xy 57.934023 -137.47531) (xy 57.895127 -137.376205) (xy 57.863746 -137.27447)
			(xy 57.840055 -137.170675) (xy 57.824188 -137.065399) (xy 57.816232 -136.959232) (xy 48.46956 -136.959232)
			(xy 48.461604 -137.065399) (xy 48.445737 -137.170675) (xy 48.422046 -137.27447) (xy 48.390665 -137.376205)
			(xy 48.351769 -137.47531) (xy 48.305576 -137.571232) (xy 48.252343 -137.663433) (xy 48.19237 -137.751398)
			(xy 48.12599 -137.834635) (xy 48.053576 -137.91268) (xy 47.975531 -137.985094) (xy 47.892294 -138.051474)
			(xy 47.804329 -138.111447) (xy 47.712128 -138.16468) (xy 47.616206 -138.210873) (xy 47.517101 -138.249769)
			(xy 47.415366 -138.28115) (xy 47.311571 -138.304841) (xy 47.206295 -138.320708) (xy 47.100128 -138.328664)
			(xy 46.993664 -138.328664) (xy 46.887497 -138.320708) (xy 46.782221 -138.304841) (xy 46.678426 -138.28115)
			(xy 46.576691 -138.249769) (xy 46.477586 -138.210873) (xy 46.381664 -138.16468) (xy 46.289463 -138.111447)
			(xy 46.201498 -138.051474) (xy 46.118261 -137.985094) (xy 46.040216 -137.91268) (xy 45.967802 -137.834635)
			(xy 45.901422 -137.751398) (xy 45.841449 -137.663433) (xy 45.788216 -137.571232) (xy 45.742023 -137.47531)
			(xy 45.703127 -137.376205) (xy 45.671746 -137.27447) (xy 45.648055 -137.170675) (xy 45.632188 -137.065399)
			(xy 45.624232 -136.959232) (xy 40.005 -136.959232) (xy 40.005 -145.085308) (xy 40.005425 -145.095378)
			(xy 40.013141 -145.11398) (xy 40.019986 -145.121376) (xy 40.868092 -145.969482) (xy 40.869616 -145.971006)
			(xy 40.87495 -145.97634) (xy 40.893492 -145.98396)
		)
		(stroke
			(width 0)
			(type solid)
		)
		(fill yes)
		(layer "In5.Cu")
		(net "P52V_HS_FILTER")
	)
	(gr_poly
		(pts
			(xy 9.97966 -145.98396) (xy 9.989724 -145.983525) (xy 10.008309 -145.97579) (xy 10.015728 -145.968974)
			(xy 10.035352 -145.949872) (xy 10.079091 -145.916919) (xy 10.127092 -145.890559) (xy 10.17837 -145.871333)
			(xy 10.23187 -145.859637) (xy 10.286492 -145.855712) (xy 10.341114 -145.859637) (xy 10.394614 -145.871333)
			(xy 10.445892 -145.890559) (xy 10.493893 -145.916919) (xy 10.537632 -145.949872) (xy 10.557256 -145.968974)
			(xy 10.564656 -145.975814) (xy 10.583255 -145.983532) (xy 10.593324 -145.98396) (xy 15.05966 -145.98396)
			(xy 15.069724 -145.983525) (xy 15.088309 -145.97579) (xy 15.095728 -145.968974) (xy 15.115352 -145.949872)
			(xy 15.159091 -145.916919) (xy 15.207092 -145.890559) (xy 15.25837 -145.871333) (xy 15.31187 -145.859637)
			(xy 15.366492 -145.855712) (xy 15.421114 -145.859637) (xy 15.474614 -145.871333) (xy 15.525892 -145.890559)
			(xy 15.573893 -145.916919) (xy 15.617632 -145.949872) (xy 15.637256 -145.968974) (xy 15.644656 -145.975814)
			(xy 15.663255 -145.983532) (xy 15.673324 -145.98396) (xy 20.13966 -145.98396) (xy 20.149724 -145.983525)
			(xy 20.168309 -145.97579) (xy 20.175728 -145.968974) (xy 20.195352 -145.949872) (xy 20.239091 -145.916919)
			(xy 20.287092 -145.890559) (xy 20.33837 -145.871333) (xy 20.39187 -145.859637) (xy 20.446492 -145.855712)
			(xy 20.501114 -145.859637) (xy 20.554614 -145.871333) (xy 20.605892 -145.890559) (xy 20.653893 -145.916919)
			(xy 20.697632 -145.949872) (xy 20.717256 -145.968974) (xy 20.724656 -145.975814) (xy 20.743255 -145.983532)
			(xy 20.753324 -145.98396) (xy 25.21966 -145.98396) (xy 25.229724 -145.983525) (xy 25.248309 -145.97579)
			(xy 25.255728 -145.968974) (xy 25.275352 -145.949872) (xy 25.319091 -145.916919) (xy 25.367092 -145.890559)
			(xy 25.41837 -145.871333) (xy 25.47187 -145.859637) (xy 25.526492 -145.855712) (xy 25.581114 -145.859637)
			(xy 25.634614 -145.871333) (xy 25.685892 -145.890559) (xy 25.733893 -145.916919) (xy 25.777632 -145.949872)
			(xy 25.797256 -145.968974) (xy 25.804656 -145.975814) (xy 25.823255 -145.983532) (xy 25.833324 -145.98396)
			(xy 30.29966 -145.98396) (xy 30.309724 -145.983525) (xy 30.328309 -145.97579) (xy 30.335728 -145.968974)
			(xy 30.355352 -145.949872) (xy 30.399091 -145.916919) (xy 30.447092 -145.890559) (xy 30.49837 -145.871333)
			(xy 30.55187 -145.859637) (xy 30.606492 -145.855712) (xy 30.661114 -145.859637) (xy 30.714614 -145.871333)
			(xy 30.765892 -145.890559) (xy 30.813893 -145.916919) (xy 30.857632 -145.949872) (xy 30.877256 -145.968974)
			(xy 30.884656 -145.975814) (xy 30.903255 -145.983532) (xy 30.913324 -145.98396) (xy 35.37966 -145.98396)
			(xy 35.389724 -145.983525) (xy 35.408309 -145.97579) (xy 35.415728 -145.968974) (xy 35.435352 -145.949872)
			(xy 35.479091 -145.916919) (xy 35.527092 -145.890559) (xy 35.57837 -145.871333) (xy 35.63187 -145.859637)
			(xy 35.686492 -145.855712) (xy 35.741114 -145.859637) (xy 35.794614 -145.871333) (xy 35.845892 -145.890559)
			(xy 35.893893 -145.916919) (xy 35.937632 -145.949872) (xy 35.957256 -145.968974) (xy 35.964656 -145.975814)
			(xy 35.983255 -145.983532) (xy 35.993324 -145.98396) (xy 38.111938 -145.98396) (xy 38.125908 -145.969482)
			(xy 38.974014 -145.121376) (xy 38.980866 -145.11398) (xy 38.988605 -145.095381) (xy 38.989 -145.085308)
			(xy 38.989 -120.754394) (xy 38.988576 -120.744324) (xy 38.98086 -120.725721) (xy 38.974014 -120.718326)
			(xy 37.696648 -119.44096) (xy 37.68925 -119.434115) (xy 37.670651 -119.42639) (xy 37.66058 -119.425974)
			(xy 23.896828 -119.425974) (xy 23.886741 -119.426389) (xy 23.868123 -119.434149) (xy 23.853959 -119.44851)
			(xy 23.849838 -119.457724) (xy 23.808436 -119.559324) (xy 23.814786 -119.58955) (xy 23.826216 -119.600472)
			(xy 23.889876 -119.662972) (xy 24.012235 -119.792829) (xy 24.128703 -119.927994) (xy 24.239049 -120.068202)
			(xy 24.343055 -120.213175) (xy 24.440517 -120.362626) (xy 24.531242 -120.51626) (xy 24.61505 -120.673774)
			(xy 24.691776 -120.834857) (xy 24.761268 -120.99919) (xy 24.823389 -121.166448) (xy 24.878016 -121.336302)
			(xy 24.925042 -121.508416) (xy 24.964373 -121.682449) (xy 24.995931 -121.858058) (xy 25.019655 -122.034896)
			(xy 25.035498 -122.212613) (xy 25.043428 -122.390859) (xy 25.043892 -122.48007) (xy 25.159471 -122.48007)
			(xy 25.16346 -122.339172) (xy 25.175414 -122.198725) (xy 25.195294 -122.05918) (xy 25.223037 -121.920983)
			(xy 25.258555 -121.784577) (xy 25.301732 -121.650398) (xy 25.352432 -121.518878) (xy 25.410492 -121.390436)
			(xy 25.475724 -121.265485) (xy 25.547922 -121.144424) (xy 25.626853 -121.027642) (xy 25.712264 -120.915513)
			(xy 25.803883 -120.808395) (xy 25.901415 -120.706632) (xy 26.004547 -120.61055) (xy 26.112951 -120.520457)
			(xy 26.226278 -120.43664) (xy 26.344165 -120.35937) (xy 26.466235 -120.288893) (xy 26.592097 -120.225434)
			(xy 26.721347 -120.169199) (xy 26.853572 -120.120365) (xy 26.988348 -120.07909) (xy 27.125243 -120.045507)
			(xy 27.263819 -120.019722) (xy 27.403632 -120.001818) (xy 27.544234 -119.991853) (xy 27.685174 -119.989858)
			(xy 27.826002 -119.995841) (xy 27.966265 -120.009781) (xy 28.105515 -120.031634) (xy 28.243306 -120.06133)
			(xy 28.379196 -120.098774) (xy 28.51275 -120.143846) (xy 28.64354 -120.196402) (xy 28.771147 -120.256273)
			(xy 28.895163 -120.323268) (xy 29.015189 -120.397171) (xy 29.130843 -120.477747) (xy 29.241752 -120.564736)
			(xy 29.347563 -120.657861) (xy 29.447935 -120.756823) (xy 29.542548 -120.861305) (xy 29.631099 -120.970973)
			(xy 29.713303 -121.085475) (xy 29.788897 -121.204444) (xy 29.85764 -121.327499) (xy 29.919311 -121.454246)
			(xy 29.973712 -121.584279) (xy 30.02067 -121.717182) (xy 30.060033 -121.852528) (xy 30.091676 -121.989885)
			(xy 30.115498 -122.128812) (xy 30.131421 -122.268864) (xy 30.139396 -122.409593) (xy 30.139894 -122.48007)
			(xy 30.139396 -122.550547) (xy 30.131421 -122.691276) (xy 30.115498 -122.831328) (xy 30.091676 -122.970255)
			(xy 30.060033 -123.107612) (xy 30.02067 -123.242958) (xy 29.973712 -123.375861) (xy 29.919311 -123.505894)
			(xy 29.85764 -123.632641) (xy 29.788897 -123.755696) (xy 29.713303 -123.874665) (xy 29.631099 -123.989167)
			(xy 29.542548 -124.098835) (xy 29.447935 -124.203317) (xy 29.347563 -124.302279) (xy 29.241752 -124.395404)
			(xy 29.130843 -124.482393) (xy 29.015189 -124.562969) (xy 28.895163 -124.636872) (xy 28.771147 -124.703867)
			(xy 28.64354 -124.763738) (xy 28.51275 -124.816294) (xy 28.379196 -124.861366) (xy 28.243306 -124.89881)
			(xy 28.105515 -124.928506) (xy 27.966265 -124.950359) (xy 27.826002 -124.964299) (xy 27.685174 -124.970282)
			(xy 27.544234 -124.968287) (xy 27.403632 -124.958322) (xy 27.263819 -124.940418) (xy 27.125243 -124.914633)
			(xy 26.988348 -124.88105) (xy 26.853572 -124.839775) (xy 26.721347 -124.790941) (xy 26.592097 -124.734706)
			(xy 26.466235 -124.671247) (xy 26.344165 -124.60077) (xy 26.226278 -124.5235) (xy 26.112951 -124.439683)
			(xy 26.004547 -124.34959) (xy 25.901415 -124.253508) (xy 25.803883 -124.151745) (xy 25.712264 -124.044627)
			(xy 25.626853 -123.932498) (xy 25.547922 -123.815716) (xy 25.475724 -123.694655) (xy 25.410492 -123.569704)
			(xy 25.352432 -123.441262) (xy 25.301732 -123.309742) (xy 25.258555 -123.175563) (xy 25.223037 -123.039157)
			(xy 25.195294 -122.90096) (xy 25.175414 -122.761415) (xy 25.16346 -122.620968) (xy 25.159471 -122.48007)
			(xy 25.043892 -122.48007) (xy 25.043387 -122.570147) (xy 25.035304 -122.750119) (xy 25.019155 -122.929548)
			(xy 24.994973 -123.108071) (xy 24.962805 -123.28533) (xy 24.922717 -123.460967) (xy 24.87479 -123.634628)
			(xy 24.819119 -123.805965) (xy 24.755817 -123.974631) (xy 24.685013 -124.140287) (xy 24.606847 -124.3026)
			(xy 24.521478 -124.461243) (xy 24.429077 -124.615895) (xy 24.329831 -124.766247) (xy 24.223939 -124.911994)
			(xy 24.111615 -125.052844) (xy 23.993085 -125.188513) (xy 23.868587 -125.318727) (xy 23.738373 -125.443225)
			(xy 23.602704 -125.561755) (xy 23.461854 -125.674079) (xy 23.316107 -125.779971) (xy 23.165755 -125.879217)
			(xy 23.011103 -125.971618) (xy 22.85246 -126.056987) (xy 22.690147 -126.135153) (xy 22.524491 -126.205957)
			(xy 22.355825 -126.269259) (xy 22.184488 -126.32493) (xy 22.010827 -126.372857) (xy 21.83519 -126.412945)
			(xy 21.657931 -126.445113) (xy 21.479408 -126.469295) (xy 21.299979 -126.485444) (xy 21.120007 -126.493527)
			(xy 21.02993 -126.494032) (xy 20.93918 -126.493526) (xy 20.757864 -126.485322) (xy 20.577105 -126.468931)
			(xy 20.397272 -126.444387) (xy 20.218732 -126.411739) (xy 20.04185 -126.371054) (xy 19.866987 -126.322416)
			(xy 19.694502 -126.265924) (xy 19.524747 -126.201693) (xy 19.358068 -126.129855) (xy 19.194807 -126.050556)
			(xy 19.035297 -125.963959) (xy 18.879864 -125.870241) (xy 18.728826 -125.769592) (xy 18.582492 -125.66222)
			(xy 18.441161 -125.548343) (xy 18.305121 -125.428195) (xy 18.174651 -125.30202) (xy 18.050018 -125.170076)
			(xy 17.931475 -125.032635) (xy 17.819267 -124.889975) (xy 17.713621 -124.74239) (xy 17.614754 -124.59018)
			(xy 17.522868 -124.433657) (xy 17.438151 -124.27314) (xy 17.399 -124.191268) (xy 17.393666 -124.179584)
			(xy 17.3736 -124.164598) (xy 17.264888 -124.148088) (xy 17.241266 -124.156216) (xy 17.232376 -124.165868)
			(xy 17.184455 -124.217229) (xy 17.083658 -124.315088) (xy 16.977503 -124.407108) (xy 16.866328 -124.492995)
			(xy 16.750487 -124.572477) (xy 16.630349 -124.6453) (xy 16.506295 -124.711232) (xy 16.37872 -124.770064)
			(xy 16.248031 -124.821609) (xy 16.114643 -124.865702) (xy 15.978981 -124.902204) (xy 15.841477 -124.930997)
			(xy 15.702568 -124.951991) (xy 15.562696 -124.965118) (xy 15.422307 -124.970337) (xy 15.281846 -124.967632)
			(xy 15.141762 -124.95701) (xy 15.002499 -124.938506) (xy 14.864501 -124.912178) (xy 14.728208 -124.87811)
			(xy 14.594052 -124.836411) (xy 14.462462 -124.787214) (xy 14.333855 -124.730674) (xy 14.208641 -124.666973)
			(xy 14.087218 -124.596312) (xy 13.969973 -124.518916) (xy 13.857279 -124.435032) (xy 13.749494 -124.344927)
			(xy 13.646962 -124.248887) (xy 13.550008 -124.147219) (xy 13.458942 -124.040245) (xy 13.374053 -123.928306)
			(xy 13.295611 -123.811758) (xy 13.223867 -123.690972) (xy 13.159047 -123.566333) (xy 13.101359 -123.438237)
			(xy 13.050986 -123.307092) (xy 13.008088 -123.173315) (xy 12.972802 -123.037332) (xy 12.94524 -122.899576)
			(xy 12.92549 -122.760485) (xy 12.913615 -122.620501) (xy 12.909653 -122.48007) (xy 12.913615 -122.339639)
			(xy 12.92549 -122.199655) (xy 12.94524 -122.060564) (xy 12.972802 -121.922808) (xy 13.008088 -121.786825)
			(xy 13.050986 -121.653048) (xy 13.101359 -121.521903) (xy 13.159047 -121.393807) (xy 13.223867 -121.269168)
			(xy 13.295611 -121.148382) (xy 13.374053 -121.031834) (xy 13.458942 -120.919895) (xy 13.550008 -120.812921)
			(xy 13.646962 -120.711253) (xy 13.749494 -120.615213) (xy 13.857279 -120.525108) (xy 13.969973 -120.441224)
			(xy 14.087218 -120.363828) (xy 14.208641 -120.293167) (xy 14.333855 -120.229466) (xy 14.462462 -120.172926)
			(xy 14.594052 -120.123729) (xy 14.728208 -120.08203) (xy 14.864501 -120.047962) (xy 15.002499 -120.021634)
			(xy 15.141762 -120.00313) (xy 15.281846 -119.992508) (xy 15.422307 -119.989803) (xy 15.562696 -119.995022)
			(xy 15.702568 -120.008149) (xy 15.841477 -120.029143) (xy 15.978981 -120.057936) (xy 16.114643 -120.094438)
			(xy 16.248031 -120.138531) (xy 16.37872 -120.190076) (xy 16.506295 -120.248908) (xy 16.630349 -120.31484)
			(xy 16.750487 -120.387663) (xy 16.866328 -120.467145) (xy 16.977503 -120.553032) (xy 17.083658 -120.645052)
			(xy 17.184455 -120.742911) (xy 17.232376 -120.794272) (xy 17.241266 -120.803924) (xy 17.264888 -120.812052)
			(xy 17.3736 -120.795542) (xy 17.393666 -120.780556) (xy 17.399 -120.768872) (xy 17.43793 -120.687468)
			(xy 17.522139 -120.527855) (xy 17.613434 -120.372186) (xy 17.71163 -120.220775) (xy 17.816529 -120.073929)
			(xy 17.927918 -119.931944) (xy 18.045574 -119.795106) (xy 18.169259 -119.663691) (xy 18.233644 -119.600472)
			(xy 18.245074 -119.58955) (xy 18.251424 -119.559324) (xy 18.210022 -119.457724) (xy 18.205826 -119.448564)
			(xy 18.191661 -119.434257) (xy 18.173097 -119.426464) (xy 18.163032 -119.425974) (xy 16.247364 -119.425974)
			(xy 16.214104 -119.42545) (xy 16.148155 -119.41676) (xy 16.083906 -119.399533) (xy 16.022456 -119.374064)
			(xy 15.964857 -119.340789) (xy 15.912097 -119.300278) (xy 15.888208 -119.27713) (xy 14.880844 -118.269766)
			(xy 14.857687 -118.245886) (xy 14.81718 -118.193123) (xy 14.783909 -118.135522) (xy 14.758443 -118.07407)
			(xy 14.74122 -118.009819) (xy 14.732533 -117.94387) (xy 14.732 -117.91061) (xy 14.732 -78.5114) (xy 14.731512 -78.501392)
			(xy 14.723852 -78.482901) (xy 14.709699 -78.468748) (xy 14.691208 -78.461088) (xy 14.6812 -78.4606)
			(xy 8.9154 -78.4606) (xy 8.88214 -78.460079) (xy 8.81619 -78.451391) (xy 8.751939 -78.434166) (xy 8.690488 -78.408697)
			(xy 8.632889 -78.375421) (xy 8.580129 -78.334908) (xy 8.556244 -78.311756) (xy 7.794244 -77.549756)
			(xy 7.771088 -77.525876) (xy 7.730582 -77.473112) (xy 7.697311 -77.415511) (xy 7.671847 -77.35406)
			(xy 7.654625 -77.289809) (xy 7.645939 -77.223859) (xy 7.6454 -77.1906) (xy 7.6454 -68.5546) (xy 7.645921 -68.52134)
			(xy 7.654609 -68.45539) (xy 7.671834 -68.391139) (xy 7.697303 -68.329688) (xy 7.730579 -68.272089)
			(xy 7.771092 -68.219329) (xy 7.794244 -68.195444) (xy 8.759444 -67.230244) (xy 8.783324 -67.207088)
			(xy 8.836088 -67.166582) (xy 8.893689 -67.133311) (xy 8.95514 -67.107847) (xy 9.019391 -67.090625)
			(xy 9.085341 -67.081939) (xy 9.1186 -67.0814) (xy 26.755598 -67.0814) (xy 26.764737 -67.081019) (xy 26.781852 -67.074604)
			(xy 26.795626 -67.062591) (xy 26.800302 -67.05473) (xy 26.849324 -66.963798) (xy 26.848054 -66.935858)
			(xy 26.840434 -66.924174) (xy 26.817257 -66.8879) (xy 26.777238 -66.811682) (xy 26.744774 -66.731953)
			(xy 26.72017 -66.649458) (xy 26.703657 -66.564971) (xy 26.695389 -66.479283) (xy 26.694892 -66.43624)
			(xy 26.695475 -66.389843) (xy 26.705104 -66.297552) (xy 26.724293 -66.206765) (xy 26.752834 -66.118471)
			(xy 26.771092 -66.075814) (xy 26.774906 -66.065871) (xy 26.774921 -66.044601) (xy 26.771092 -66.034666)
			(xy 26.752857 -65.992001) (xy 26.724325 -65.903707) (xy 26.705135 -65.812923) (xy 26.695496 -65.720635)
			(xy 26.694892 -65.67424) (xy 26.695475 -65.627843) (xy 26.705104 -65.535552) (xy 26.724293 -65.444765)
			(xy 26.752834 -65.356471) (xy 26.771092 -65.313814) (xy 26.774906 -65.303871) (xy 26.774921 -65.282601)
			(xy 26.771092 -65.272666) (xy 26.752857 -65.230001) (xy 26.724325 -65.141707) (xy 26.705135 -65.050923)
			(xy 26.695496 -64.958635) (xy 26.694892 -64.91224) (xy 26.69535 -64.871136) (xy 26.702932 -64.789277)
			(xy 26.718035 -64.708468) (xy 26.740529 -64.629397) (xy 26.770224 -64.552738) (xy 26.806865 -64.479147)
			(xy 26.85014 -64.40925) (xy 26.89968 -64.343645) (xy 26.955063 -64.282891) (xy 27.015814 -64.227506)
			(xy 27.081417 -64.177963) (xy 27.151312 -64.134685) (xy 27.224902 -64.09804) (xy 27.301559 -64.068342)
			(xy 27.380629 -64.045844) (xy 27.461438 -64.030738) (xy 27.543296 -64.023152) (xy 27.5844 -64.022732)
			(xy 27.630796 -64.023317) (xy 27.723086 -64.032951) (xy 27.813871 -64.052144) (xy 27.902163 -64.08069)
			(xy 27.944826 -64.098932) (xy 27.954768 -64.102738) (xy 27.976032 -64.102738) (xy 27.985974 -64.098932)
			(xy 28.028639 -64.080693) (xy 28.116932 -64.052154) (xy 28.207716 -64.032957) (xy 28.300004 -64.023311)
			(xy 28.3464 -64.022732) (xy 28.387502 -64.023192) (xy 28.469357 -64.030777) (xy 28.550162 -64.045883)
			(xy 28.629229 -64.06838) (xy 28.705882 -64.098077) (xy 28.779469 -64.13472) (xy 28.84936 -64.177996)
			(xy 28.91496 -64.227537) (xy 28.975709 -64.282919) (xy 29.031089 -64.343671) (xy 29.080627 -64.409273)
			(xy 29.1239 -64.479166) (xy 29.16054 -64.552754) (xy 29.190233 -64.629409) (xy 29.212726 -64.708477)
			(xy 29.227828 -64.789283) (xy 29.23541 -64.871137) (xy 29.235908 -64.91224) (xy 29.235321 -64.958636)
			(xy 29.225684 -65.050925) (xy 29.206487 -65.141708) (xy 29.17794 -65.229998) (xy 29.159708 -65.272666)
			(xy 29.155911 -65.282608) (xy 29.155926 -65.303864) (xy 29.159708 -65.313814) (xy 29.177944 -65.356479)
			(xy 29.206478 -65.444773) (xy 29.22567 -65.535557) (xy 29.235311 -65.627845) (xy 29.235908 -65.67424)
			(xy 29.235321 -65.720636) (xy 29.225684 -65.812925) (xy 29.206487 -65.903708) (xy 29.17794 -65.991998)
			(xy 29.159708 -66.034666) (xy 29.155911 -66.044608) (xy 29.155926 -66.065864) (xy 29.159708 -66.075814)
			(xy 29.177944 -66.118479) (xy 29.206478 -66.206773) (xy 29.22567 -66.297557) (xy 29.235311 -66.389845)
			(xy 29.235908 -66.43624) (xy 29.235412 -66.479282) (xy 29.227117 -66.564964) (xy 29.210589 -66.649445)
			(xy 29.185982 -66.731936) (xy 29.153527 -66.811667) (xy 29.113526 -66.887891) (xy 29.090366 -66.924174)
			(xy 29.082746 -66.935858) (xy 29.081476 -66.963798) (xy 29.130498 -67.05473) (xy 29.135175 -67.06259)
			(xy 29.148949 -67.074604) (xy 29.166063 -67.081018) (xy 29.175202 -67.0814) (xy 38.706806 -67.0814)
			(xy 38.716876 -67.080976) (xy 38.735479 -67.07326) (xy 38.742874 -67.066414) (xy 39.107872 -66.701416)
			(xy 39.114708 -66.694014) (xy 39.122417 -66.675416) (xy 39.122858 -66.665348) (xy 39.122858 -63.048896)
			(xy 39.102284 -63.021718) (xy 39.086028 -63.017146) (xy 39.04662 -63.005433) (xy 38.969959 -62.975721)
			(xy 38.896366 -62.939064) (xy 38.826468 -62.895774) (xy 38.760861 -62.846221) (xy 38.700105 -62.790827)
			(xy 38.644718 -62.730065) (xy 38.595172 -62.664453) (xy 38.55189 -62.59455) (xy 38.51524 -62.520953)
			(xy 38.485536 -62.444289) (xy 38.463031 -62.365211) (xy 38.447916 -62.284395) (xy 38.440321 -62.202529)
			(xy 38.439852 -62.16142) (xy 38.4403 -62.120284) (xy 38.447872 -62.03836) (xy 38.46298 -61.957487)
			(xy 38.485495 -61.878355) (xy 38.515225 -61.801642) (xy 38.551916 -61.728004) (xy 38.595253 -61.658071)
			(xy 38.619684 -61.624972) (xy 38.631114 -61.609732) (xy 38.628574 -61.571886) (xy 34.565844 -57.509156)
			(xy 34.542688 -57.485276) (xy 34.502182 -57.432512) (xy 34.468911 -57.374911) (xy 34.443447 -57.31346)
			(xy 34.426225 -57.249209) (xy 34.417539 -57.183259) (xy 34.417 -57.15) (xy 34.417 -46.433994) (xy 34.417522 -46.400734)
			(xy 34.42621 -46.334784) (xy 34.443436 -46.270534) (xy 34.468905 -46.209083) (xy 34.502182 -46.151485)
			(xy 34.542695 -46.098726) (xy 34.565844 -46.074838) (xy 57.171844 -23.468838) (xy 57.195722 -23.445678)
			(xy 57.248483 -23.405165) (xy 57.306083 -23.371888) (xy 57.367536 -23.346419) (xy 57.431788 -23.329193)
			(xy 57.497739 -23.320506) (xy 57.531 -23.319994) (xy 202.389994 -23.319994) (xy 202.423254 -23.320515)
			(xy 202.489205 -23.329201) (xy 202.553456 -23.346426) (xy 202.614908 -23.371894) (xy 202.672508 -23.40517)
			(xy 202.725268 -23.445682) (xy 202.74915 -23.468838) (xy 204.575156 -25.294844) (xy 204.598312 -25.318724)
			(xy 204.638818 -25.371488) (xy 204.672089 -25.429089) (xy 204.697553 -25.49054) (xy 204.714775 -25.554791)
			(xy 204.723461 -25.620741) (xy 204.724 -25.654) (xy 204.724 -33.112386) (xy 274.529546 -33.112386)
			(xy 274.529546 -33.02769) (xy 274.537597 -32.943376) (xy 274.553626 -32.86021) (xy 274.577487 -32.778943)
			(xy 274.608966 -32.700313) (xy 274.647777 -32.625032) (xy 274.693567 -32.55378) (xy 274.745923 -32.487204)
			(xy 274.804371 -32.425906) (xy 274.868381 -32.370441) (xy 274.937373 -32.321312) (xy 275.010723 -32.278963)
			(xy 275.087766 -32.243779) (xy 275.167805 -32.216077) (xy 275.250114 -32.196109) (xy 275.333949 -32.184056)
			(xy 275.41855 -32.180026) (xy 275.503151 -32.184056) (xy 275.586986 -32.196109) (xy 275.669295 -32.216077)
			(xy 275.749334 -32.243779) (xy 275.826377 -32.278963) (xy 275.899727 -32.321312) (xy 275.968719 -32.370441)
			(xy 276.032729 -32.425906) (xy 276.091177 -32.487204) (xy 276.143533 -32.55378) (xy 276.189323 -32.625032)
			(xy 276.228134 -32.700313) (xy 276.259613 -32.778943) (xy 276.283474 -32.86021) (xy 276.299503 -32.943376)
			(xy 276.307554 -33.02769) (xy 276.308058 -33.070038) (xy 276.307554 -33.112386) (xy 276.299503 -33.1967)
			(xy 276.283474 -33.279866) (xy 276.259613 -33.361133) (xy 276.228134 -33.439763) (xy 276.189323 -33.515044)
			(xy 276.143533 -33.586296) (xy 276.091177 -33.652872) (xy 276.032729 -33.71417) (xy 275.968719 -33.769635)
			(xy 275.899727 -33.818764) (xy 275.826377 -33.861113) (xy 275.749334 -33.896297) (xy 275.669295 -33.923999)
			(xy 275.586986 -33.943967) (xy 275.503151 -33.95602) (xy 275.41855 -33.960051) (xy 275.333949 -33.95602)
			(xy 275.250114 -33.943967) (xy 275.167805 -33.923999) (xy 275.087766 -33.896297) (xy 275.010723 -33.861113)
			(xy 274.937373 -33.818764) (xy 274.868381 -33.769635) (xy 274.804371 -33.71417) (xy 274.745923 -33.652872)
			(xy 274.693567 -33.586296) (xy 274.647777 -33.515044) (xy 274.608966 -33.439763) (xy 274.577487 -33.361133)
			(xy 274.553626 -33.279866) (xy 274.537597 -33.1967) (xy 274.529546 -33.112386) (xy 204.724 -33.112386)
			(xy 204.724 -38.03481) (xy 245.302523 -38.03481) (xy 245.302523 -37.864454) (xy 245.310508 -37.694286)
			(xy 245.32646 -37.524679) (xy 245.350345 -37.356007) (xy 245.382109 -37.188639) (xy 245.421684 -37.022944)
			(xy 245.468981 -36.859286) (xy 245.523898 -36.698025) (xy 245.586313 -36.539515) (xy 245.656089 -36.384105)
			(xy 245.733072 -36.232137) (xy 245.817094 -36.083943) (xy 245.90797 -35.939851) (xy 246.0055 -35.800177)
			(xy 246.10947 -35.665228) (xy 246.219651 -35.5353) (xy 246.3358 -35.41068) (xy 246.457664 -35.291641)
			(xy 246.584972 -35.178445) (xy 246.717447 -35.07134) (xy 246.854797 -34.970563) (xy 246.996719 -34.876334)
			(xy 247.142901 -34.788861) (xy 247.293024 -34.708336) (xy 247.446755 -34.634936) (xy 247.603758 -34.568822)
			(xy 247.763688 -34.51014) (xy 247.926192 -34.459019) (xy 248.090913 -34.415571) (xy 248.257491 -34.379892)
			(xy 248.425557 -34.35206) (xy 248.594743 -34.332136) (xy 248.764677 -34.320164) (xy 248.934986 -34.316171)
			(xy 249.105295 -34.320164) (xy 249.275229 -34.332136) (xy 249.444415 -34.35206) (xy 249.612481 -34.379892)
			(xy 249.779059 -34.415571) (xy 249.94378 -34.459019) (xy 250.106284 -34.51014) (xy 250.266214 -34.568822)
			(xy 250.423217 -34.634936) (xy 250.576948 -34.708336) (xy 250.727071 -34.788861) (xy 250.873253 -34.876334)
			(xy 251.015175 -34.970563) (xy 251.152525 -35.07134) (xy 251.285 -35.178445) (xy 251.412308 -35.291641)
			(xy 251.534172 -35.41068) (xy 251.650321 -35.5353) (xy 251.760502 -35.665228) (xy 251.864472 -35.800177)
			(xy 251.962002 -35.939851) (xy 252.052878 -36.083943) (xy 252.1369 -36.232137) (xy 252.213883 -36.384105)
			(xy 252.283659 -36.539515) (xy 252.346074 -36.698025) (xy 252.400991 -36.859286) (xy 252.448288 -37.022944)
			(xy 252.487863 -37.188639) (xy 252.504967 -37.278761) (xy 259.293102 -37.278761) (xy 259.293102 -37.194039)
			(xy 259.301155 -37.109702) (xy 259.317189 -37.026512) (xy 259.341057 -36.945222) (xy 259.372545 -36.86657)
			(xy 259.411367 -36.791267) (xy 259.45717 -36.719995) (xy 259.509541 -36.653399) (xy 259.568006 -36.592084)
			(xy 259.632034 -36.536603) (xy 259.701046 -36.48746) (xy 259.774416 -36.4451) (xy 259.851481 -36.409905)
			(xy 259.931543 -36.382196) (xy 260.013876 -36.362222) (xy 260.097735 -36.350165) (xy 260.18236 -36.346134)
			(xy 260.266985 -36.350165) (xy 260.350844 -36.362222) (xy 260.433177 -36.382196) (xy 260.513239 -36.409905)
			(xy 260.590304 -36.4451) (xy 260.663674 -36.48746) (xy 260.732686 -36.536603) (xy 260.796714 -36.592084)
			(xy 260.855179 -36.653399) (xy 260.90755 -36.719995) (xy 260.953353 -36.791267) (xy 260.992175 -36.86657)
			(xy 261.023663 -36.945222) (xy 261.047531 -37.026512) (xy 261.063565 -37.109702) (xy 261.071618 -37.194039)
			(xy 261.072122 -37.2364) (xy 261.071618 -37.278761) (xy 261.063565 -37.363098) (xy 261.047531 -37.446288)
			(xy 261.023663 -37.527578) (xy 260.992175 -37.60623) (xy 260.953353 -37.681533) (xy 260.90755 -37.752805)
			(xy 260.855179 -37.819401) (xy 260.796714 -37.880716) (xy 260.732686 -37.936197) (xy 260.663674 -37.98534)
			(xy 260.590304 -38.0277) (xy 260.513239 -38.062895) (xy 260.433177 -38.090604) (xy 260.350844 -38.110578)
			(xy 260.266985 -38.122635) (xy 260.18236 -38.126667) (xy 260.097735 -38.122635) (xy 260.013876 -38.110578)
			(xy 259.931543 -38.090604) (xy 259.851481 -38.062895) (xy 259.774416 -38.0277) (xy 259.701046 -37.98534)
			(xy 259.632034 -37.936197) (xy 259.568006 -37.880716) (xy 259.509541 -37.819401) (xy 259.45717 -37.752805)
			(xy 259.411367 -37.681533) (xy 259.372545 -37.60623) (xy 259.341057 -37.527578) (xy 259.317189 -37.446288)
			(xy 259.301155 -37.363098) (xy 259.293102 -37.278761) (xy 252.504967 -37.278761) (xy 252.519627 -37.356007)
			(xy 252.543512 -37.524679) (xy 252.559464 -37.694286) (xy 252.567449 -37.864454) (xy 252.567948 -37.949632)
			(xy 252.567449 -38.03481) (xy 252.559464 -38.204978) (xy 252.543512 -38.374585) (xy 252.519627 -38.543257)
			(xy 252.487863 -38.710625) (xy 252.448288 -38.87632) (xy 252.400991 -39.039978) (xy 252.350882 -39.18712)
			(xy 257.640836 -39.18712) (xy 257.641465 -39.140264) (xy 257.651373 -39.047077) (xy 257.671018 -38.955447)
			(xy 257.700183 -38.866389) (xy 257.718814 -38.823392) (xy 257.722591 -38.813952) (xy 257.723116 -38.793644)
			(xy 257.71983 -38.784022) (xy 257.705286 -38.745426) (xy 257.682591 -38.666124) (xy 257.667328 -38.585063)
			(xy 257.659626 -38.502938) (xy 257.659124 -38.461696) (xy 257.659628 -38.419335) (xy 257.667681 -38.334998)
			(xy 257.683715 -38.251808) (xy 257.707583 -38.170518) (xy 257.739071 -38.091866) (xy 257.777893 -38.016563)
			(xy 257.823696 -37.945291) (xy 257.876067 -37.878695) (xy 257.934532 -37.81738) (xy 257.99856 -37.761899)
			(xy 258.067572 -37.712756) (xy 258.140942 -37.670396) (xy 258.218007 -37.635201) (xy 258.298069 -37.607492)
			(xy 258.380402 -37.587518) (xy 258.464261 -37.575461) (xy 258.548886 -37.57143) (xy 258.633511 -37.575461)
			(xy 258.71737 -37.587518) (xy 258.799703 -37.607492) (xy 258.879765 -37.635201) (xy 258.95683 -37.670396)
			(xy 259.0302 -37.712756) (xy 259.099212 -37.761899) (xy 259.16324 -37.81738) (xy 259.221705 -37.878695)
			(xy 259.274076 -37.945291) (xy 259.319879 -38.016563) (xy 259.358701 -38.091866) (xy 259.390189 -38.170518)
			(xy 259.414057 -38.251808) (xy 259.430091 -38.334998) (xy 259.438144 -38.419335) (xy 259.438648 -38.461696)
			(xy 259.438331 -38.49433) (xy 259.433502 -38.559421) (xy 259.428996 -38.591744) (xy 259.427218 -38.603682)
			(xy 259.43433 -38.62578) (xy 259.506212 -38.700964) (xy 259.528056 -38.709092) (xy 259.53974 -38.707822)
			(xy 259.562407 -38.705593) (xy 259.607896 -38.703178) (xy 259.630672 -38.702996) (xy 259.671782 -38.703479)
			(xy 259.753652 -38.711065) (xy 259.834473 -38.726173) (xy 259.913554 -38.748676) (xy 259.990221 -38.778381)
			(xy 260.06382 -38.815034) (xy 260.133721 -38.858323) (xy 260.19933 -38.907879) (xy 260.260085 -38.963278)
			(xy 260.315468 -39.024047) (xy 260.365007 -39.089669) (xy 260.408278 -39.159581) (xy 260.444912 -39.233189)
			(xy 260.474597 -39.309864) (xy 260.49708 -39.388951) (xy 260.512167 -39.469776) (xy 260.519731 -39.551648)
			(xy 260.52018 -39.592758) (xy 260.519659 -39.635175) (xy 260.511589 -39.719623) (xy 260.495517 -39.80292)
			(xy 260.47159 -39.884309) (xy 260.440025 -39.963051) (xy 260.401108 -40.038431) (xy 260.355193 -40.109764)
			(xy 260.302698 -40.176404) (xy 260.244097 -40.237744) (xy 260.212332 -40.265858) (xy 260.203696 -40.273224)
			(xy 260.194806 -40.293036) (xy 260.194806 -40.392604) (xy 260.203696 -40.412416) (xy 260.212332 -40.419782)
			(xy 260.24409 -40.447905) (xy 260.302694 -40.509243) (xy 260.355193 -40.575881) (xy 260.401112 -40.647213)
			(xy 260.440033 -40.722591) (xy 260.471603 -40.801332) (xy 260.495535 -40.88272) (xy 260.511612 -40.966017)
			(xy 260.519688 -41.050465) (xy 260.52018 -41.092882) (xy 260.519705 -41.135309) (xy 260.511626 -41.219777)
			(xy 260.49554 -41.303091) (xy 260.471593 -41.384495) (xy 260.440002 -41.463249) (xy 260.401055 -41.538636)
			(xy 260.355107 -41.609972) (xy 260.302573 -41.676608) (xy 260.243933 -41.737938) (xy 260.179718 -41.793405)
			(xy 260.110513 -41.842505) (xy 260.036947 -41.884791) (xy 259.959689 -41.919879) (xy 259.919724 -41.93413)
			(xy 259.910326 -41.937432) (xy 259.895594 -41.950132) (xy 259.854446 -42.03065) (xy 259.852668 -42.049954)
			(xy 259.855462 -42.059606) (xy 259.867486 -42.101336) (xy 259.88432 -42.186539) (xy 259.892782 -42.272975)
			(xy 259.893308 -42.3164) (xy 259.892842 -42.358233) (xy 259.885017 -42.441532) (xy 259.869417 -42.523731)
			(xy 259.858256 -42.56405) (xy 259.85597 -42.573278) (xy 259.857676 -42.592201) (xy 259.861558 -42.60088)
			(xy 259.87502 -42.627804) (xy 259.879656 -42.63618) (xy 259.893889 -42.648965) (xy 259.902706 -42.652696)
			(xy 259.941221 -42.667831) (xy 260.015569 -42.704177) (xy 260.086221 -42.747271) (xy 260.152565 -42.79674)
			(xy 260.214028 -42.852157) (xy 260.270078 -42.913043) (xy 260.320231 -42.978871) (xy 260.364054 -43.049073)
			(xy 260.401167 -43.123041) (xy 260.431251 -43.200137) (xy 260.454044 -43.279693) (xy 260.469349 -43.361022)
			(xy 260.477035 -43.443421) (xy 260.477508 -43.4848) (xy 260.477004 -43.527148) (xy 260.468953 -43.611462)
			(xy 260.452924 -43.694628) (xy 260.429063 -43.775895) (xy 260.397584 -43.854525) (xy 260.358773 -43.929806)
			(xy 260.312983 -44.001058) (xy 260.260627 -44.067634) (xy 260.202179 -44.128932) (xy 260.138169 -44.184397)
			(xy 260.069177 -44.233526) (xy 259.995827 -44.275875) (xy 259.918784 -44.311059) (xy 259.838745 -44.338761)
			(xy 259.756436 -44.358729) (xy 259.672601 -44.370782) (xy 259.588 -44.374813) (xy 259.503399 -44.370782)
			(xy 259.419564 -44.358729) (xy 259.337255 -44.338761) (xy 259.257216 -44.311059) (xy 259.180173 -44.275875)
			(xy 259.106823 -44.233526) (xy 259.037831 -44.184397) (xy 258.973821 -44.128932) (xy 258.915373 -44.067634)
			(xy 258.863017 -44.001058) (xy 258.817227 -43.929806) (xy 258.778416 -43.854525) (xy 258.746937 -43.775895)
			(xy 258.723076 -43.694628) (xy 258.707047 -43.611462) (xy 258.698996 -43.527148) (xy 258.698492 -43.4848)
			(xy 258.698958 -43.442967) (xy 258.706783 -43.359668) (xy 258.722383 -43.277469) (xy 258.733544 -43.23715)
			(xy 258.73583 -43.227922) (xy 258.734124 -43.208999) (xy 258.730242 -43.20032) (xy 258.71678 -43.173396)
			(xy 258.712144 -43.16502) (xy 258.697911 -43.152235) (xy 258.689094 -43.148504) (xy 258.650579 -43.133369)
			(xy 258.576231 -43.097023) (xy 258.505579 -43.053929) (xy 258.439235 -43.00446) (xy 258.377772 -42.949043)
			(xy 258.321722 -42.888157) (xy 258.271569 -42.822329) (xy 258.227746 -42.752127) (xy 258.190633 -42.678159)
			(xy 258.160549 -42.601063) (xy 258.137756 -42.521507) (xy 258.122451 -42.440178) (xy 258.114765 -42.357779)
			(xy 258.114292 -42.3164) (xy 258.114767 -42.275174) (xy 258.122403 -42.193078) (xy 258.1376 -42.112039)
			(xy 258.160229 -42.032754) (xy 258.190094 -41.955902) (xy 258.226941 -41.882142) (xy 258.270452 -41.812106)
			(xy 258.320255 -41.746396) (xy 258.375923 -41.685574) (xy 258.406138 -41.657524) (xy 258.415282 -41.649142)
			(xy 258.423918 -41.62679) (xy 258.412488 -41.520618) (xy 258.39928 -41.500298) (xy 258.388612 -41.494202)
			(xy 258.352203 -41.47258) (xy 258.283247 -41.423422) (xy 258.219273 -41.367935) (xy 258.16086 -41.306622)
			(xy 258.108535 -41.240036) (xy 258.062773 -41.168781) (xy 258.023988 -41.093501) (xy 257.992529 -41.014876)
			(xy 257.968682 -40.933619) (xy 257.952663 -40.850463) (xy 257.944616 -40.766162) (xy 257.944112 -40.72382)
			(xy 257.944722 -40.676728) (xy 257.954664 -40.583071) (xy 257.974438 -40.490987) (xy 258.003824 -40.401506)
			(xy 258.022598 -40.358314) (xy 258.02655 -40.348334) (xy 258.026555 -40.32689) (xy 258.022598 -40.316912)
			(xy 258.004411 -40.274268) (xy 257.97595 -40.186031) (xy 257.956819 -40.095313) (xy 257.947225 -40.003097)
			(xy 257.946652 -39.95674) (xy 257.946693 -39.939388) (xy 257.947962 -39.904707) (xy 257.949192 -39.887398)
			(xy 257.949484 -39.87578) (xy 257.9409 -39.854212) (xy 257.932682 -39.845996) (xy 257.902445 -39.817967)
			(xy 257.846768 -39.757149) (xy 257.796958 -39.69144) (xy 257.753442 -39.621403) (xy 257.716595 -39.54764)
			(xy 257.686732 -39.470783) (xy 257.664109 -39.391493) (xy 257.648921 -39.310449) (xy 257.641298 -39.228347)
			(xy 257.640836 -39.18712) (xy 252.350882 -39.18712) (xy 252.346074 -39.201239) (xy 252.283659 -39.359749)
			(xy 252.213883 -39.515159) (xy 252.1369 -39.667127) (xy 252.052878 -39.815321) (xy 251.962002 -39.959413)
			(xy 251.864472 -40.099087) (xy 251.760502 -40.234036) (xy 251.650321 -40.363964) (xy 251.534172 -40.488584)
			(xy 251.412308 -40.607623) (xy 251.285 -40.720819) (xy 251.152525 -40.827924) (xy 251.015175 -40.928701)
			(xy 250.873253 -41.02293) (xy 250.727071 -41.110403) (xy 250.576948 -41.190928) (xy 250.423217 -41.264328)
			(xy 250.266214 -41.330442) (xy 250.106284 -41.389124) (xy 249.94378 -41.440245) (xy 249.779059 -41.483693)
			(xy 249.612481 -41.519372) (xy 249.444415 -41.547204) (xy 249.275229 -41.567128) (xy 249.105295 -41.5791)
			(xy 248.934986 -41.583094) (xy 248.764677 -41.5791) (xy 248.594743 -41.567128) (xy 248.425557 -41.547204)
			(xy 248.257491 -41.519372) (xy 248.090913 -41.483693) (xy 247.926192 -41.440245) (xy 247.763688 -41.389124)
			(xy 247.603758 -41.330442) (xy 247.446755 -41.264328) (xy 247.293024 -41.190928) (xy 247.142901 -41.110403)
			(xy 246.996719 -41.02293) (xy 246.854797 -40.928701) (xy 246.717447 -40.827924) (xy 246.584972 -40.720819)
			(xy 246.457664 -40.607623) (xy 246.3358 -40.488584) (xy 246.219651 -40.363964) (xy 246.10947 -40.234036)
			(xy 246.0055 -40.099087) (xy 245.90797 -39.959413) (xy 245.817094 -39.815321) (xy 245.733072 -39.667127)
			(xy 245.656089 -39.515159) (xy 245.586313 -39.359749) (xy 245.523898 -39.201239) (xy 245.468981 -39.039978)
			(xy 245.421684 -38.87632) (xy 245.382109 -38.710625) (xy 245.350345 -38.543257) (xy 245.32646 -38.374585)
			(xy 245.310508 -38.204978) (xy 245.302523 -38.03481) (xy 204.724 -38.03481) (xy 204.724 -44.995338)
			(xy 204.72443 -45.005405) (xy 204.732154 -45.023999) (xy 204.738986 -45.031406) (xy 205.316328 -45.608748)
			(xy 205.323726 -45.615596) (xy 205.342324 -45.623328) (xy 205.352396 -45.623734) (xy 212.598508 -45.623734)
			(xy 212.631768 -45.624256) (xy 212.697719 -45.632943) (xy 212.761971 -45.650168) (xy 212.823423 -45.675635)
			(xy 212.881024 -45.708908) (xy 212.933786 -45.749418) (xy 212.957664 -45.772578) (xy 214.509604 -47.324518)
			(xy 214.532763 -47.348397) (xy 214.573277 -47.401158) (xy 214.606553 -47.458758) (xy 214.632023 -47.52021)
			(xy 214.649251 -47.584462) (xy 214.657941 -47.650413) (xy 214.658448 -47.683674) (xy 214.658448 -48.327818)
			(xy 257.330448 -48.327818) (xy 257.331032 -48.281422) (xy 257.340676 -48.189134) (xy 257.359872 -48.09835)
			(xy 257.38841 -48.010057) (xy 257.406648 -47.967392) (xy 257.410445 -47.957447) (xy 257.410452 -47.936186)
			(xy 257.406648 -47.926244) (xy 257.388413 -47.883578) (xy 257.359865 -47.795287) (xy 257.340669 -47.704503)
			(xy 257.331034 -47.612214) (xy 257.330448 -47.565818) (xy 257.330952 -47.52347) (xy 257.339003 -47.439156)
			(xy 257.355032 -47.35599) (xy 257.378893 -47.274723) (xy 257.410372 -47.196093) (xy 257.449183 -47.120812)
			(xy 257.494973 -47.04956) (xy 257.547329 -46.982984) (xy 257.605777 -46.921686) (xy 257.669787 -46.866221)
			(xy 257.738779 -46.817092) (xy 257.812129 -46.774743) (xy 257.889172 -46.739559) (xy 257.969211 -46.711857)
			(xy 258.05152 -46.691889) (xy 258.135355 -46.679836) (xy 258.219956 -46.675806) (xy 258.304557 -46.679836)
			(xy 258.388392 -46.691889) (xy 258.470701 -46.711857) (xy 258.55074 -46.739559) (xy 258.627783 -46.774743)
			(xy 258.701133 -46.817092) (xy 258.770125 -46.866221) (xy 258.834135 -46.921686) (xy 258.892583 -46.982984)
			(xy 258.944939 -47.04956) (xy 258.990729 -47.120812) (xy 259.02954 -47.196093) (xy 259.061019 -47.274723)
			(xy 259.08488 -47.35599) (xy 259.100909 -47.439156) (xy 259.10896 -47.52347) (xy 259.109464 -47.565818)
			(xy 259.108891 -47.612214) (xy 259.099244 -47.704503) (xy 259.080045 -47.795286) (xy 259.051504 -47.88358)
			(xy 259.033264 -47.926244) (xy 259.029445 -47.936182) (xy 259.029452 -47.95745) (xy 259.033264 -47.967392)
			(xy 259.051512 -48.010053) (xy 259.080056 -48.098346) (xy 259.099248 -48.189131) (xy 259.10888 -48.281422)
			(xy 259.109464 -48.327818) (xy 259.10896 -48.370166) (xy 259.100909 -48.45448) (xy 259.08488 -48.537646)
			(xy 259.061019 -48.618913) (xy 259.02954 -48.697543) (xy 258.990729 -48.772824) (xy 258.944939 -48.844076)
			(xy 258.892583 -48.910652) (xy 258.834135 -48.97195) (xy 258.770125 -49.027415) (xy 258.701133 -49.076544)
			(xy 258.627783 -49.118893) (xy 258.55074 -49.154077) (xy 258.470701 -49.181779) (xy 258.388392 -49.201747)
			(xy 258.304557 -49.2138) (xy 258.219956 -49.217831) (xy 258.135355 -49.2138) (xy 258.05152 -49.201747)
			(xy 257.969211 -49.181779) (xy 257.889172 -49.154077) (xy 257.812129 -49.118893) (xy 257.738779 -49.076544)
			(xy 257.669787 -49.027415) (xy 257.605777 -48.97195) (xy 257.547329 -48.910652) (xy 257.494973 -48.844076)
			(xy 257.449183 -48.772824) (xy 257.410372 -48.697543) (xy 257.378893 -48.618913) (xy 257.355032 -48.537646)
			(xy 257.339003 -48.45448) (xy 257.330952 -48.370166) (xy 257.330448 -48.327818) (xy 214.658448 -48.327818)
			(xy 214.658448 -64.802258) (xy 214.657929 -64.835519) (xy 214.649248 -64.901473) (xy 214.632028 -64.965728)
			(xy 214.606564 -65.027184) (xy 214.573293 -65.084789) (xy 214.532785 -65.137556) (xy 214.509604 -65.161414)
			(xy 213.167722 -66.503296) (xy 213.163912 -66.51244) (xy 213.146734 -66.551874) (xy 213.105841 -66.627551)
			(xy 213.057836 -66.698929) (xy 213.003165 -66.76534) (xy 212.94234 -66.826165) (xy 212.875929 -66.880836)
			(xy 212.804551 -66.928841) (xy 212.728874 -66.969734) (xy 212.68944 -66.986912) (xy 212.685014 -66.98888)
			(xy 212.676956 -66.994251) (xy 212.673438 -66.99758) (xy 210.638898 -69.03212) (xy 210.635386 -69.035785)
			(xy 210.629764 -69.044236) (xy 210.627722 -69.048884) (xy 210.610489 -69.089723) (xy 210.569044 -69.168083)
			(xy 210.520009 -69.241931) (xy 210.463871 -69.310535) (xy 210.401187 -69.373215) (xy 210.332579 -69.429348)
			(xy 210.258727 -69.478377) (xy 210.180364 -69.519817) (xy 210.139534 -69.537072) (xy 210.134889 -69.539117)
			(xy 210.126447 -69.544749) (xy 210.12277 -69.548248) (xy 204.47889 -75.192128) (xy 204.455011 -75.215287)
			(xy 204.402249 -75.255799) (xy 204.344649 -75.289075) (xy 204.283197 -75.314545) (xy 204.218945 -75.331772)
			(xy 204.152995 -75.340463) (xy 204.119734 -75.340972) (xy 176.652682 -75.340972) (xy 176.643924 -75.341281)
			(xy 176.627417 -75.347122) (xy 176.620424 -75.352402) (xy 176.599914 -75.368614) (xy 176.555298 -75.395867)
			(xy 176.507378 -75.416771) (xy 176.457053 -75.430934) (xy 176.405264 -75.438091) (xy 176.379124 -75.438508)
			(xy 176.352294 -75.438054) (xy 176.299162 -75.43054) (xy 176.247606 -75.415657) (xy 176.198644 -75.393698)
			(xy 176.153242 -75.365096) (xy 176.13249 -75.348084) (xy 176.126806 -75.343531) (xy 176.113512 -75.3376)
			(xy 176.106328 -75.3364) (xy 176.073591 -75.331448) (xy 176.009681 -75.31415) (xy 175.948559 -75.288695)
			(xy 175.891263 -75.255515) (xy 175.838764 -75.215171) (xy 175.81499 -75.192128) (xy 169.598848 -68.975986)
			(xy 169.591451 -68.969139) (xy 169.572852 -68.96141) (xy 169.56278 -68.961) (xy 165.087808 -68.961)
			(xy 165.077737 -68.961422) (xy 165.059131 -68.969134) (xy 165.05174 -68.975986) (xy 158.835598 -75.192128)
			(xy 158.811719 -75.215287) (xy 158.758957 -75.2558) (xy 158.701357 -75.289077) (xy 158.639906 -75.314548)
			(xy 158.575654 -75.331776) (xy 158.509703 -75.340468) (xy 158.476442 -75.340972) (xy 136.173972 -75.340972)
			(xy 136.140712 -75.340449) (xy 136.074763 -75.331759) (xy 136.010512 -75.314533) (xy 135.949062 -75.289064)
			(xy 135.891463 -75.25579) (xy 135.838702 -75.215279) (xy 135.814816 -75.192128) (xy 129.598674 -68.975986)
			(xy 129.591278 -68.969134) (xy 129.572679 -68.961396) (xy 129.562606 -68.961) (xy 125.087634 -68.961)
			(xy 125.077569 -68.961435) (xy 125.058982 -68.969167) (xy 125.051566 -68.975986) (xy 118.835424 -75.192128)
			(xy 118.811544 -75.215284) (xy 118.75878 -75.255789) (xy 118.701179 -75.289057) (xy 118.639727 -75.314519)
			(xy 118.575476 -75.331738) (xy 118.509527 -75.34042) (xy 118.476268 -75.340972) (xy 96.173798 -75.340972)
			(xy 96.140538 -75.340451) (xy 96.074586 -75.331764) (xy 96.010334 -75.31454) (xy 95.948881 -75.289074)
			(xy 95.891279 -75.255801) (xy 95.838516 -75.215292) (xy 95.814642 -75.192128) (xy 89.5985 -68.975986)
			(xy 89.591106 -68.96913) (xy 89.572507 -68.961382) (xy 89.562432 -68.961) (xy 85.08746 -68.961) (xy 85.077393 -68.961431)
			(xy 85.058799 -68.969155) (xy 85.051392 -68.975986) (xy 78.83525 -75.192128) (xy 78.81137 -75.215285)
			(xy 78.758607 -75.255793) (xy 78.701007 -75.289064) (xy 78.639555 -75.314529) (xy 78.575304 -75.331752)
			(xy 78.509354 -75.340437) (xy 78.476094 -75.340972) (xy 56.173878 -75.340972) (xy 56.140618 -75.340449)
			(xy 56.074668 -75.331761) (xy 56.010417 -75.314535) (xy 55.948966 -75.289067) (xy 55.891366 -75.255792)
			(xy 55.838605 -75.215282) (xy 55.814722 -75.192128) (xy 49.59858 -68.975986) (xy 49.591185 -68.969133)
			(xy 49.572586 -68.961393) (xy 49.562512 -68.961) (xy 39.862252 -68.961) (xy 39.852186 -68.961432)
			(xy 39.833594 -68.969159) (xy 39.826184 -68.975986) (xy 38.876986 -69.925184) (xy 38.870143 -69.932583)
			(xy 38.862426 -69.951182) (xy 38.862 -69.961252) (xy 38.862 -74.601578) (xy 38.862438 -74.611642)
			(xy 38.870172 -74.630226) (xy 38.876986 -74.637646) (xy 41.999351 -77.760011) (xy 61.960756 -77.760011)
			(xy 61.960756 -77.675289) (xy 61.968809 -77.590952) (xy 61.984843 -77.507762) (xy 62.008711 -77.426472)
			(xy 62.040199 -77.34782) (xy 62.079021 -77.272517) (xy 62.124824 -77.201245) (xy 62.177195 -77.134649)
			(xy 62.23566 -77.073334) (xy 62.299688 -77.017853) (xy 62.3687 -76.96871) (xy 62.44207 -76.92635)
			(xy 62.519135 -76.891155) (xy 62.599197 -76.863446) (xy 62.68153 -76.843472) (xy 62.765389 -76.831415)
			(xy 62.850014 -76.827384) (xy 62.934639 -76.831415) (xy 63.018498 -76.843472) (xy 63.100831 -76.863446)
			(xy 63.180893 -76.891155) (xy 63.257958 -76.92635) (xy 63.331328 -76.96871) (xy 63.40034 -77.017853)
			(xy 63.464368 -77.073334) (xy 63.522833 -77.134649) (xy 63.575204 -77.201245) (xy 63.621007 -77.272517)
			(xy 63.659829 -77.34782) (xy 63.691317 -77.426472) (xy 63.715185 -77.507762) (xy 63.731219 -77.590952)
			(xy 63.739272 -77.675289) (xy 63.739776 -77.71765) (xy 63.739272 -77.760011) (xy 101.960676 -77.760011)
			(xy 101.960676 -77.675289) (xy 101.968729 -77.590952) (xy 101.984763 -77.507762) (xy 102.008631 -77.426472)
			(xy 102.040119 -77.34782) (xy 102.078941 -77.272517) (xy 102.124744 -77.201245) (xy 102.177115 -77.134649)
			(xy 102.23558 -77.073334) (xy 102.299608 -77.017853) (xy 102.36862 -76.96871) (xy 102.44199 -76.92635)
			(xy 102.519055 -76.891155) (xy 102.599117 -76.863446) (xy 102.68145 -76.843472) (xy 102.765309 -76.831415)
			(xy 102.849934 -76.827384) (xy 102.934559 -76.831415) (xy 103.018418 -76.843472) (xy 103.100751 -76.863446)
			(xy 103.180813 -76.891155) (xy 103.257878 -76.92635) (xy 103.331248 -76.96871) (xy 103.40026 -77.017853)
			(xy 103.464288 -77.073334) (xy 103.522753 -77.134649) (xy 103.575124 -77.201245) (xy 103.620927 -77.272517)
			(xy 103.659749 -77.34782) (xy 103.691237 -77.426472) (xy 103.715105 -77.507762) (xy 103.731139 -77.590952)
			(xy 103.739192 -77.675289) (xy 103.739696 -77.71765) (xy 103.739192 -77.760011) (xy 141.96085 -77.760011)
			(xy 141.96085 -77.675289) (xy 141.968903 -77.590952) (xy 141.984937 -77.507762) (xy 142.008805 -77.426472)
			(xy 142.040293 -77.34782) (xy 142.079115 -77.272517) (xy 142.124918 -77.201245) (xy 142.177289 -77.134649)
			(xy 142.235754 -77.073334) (xy 142.299782 -77.017853) (xy 142.368794 -76.96871) (xy 142.442164 -76.92635)
			(xy 142.519229 -76.891155) (xy 142.599291 -76.863446) (xy 142.681624 -76.843472) (xy 142.765483 -76.831415)
			(xy 142.850108 -76.827384) (xy 142.934733 -76.831415) (xy 143.018592 -76.843472) (xy 143.100925 -76.863446)
			(xy 143.180987 -76.891155) (xy 143.258052 -76.92635) (xy 143.331422 -76.96871) (xy 143.400434 -77.017853)
			(xy 143.464462 -77.073334) (xy 143.522927 -77.134649) (xy 143.575298 -77.201245) (xy 143.621101 -77.272517)
			(xy 143.659923 -77.34782) (xy 143.691411 -77.426472) (xy 143.715279 -77.507762) (xy 143.731313 -77.590952)
			(xy 143.739366 -77.675289) (xy 143.73987 -77.71765) (xy 143.739366 -77.760011) (xy 181.961024 -77.760011)
			(xy 181.961024 -77.675289) (xy 181.969077 -77.590952) (xy 181.985111 -77.507762) (xy 182.008979 -77.426472)
			(xy 182.040467 -77.34782) (xy 182.079289 -77.272517) (xy 182.125092 -77.201245) (xy 182.177463 -77.134649)
			(xy 182.235928 -77.073334) (xy 182.299956 -77.017853) (xy 182.368968 -76.96871) (xy 182.442338 -76.92635)
			(xy 182.519403 -76.891155) (xy 182.599465 -76.863446) (xy 182.681798 -76.843472) (xy 182.765657 -76.831415)
			(xy 182.850282 -76.827384) (xy 182.934907 -76.831415) (xy 183.018766 -76.843472) (xy 183.101099 -76.863446)
			(xy 183.181161 -76.891155) (xy 183.258226 -76.92635) (xy 183.331596 -76.96871) (xy 183.400608 -77.017853)
			(xy 183.464636 -77.073334) (xy 183.523101 -77.134649) (xy 183.575472 -77.201245) (xy 183.621275 -77.272517)
			(xy 183.660097 -77.34782) (xy 183.691585 -77.426472) (xy 183.715453 -77.507762) (xy 183.731487 -77.590952)
			(xy 183.73954 -77.675289) (xy 183.740044 -77.71765) (xy 183.73954 -77.760011) (xy 183.731487 -77.844348)
			(xy 183.715453 -77.927538) (xy 183.691585 -78.008828) (xy 183.660097 -78.08748) (xy 183.621275 -78.162783)
			(xy 183.575472 -78.234055) (xy 183.523101 -78.300651) (xy 183.464636 -78.361966) (xy 183.400608 -78.417447)
			(xy 183.331596 -78.46659) (xy 183.258226 -78.50895) (xy 183.181161 -78.544145) (xy 183.101099 -78.571854)
			(xy 183.018766 -78.591828) (xy 182.934907 -78.603885) (xy 182.850282 -78.607917) (xy 182.765657 -78.603885)
			(xy 182.681798 -78.591828) (xy 182.599465 -78.571854) (xy 182.519403 -78.544145) (xy 182.442338 -78.50895)
			(xy 182.368968 -78.46659) (xy 182.299956 -78.417447) (xy 182.235928 -78.361966) (xy 182.177463 -78.300651)
			(xy 182.125092 -78.234055) (xy 182.079289 -78.162783) (xy 182.040467 -78.08748) (xy 182.008979 -78.008828)
			(xy 181.985111 -77.927538) (xy 181.969077 -77.844348) (xy 181.961024 -77.760011) (xy 143.739366 -77.760011)
			(xy 143.731313 -77.844348) (xy 143.715279 -77.927538) (xy 143.691411 -78.008828) (xy 143.659923 -78.08748)
			(xy 143.621101 -78.162783) (xy 143.575298 -78.234055) (xy 143.522927 -78.300651) (xy 143.464462 -78.361966)
			(xy 143.400434 -78.417447) (xy 143.331422 -78.46659) (xy 143.258052 -78.50895) (xy 143.180987 -78.544145)
			(xy 143.100925 -78.571854) (xy 143.018592 -78.591828) (xy 142.934733 -78.603885) (xy 142.850108 -78.607917)
			(xy 142.765483 -78.603885) (xy 142.681624 -78.591828) (xy 142.599291 -78.571854) (xy 142.519229 -78.544145)
			(xy 142.442164 -78.50895) (xy 142.368794 -78.46659) (xy 142.299782 -78.417447) (xy 142.235754 -78.361966)
			(xy 142.177289 -78.300651) (xy 142.124918 -78.234055) (xy 142.079115 -78.162783) (xy 142.040293 -78.08748)
			(xy 142.008805 -78.008828) (xy 141.984937 -77.927538) (xy 141.968903 -77.844348) (xy 141.96085 -77.760011)
			(xy 103.739192 -77.760011) (xy 103.731139 -77.844348) (xy 103.715105 -77.927538) (xy 103.691237 -78.008828)
			(xy 103.659749 -78.08748) (xy 103.620927 -78.162783) (xy 103.575124 -78.234055) (xy 103.522753 -78.300651)
			(xy 103.464288 -78.361966) (xy 103.40026 -78.417447) (xy 103.331248 -78.46659) (xy 103.257878 -78.50895)
			(xy 103.180813 -78.544145) (xy 103.100751 -78.571854) (xy 103.018418 -78.591828) (xy 102.934559 -78.603885)
			(xy 102.849934 -78.607917) (xy 102.765309 -78.603885) (xy 102.68145 -78.591828) (xy 102.599117 -78.571854)
			(xy 102.519055 -78.544145) (xy 102.44199 -78.50895) (xy 102.36862 -78.46659) (xy 102.299608 -78.417447)
			(xy 102.23558 -78.361966) (xy 102.177115 -78.300651) (xy 102.124744 -78.234055) (xy 102.078941 -78.162783)
			(xy 102.040119 -78.08748) (xy 102.008631 -78.008828) (xy 101.984763 -77.927538) (xy 101.968729 -77.844348)
			(xy 101.960676 -77.760011) (xy 63.739272 -77.760011) (xy 63.731219 -77.844348) (xy 63.715185 -77.927538)
			(xy 63.691317 -78.008828) (xy 63.659829 -78.08748) (xy 63.621007 -78.162783) (xy 63.575204 -78.234055)
			(xy 63.522833 -78.300651) (xy 63.464368 -78.361966) (xy 63.40034 -78.417447) (xy 63.331328 -78.46659)
			(xy 63.257958 -78.50895) (xy 63.180893 -78.544145) (xy 63.100831 -78.571854) (xy 63.018498 -78.591828)
			(xy 62.934639 -78.603885) (xy 62.850014 -78.607917) (xy 62.765389 -78.603885) (xy 62.68153 -78.591828)
			(xy 62.599197 -78.571854) (xy 62.519135 -78.544145) (xy 62.44207 -78.50895) (xy 62.3687 -78.46659)
			(xy 62.299688 -78.417447) (xy 62.23566 -78.361966) (xy 62.177195 -78.300651) (xy 62.124824 -78.234055)
			(xy 62.079021 -78.162783) (xy 62.040199 -78.08748) (xy 62.008711 -78.008828) (xy 61.984843 -77.927538)
			(xy 61.968809 -77.844348) (xy 61.960756 -77.760011) (xy 41.999351 -77.760011) (xy 47.028354 -82.789014)
			(xy 47.035751 -82.795861) (xy 47.054351 -82.803589) (xy 47.064422 -82.804) (xy 149.098 -82.804) (xy 149.13126 -82.804521)
			(xy 149.19721 -82.813209) (xy 149.261461 -82.830434) (xy 149.322912 -82.855903) (xy 149.380511 -82.889179)
			(xy 149.433271 -82.929692) (xy 149.457156 -82.952844) (xy 157.294326 -90.790014) (xy 157.301722 -90.796866)
			(xy 157.320321 -90.804604) (xy 157.330394 -90.805) (xy 178.638454 -90.805) (xy 178.64745 -90.804695)
			(xy 178.664374 -90.798594) (xy 178.671474 -90.793062) (xy 178.692204 -90.776117) (xy 178.737517 -90.747595)
			(xy 178.786374 -90.725693) (xy 178.837816 -90.710843) (xy 178.890829 -90.703338) (xy 178.9176 -90.702892)
			(xy 178.944368 -90.703364) (xy 178.997375 -90.710885) (xy 179.048811 -90.725736) (xy 179.097668 -90.747628)
			(xy 179.142987 -90.77613) (xy 179.163726 -90.793062) (xy 179.17083 -90.798594) (xy 179.187748 -90.80472)
			(xy 179.196746 -90.805) (xy 179.542186 -90.805) (xy 179.54916 -90.804748) (xy 179.562563 -90.800878)
			(xy 179.568602 -90.79738) (xy 179.591248 -90.783987) (xy 179.639439 -90.762873) (xy 179.690074 -90.748584)
			(xy 179.742193 -90.741392) (xy 179.7685 -90.740992) (xy 179.794805 -90.741419) (xy 179.846919 -90.748616)
			(xy 179.897551 -90.762902) (xy 179.945742 -90.784007) (xy 179.968398 -90.79738) (xy 179.974456 -90.800831)
			(xy 179.987848 -90.804686) (xy 179.994814 -90.805) (xy 200.789032 -90.805) (xy 200.814178 -90.788744)
			(xy 200.820274 -90.775028) (xy 200.831959 -90.750287) (xy 200.861364 -90.704146) (xy 200.897059 -90.662679)
			(xy 200.938311 -90.626736) (xy 200.984276 -90.597055) (xy 201.034008 -90.574244) (xy 201.08649 -90.558772)
			(xy 201.140643 -90.550956) (xy 201.195357 -90.550956) (xy 201.24951 -90.558772) (xy 201.301992 -90.574244)
			(xy 201.351724 -90.597055) (xy 201.397689 -90.626736) (xy 201.438941 -90.662679) (xy 201.474636 -90.704146)
			(xy 201.504041 -90.750287) (xy 201.515726 -90.775028) (xy 201.521822 -90.788744) (xy 201.546968 -90.805)
			(xy 209.574384 -90.805) (xy 209.581256 -90.804802) (xy 209.594513 -90.801186) (xy 209.600546 -90.797888)
			(xy 209.635113 -90.777656) (xy 209.707223 -90.742783) (xy 209.782179 -90.714539) (xy 209.859371 -90.693153)
			(xy 209.938175 -90.678798) (xy 210.01795 -90.671592) (xy 210.058 -90.671142) (xy 210.098049 -90.671595)
			(xy 210.177822 -90.678818) (xy 210.256623 -90.69318) (xy 210.333815 -90.714563) (xy 210.408774 -90.742795)
			(xy 210.480893 -90.777648) (xy 210.515454 -90.797888) (xy 210.52148 -90.801198) (xy 210.534743 -90.804802)
			(xy 210.541616 -90.805) (xy 219.276422 -90.805) (xy 219.28649 -90.804573) (xy 219.305089 -90.796853)
			(xy 219.31249 -90.790014) (xy 219.329065 -90.77383) (xy 219.365466 -90.745174) (xy 219.405061 -90.721125)
			(xy 219.426028 -90.711274) (xy 219.439744 -90.705178) (xy 219.456 -90.680032) (xy 219.456 -79.859378)
			(xy 219.455573 -79.84931) (xy 219.447853 -79.830711) (xy 219.441014 -79.82331) (xy 219.421952 -79.803693)
			(xy 219.389072 -79.759981) (xy 219.362772 -79.712021) (xy 219.343591 -79.660796) (xy 219.331923 -79.607357)
			(xy 219.328007 -79.5528) (xy 219.331923 -79.498243) (xy 219.343591 -79.444804) (xy 219.362772 -79.393579)
			(xy 219.389072 -79.345619) (xy 219.421952 -79.301907) (xy 219.441014 -79.28229) (xy 219.447868 -79.274895)
			(xy 219.455613 -79.256296) (xy 219.456 -79.246222) (xy 219.456 -72.745854) (xy 219.455746 -72.730614)
			(xy 219.456266 -72.697353) (xy 219.464951 -72.631401) (xy 219.482174 -72.567148) (xy 219.50764 -72.505694)
			(xy 219.540912 -72.448092) (xy 219.581422 -72.395328) (xy 219.60459 -72.371458) (xy 228.896164 -63.079884)
			(xy 228.902727 -63.072632) (xy 228.91031 -63.05462) (xy 228.910638 -63.035079) (xy 228.907594 -63.025782)
			(xy 228.868732 -62.924944) (xy 228.844602 -62.907418) (xy 228.829362 -62.906656) (xy 228.729439 -62.901165)
			(xy 228.530104 -62.88318) (xy 228.331648 -62.857234) (xy 228.13439 -62.823368) (xy 227.938644 -62.781637)
			(xy 227.744724 -62.732107) (xy 227.552942 -62.674859) (xy 227.363604 -62.609983) (xy 227.177013 -62.537583)
			(xy 226.993468 -62.457776) (xy 226.813263 -62.370689) (xy 226.636687 -62.276461) (xy 226.464022 -62.175244)
			(xy 226.295546 -62.0672) (xy 226.131527 -61.952501) (xy 225.972229 -61.831332) (xy 225.817906 -61.703887)
			(xy 225.668806 -61.570368) (xy 225.525168 -61.430991) (xy 225.387221 -61.285979) (xy 225.255187 -61.135564)
			(xy 225.129276 -60.979986) (xy 225.009691 -60.819495) (xy 224.896624 -60.654348) (xy 224.790254 -60.484809)
			(xy 224.690753 -60.31115) (xy 224.59828 -60.133649) (xy 224.512982 -59.95259) (xy 224.434998 -59.768263)
			(xy 224.36445 -59.580964) (xy 224.301453 -59.390992) (xy 224.246108 -59.198652) (xy 224.198502 -59.004251)
			(xy 224.158713 -58.808102) (xy 224.126803 -58.610517) (xy 224.102825 -58.411814) (xy 224.086816 -58.212311)
			(xy 224.078802 -58.012326) (xy 224.078292 -57.912254) (xy 224.078794 -57.811546) (xy 224.086906 -57.610292)
			(xy 224.103115 -57.409529) (xy 224.127396 -57.209581) (xy 224.159708 -57.010773) (xy 224.199999 -56.813427)
			(xy 224.248205 -56.617864) (xy 224.304245 -56.424401) (xy 224.368031 -56.233351) (xy 224.439458 -56.045024)
			(xy 224.51841 -55.859726) (xy 224.60476 -55.677758) (xy 224.698366 -55.499414) (xy 224.799079 -55.324984)
			(xy 224.906733 -55.154752) (xy 225.021155 -54.988992) (xy 225.142159 -54.827973) (xy 225.269548 -54.671958)
			(xy 225.403116 -54.5212) (xy 225.542646 -54.375941) (xy 225.687913 -54.236419) (xy 225.838679 -54.10286)
			(xy 225.994702 -53.97548) (xy 226.155727 -53.854485) (xy 226.321493 -53.740073) (xy 226.491733 -53.632429)
			(xy 226.666168 -53.531727) (xy 226.844517 -53.43813) (xy 227.026491 -53.351791) (xy 227.211793 -53.27285)
			(xy 227.400124 -53.201434) (xy 227.591177 -53.137659) (xy 227.784644 -53.08163) (xy 227.98021 -53.033436)
			(xy 228.177558 -52.993156) (xy 228.376368 -52.960855) (xy 228.576317 -52.936586) (xy 228.777082 -52.920388)
			(xy 228.978336 -52.912288) (xy 229.079044 -52.911756) (xy 251.079 -52.911756) (xy 251.176834 -52.912225)
			(xy 251.372352 -52.919868) (xy 251.567421 -52.935154) (xy 251.761743 -52.95806) (xy 251.955021 -52.98855)
			(xy 252.146957 -53.026578) (xy 252.337259 -53.072086) (xy 252.525635 -53.125004) (xy 252.711796 -53.18525)
			(xy 252.895458 -53.252734) (xy 253.07634 -53.327351) (xy 253.254164 -53.408987) (xy 253.428658 -53.497517)
			(xy 253.599555 -53.592806) (xy 253.766593 -53.694707) (xy 253.929517 -53.803065) (xy 254.088077 -53.917714)
			(xy 254.242031 -54.038479) (xy 254.391142 -54.165173) (xy 254.535183 -54.297604) (xy 254.673933 -54.435569)
			(xy 254.740918 -54.506876) (xy 254.74803 -54.514496) (xy 254.766826 -54.522878) (xy 254.850392 -54.524402)
			(xy 254.860651 -54.524082) (xy 254.879641 -54.516338) (xy 254.887222 -54.509416) (xy 258.116324 -51.280314)
			(xy 258.122624 -51.273474) (xy 258.130275 -51.256542) (xy 258.131404 -51.237996) (xy 258.129024 -51.229006)
			(xy 258.097782 -51.129692) (xy 258.076446 -51.110896) (xy 258.062476 -51.108356) (xy 258.021904 -51.100582)
			(xy 257.9423 -51.078482) (xy 257.865088 -51.049094) (xy 257.790935 -51.012673) (xy 257.720478 -50.969532)
			(xy 257.654327 -50.920043) (xy 257.593049 -50.864632) (xy 257.537175 -50.803778) (xy 257.487184 -50.738004)
			(xy 257.443509 -50.667878) (xy 257.406525 -50.594003) (xy 257.376552 -50.517017) (xy 257.353847 -50.437583)
			(xy 257.338607 -50.356386) (xy 257.330962 -50.274126) (xy 257.330448 -50.232818) (xy 257.330952 -50.19047)
			(xy 257.339003 -50.106156) (xy 257.355032 -50.02299) (xy 257.378893 -49.941723) (xy 257.410372 -49.863093)
			(xy 257.449183 -49.787812) (xy 257.494973 -49.71656) (xy 257.547329 -49.649984) (xy 257.605777 -49.588686)
			(xy 257.669787 -49.533221) (xy 257.738779 -49.484092) (xy 257.812129 -49.441743) (xy 257.889172 -49.406559)
			(xy 257.969211 -49.378857) (xy 258.05152 -49.358889) (xy 258.135355 -49.346836) (xy 258.219956 -49.342806)
			(xy 258.304557 -49.346836) (xy 258.388392 -49.358889) (xy 258.470701 -49.378857) (xy 258.55074 -49.406559)
			(xy 258.627783 -49.441743) (xy 258.701133 -49.484092) (xy 258.770125 -49.533221) (xy 258.834135 -49.588686)
			(xy 258.892583 -49.649984) (xy 258.944939 -49.71656) (xy 258.990729 -49.787812) (xy 259.02954 -49.863093)
			(xy 259.061019 -49.941723) (xy 259.08488 -50.02299) (xy 259.100909 -50.106156) (xy 259.10896 -50.19047)
			(xy 259.109464 -50.232818) (xy 259.109027 -50.272979) (xy 259.101804 -50.352974) (xy 259.0874 -50.431993)
			(xy 259.065932 -50.509392) (xy 259.037575 -50.584542) (xy 259.002561 -50.656829) (xy 258.961173 -50.725666)
			(xy 258.913749 -50.790492) (xy 258.860675 -50.85078) (xy 258.831842 -50.87874) (xy 258.820412 -50.889408)
			(xy 258.813808 -50.919888) (xy 258.854448 -51.021996) (xy 258.858605 -51.031265) (xy 258.87282 -51.045754)
			(xy 258.891542 -51.053594) (xy 258.901692 -51.054) (xy 270.405606 -51.054) (xy 270.415676 -51.053576)
			(xy 270.434279 -51.04586) (xy 270.441674 -51.039014) (xy 271.257014 -50.223674) (xy 271.263866 -50.216278)
			(xy 271.271604 -50.197679) (xy 271.272 -50.187606) (xy 271.272 -45.940472) (xy 271.271637 -45.932024)
			(xy 271.266042 -45.916077) (xy 271.261078 -45.90923) (xy 271.235436 -45.875668) (xy 271.189905 -45.804524)
			(xy 271.151319 -45.729386) (xy 271.120025 -45.65093) (xy 271.096305 -45.569862) (xy 271.080373 -45.486912)
			(xy 271.072371 -45.402825) (xy 271.072372 -45.318359) (xy 271.080375 -45.234272) (xy 271.096309 -45.151322)
			(xy 271.12003 -45.070255) (xy 271.151325 -44.9918) (xy 271.189913 -44.916662) (xy 271.235445 -44.845519)
			(xy 271.261078 -44.81195) (xy 271.266076 -44.805123) (xy 271.27166 -44.789162) (xy 271.272 -44.780708)
			(xy 271.272 -43.18) (xy 271.272521 -43.14674) (xy 271.281209 -43.08079) (xy 271.298434 -43.016539)
			(xy 271.323903 -42.955088) (xy 271.357179 -42.897489) (xy 271.397692 -42.844729) (xy 271.420844 -42.820844)
			(xy 273.706844 -40.534844) (xy 273.730724 -40.511688) (xy 273.783488 -40.471182) (xy 273.841089 -40.437911)
			(xy 273.90254 -40.412447) (xy 273.966791 -40.395225) (xy 274.032741 -40.386539) (xy 274.066 -40.386)
			(xy 275.03882 -40.386) (xy 275.065998 -40.365426) (xy 275.07057 -40.348916) (xy 275.078468 -40.322567)
			(xy 275.100789 -40.272294) (xy 275.130098 -40.225748) (xy 275.165789 -40.183894) (xy 275.207121 -40.1476)
			(xy 275.253236 -40.117618) (xy 275.30318 -40.094571) (xy 275.355916 -40.078935) (xy 275.410351 -40.071035)
			(xy 275.465357 -40.071035) (xy 275.519792 -40.078935) (xy 275.572528 -40.094571) (xy 275.622472 -40.117618)
			(xy 275.668587 -40.1476) (xy 275.709919 -40.183894) (xy 275.74561 -40.225748) (xy 275.774919 -40.272294)
			(xy 275.79724 -40.322567) (xy 275.805138 -40.348916) (xy 275.80971 -40.365426) (xy 275.836888 -40.386)
			(xy 276.989032 -40.386) (xy 277.014178 -40.369744) (xy 277.020274 -40.356028) (xy 277.031959 -40.331287)
			(xy 277.061364 -40.285146) (xy 277.097059 -40.243679) (xy 277.138311 -40.207736) (xy 277.184276 -40.178055)
			(xy 277.234008 -40.155244) (xy 277.28649 -40.139772) (xy 277.340643 -40.131956) (xy 277.395357 -40.131956)
			(xy 277.44951 -40.139772) (xy 277.501992 -40.155244) (xy 277.551724 -40.178055) (xy 277.597689 -40.207736)
			(xy 277.638941 -40.243679) (xy 277.674636 -40.285146) (xy 277.704041 -40.331287) (xy 277.715726 -40.356028)
			(xy 277.721822 -40.369744) (xy 277.746968 -40.386) (xy 282.089606 -40.386) (xy 282.099676 -40.385576)
			(xy 282.118279 -40.37786) (xy 282.125674 -40.371014) (xy 283.322014 -39.174674) (xy 283.328866 -39.167278)
			(xy 283.336604 -39.148679) (xy 283.337 -39.138606) (xy 283.337 -33.068768) (xy 283.312108 -33.04032)
			(xy 283.293058 -33.03778) (xy 283.250948 -33.031537) (xy 283.168078 -33.012032) (xy 283.08745 -32.984698)
			(xy 283.009803 -32.949786) (xy 282.935847 -32.907615) (xy 282.866258 -32.858571) (xy 282.801673 -32.803103)
			(xy 282.742683 -32.741718) (xy 282.689828 -32.674978) (xy 282.643591 -32.603494) (xy 282.604396 -32.527918)
			(xy 282.5726 -32.448944) (xy 282.548495 -32.367293) (xy 282.532302 -32.283713) (xy 282.524168 -32.198967)
			(xy 282.524168 -32.113833) (xy 282.532302 -32.029087) (xy 282.548495 -31.945507) (xy 282.5726 -31.863856)
			(xy 282.604396 -31.784882) (xy 282.643591 -31.709306) (xy 282.689828 -31.637822) (xy 282.742683 -31.571082)
			(xy 282.801673 -31.509697) (xy 282.866258 -31.454229) (xy 282.935847 -31.405185) (xy 283.009803 -31.363014)
			(xy 283.08745 -31.328102) (xy 283.168078 -31.300768) (xy 283.250948 -31.281263) (xy 283.293058 -31.27502)
			(xy 283.312108 -31.27248) (xy 283.337 -31.244032) (xy 283.337 -30.099) (xy 283.337521 -30.06574)
			(xy 283.346209 -29.99979) (xy 283.363434 -29.935539) (xy 283.388903 -29.874088) (xy 283.422179 -29.816489)
			(xy 283.462692 -29.763729) (xy 283.485844 -29.739844) (xy 283.993844 -29.231844) (xy 284.017724 -29.208688)
			(xy 284.070488 -29.168182) (xy 284.128089 -29.134911) (xy 284.18954 -29.109447) (xy 284.253791 -29.092225)
			(xy 284.319741 -29.083539) (xy 284.353 -29.083) (xy 289.296856 -29.083) (xy 289.330117 -29.083519)
			(xy 289.39607 -29.092201) (xy 289.460325 -29.109422) (xy 289.52178 -29.134887) (xy 289.579382 -29.16816)
			(xy 289.632147 -29.208671) (xy 289.656012 -29.231844) (xy 290.046156 -29.621988) (xy 290.069315 -29.645867)
			(xy 290.109828 -29.698629) (xy 290.143104 -29.756229) (xy 290.168575 -29.817681) (xy 290.185804 -29.881932)
			(xy 290.194497 -29.947883) (xy 290.195 -29.981144) (xy 290.195 -30.300422) (xy 290.195427 -30.31049)
			(xy 290.203147 -30.329089) (xy 290.209986 -30.33649) (xy 290.229048 -30.356107) (xy 290.261928 -30.399819)
			(xy 290.288228 -30.447779) (xy 290.307409 -30.499004) (xy 290.319077 -30.552443) (xy 290.322993 -30.607)
			(xy 290.319077 -30.661557) (xy 290.307409 -30.714996) (xy 290.288228 -30.766221) (xy 290.261928 -30.814181)
			(xy 290.229048 -30.857893) (xy 290.209986 -30.87751) (xy 290.203132 -30.884905) (xy 290.195387 -30.903504)
			(xy 290.195 -30.913578) (xy 290.195 -31.297372) (xy 290.195436 -31.307436) (xy 290.203169 -31.326022)
			(xy 290.209986 -31.33344) (xy 290.229051 -31.353057) (xy 290.261939 -31.39677) (xy 290.288246 -31.444732)
			(xy 290.307433 -31.49596) (xy 290.319107 -31.549402) (xy 290.323029 -31.603965) (xy 290.319117 -31.658528)
			(xy 290.307453 -31.711973) (xy 290.288275 -31.763204) (xy 290.261977 -31.811171) (xy 290.229098 -31.85489)
			(xy 290.209986 -31.87446) (xy 290.20314 -31.881858) (xy 290.195414 -31.900457) (xy 290.195 -31.910528)
			(xy 290.195 -33.875472) (xy 290.195436 -33.885536) (xy 290.203169 -33.904122) (xy 290.209986 -33.91154)
			(xy 290.229051 -33.931157) (xy 290.261939 -33.97487) (xy 290.288246 -34.022832) (xy 290.307433 -34.07406)
			(xy 290.319107 -34.127502) (xy 290.323029 -34.182065) (xy 290.319117 -34.236628) (xy 290.307453 -34.290073)
			(xy 290.288275 -34.341304) (xy 290.261977 -34.389271) (xy 290.229098 -34.43299) (xy 290.209986 -34.45256)
			(xy 290.20314 -34.459958) (xy 290.195414 -34.478557) (xy 290.195 -34.488628) (xy 290.195 -35.018148)
			(xy 293.293796 -35.018148) (xy 293.293796 -34.933452) (xy 293.301847 -34.849138) (xy 293.317876 -34.765972)
			(xy 293.341737 -34.684705) (xy 293.373216 -34.606075) (xy 293.412027 -34.530794) (xy 293.457817 -34.459542)
			(xy 293.510173 -34.392966) (xy 293.568621 -34.331668) (xy 293.632631 -34.276203) (xy 293.701623 -34.227074)
			(xy 293.774973 -34.184725) (xy 293.852016 -34.149541) (xy 293.932055 -34.121839) (xy 294.014364 -34.101871)
			(xy 294.098199 -34.089818) (xy 294.1828 -34.085788) (xy 294.267401 -34.089818) (xy 294.351236 -34.101871)
			(xy 294.433545 -34.121839) (xy 294.513584 -34.149541) (xy 294.590627 -34.184725) (xy 294.663977 -34.227074)
			(xy 294.732969 -34.276203) (xy 294.796979 -34.331668) (xy 294.855427 -34.392966) (xy 294.907783 -34.459542)
			(xy 294.953573 -34.530794) (xy 294.992384 -34.606075) (xy 295.023863 -34.684705) (xy 295.047724 -34.765972)
			(xy 295.063753 -34.849138) (xy 295.071804 -34.933452) (xy 295.072308 -34.9758) (xy 295.071804 -35.018148)
			(xy 295.063753 -35.102462) (xy 295.047724 -35.185628) (xy 295.023863 -35.266895) (xy 294.992384 -35.345525)
			(xy 294.953573 -35.420806) (xy 294.907783 -35.492058) (xy 294.855427 -35.558634) (xy 294.796979 -35.619932)
			(xy 294.732969 -35.675397) (xy 294.663977 -35.724526) (xy 294.590627 -35.766875) (xy 294.513584 -35.802059)
			(xy 294.433545 -35.829761) (xy 294.351236 -35.849729) (xy 294.267401 -35.861782) (xy 294.1828 -35.865813)
			(xy 294.098199 -35.861782) (xy 294.014364 -35.849729) (xy 293.932055 -35.829761) (xy 293.852016 -35.802059)
			(xy 293.774973 -35.766875) (xy 293.701623 -35.724526) (xy 293.632631 -35.675397) (xy 293.568621 -35.619932)
			(xy 293.510173 -35.558634) (xy 293.457817 -35.492058) (xy 293.412027 -35.420806) (xy 293.373216 -35.345525)
			(xy 293.341737 -35.266895) (xy 293.317876 -35.185628) (xy 293.301847 -35.102462) (xy 293.293796 -35.018148)
			(xy 290.195 -35.018148) (xy 290.195 -39.900606) (xy 290.195424 -39.910676) (xy 290.20314 -39.929279)
			(xy 290.209986 -39.936674) (xy 290.644326 -40.371014) (xy 290.651722 -40.377866) (xy 290.670321 -40.385604)
			(xy 290.680394 -40.386) (xy 294.767 -40.386) (xy 294.80026 -40.386521) (xy 294.86621 -40.395209)
			(xy 294.930461 -40.412434) (xy 294.991912 -40.437903) (xy 295.049511 -40.471179) (xy 295.102271 -40.511692)
			(xy 295.126156 -40.534844) (xy 296.446956 -41.855644) (xy 296.470112 -41.879524) (xy 296.510618 -41.932288)
			(xy 296.543889 -41.989889) (xy 296.569353 -42.05134) (xy 296.586575 -42.115591) (xy 296.591345 -42.151808)
			(xy 298.200572 -42.151808) (xy 298.201202 -42.105406) (xy 298.210891 -42.013109) (xy 298.230144 -41.922323)
			(xy 298.258751 -41.834038) (xy 298.277026 -41.791382) (xy 298.280825 -41.781438) (xy 298.280828 -41.760177)
			(xy 298.277026 -41.750234) (xy 298.258766 -41.707572) (xy 298.230172 -41.619284) (xy 298.210915 -41.528502)
			(xy 298.201201 -41.436209) (xy 298.200572 -41.389808) (xy 298.20106 -41.348698) (xy 298.208647 -41.266829)
			(xy 298.223757 -41.18601) (xy 298.24626 -41.106929) (xy 298.275966 -41.030263) (xy 298.312619 -40.956666)
			(xy 298.355909 -40.886765) (xy 298.405464 -40.821157) (xy 298.460862 -40.760402) (xy 298.521631 -40.705019)
			(xy 298.587251 -40.655481) (xy 298.657163 -40.612209) (xy 298.73077 -40.575574) (xy 298.807444 -40.545888)
			(xy 298.88653 -40.523405) (xy 298.967353 -40.508316) (xy 299.049224 -40.50075) (xy 299.090334 -40.5003)
			(xy 299.136729 -40.500905) (xy 299.229017 -40.510544) (xy 299.319801 -40.529733) (xy 299.408095 -40.558265)
			(xy 299.45076 -40.5765) (xy 299.460702 -40.580306) (xy 299.481966 -40.580306) (xy 299.491908 -40.5765)
			(xy 299.534566 -40.558244) (xy 299.62286 -40.529703) (xy 299.713646 -40.510513) (xy 299.805938 -40.500883)
			(xy 299.852334 -40.5003) (xy 299.890619 -40.500677) (xy 299.966907 -40.507219) (xy 300.04235 -40.520304)
			(xy 300.116386 -40.539833) (xy 300.152562 -40.55237) (xy 300.160999 -40.555021) (xy 300.178669 -40.555021)
			(xy 300.187106 -40.55237) (xy 300.223291 -40.539863) (xy 300.297328 -40.520351) (xy 300.372767 -40.507266)
			(xy 300.449051 -40.500704) (xy 300.487334 -40.5003) (xy 300.525619 -40.500677) (xy 300.601907 -40.507219)
			(xy 300.67735 -40.520304) (xy 300.751386 -40.539833) (xy 300.787562 -40.55237) (xy 300.795999 -40.555021)
			(xy 300.813669 -40.555021) (xy 300.822106 -40.55237) (xy 300.858291 -40.539863) (xy 300.932328 -40.520351)
			(xy 301.007767 -40.507266) (xy 301.084051 -40.500704) (xy 301.122334 -40.5003) (xy 301.164317 -40.500787)
			(xy 301.247912 -40.508666) (xy 301.330395 -40.524379) (xy 301.411032 -40.547787) (xy 301.450248 -40.562784)
			(xy 301.460692 -40.566294) (xy 301.482669 -40.565127) (xy 301.492666 -40.560498) (xy 301.531214 -40.540705)
			(xy 301.611385 -40.507804) (xy 301.694374 -40.482849) (xy 301.779394 -40.466076) (xy 301.865642 -40.457644)
			(xy 301.908972 -40.45712) (xy 301.950076 -40.457579) (xy 302.031932 -40.465162) (xy 302.11274 -40.480265)
			(xy 302.191809 -40.502761) (xy 302.268465 -40.532456) (xy 302.342055 -40.569098) (xy 302.411949 -40.612374)
			(xy 302.477552 -40.661914) (xy 302.538303 -40.717297) (xy 302.593686 -40.778048) (xy 302.643226 -40.843651)
			(xy 302.686502 -40.913545) (xy 302.723144 -40.987135) (xy 302.752839 -41.063791) (xy 302.775335 -41.14286)
			(xy 302.790438 -41.223668) (xy 302.798021 -41.305524) (xy 302.79848 -41.346628) (xy 302.798042 -41.387131)
			(xy 302.7907 -41.467804) (xy 302.776059 -41.547476) (xy 302.754242 -41.625489) (xy 302.725429 -41.701197)
			(xy 302.708056 -41.737788) (xy 302.703447 -41.748346) (xy 302.703335 -41.771364) (xy 302.707802 -41.781984)
			(xy 302.724373 -41.817832) (xy 302.751818 -41.891892) (xy 302.772586 -41.968094) (xy 302.786514 -42.045837)
			(xy 302.793492 -42.124509) (xy 302.793908 -42.164) (xy 302.793433 -42.205102) (xy 302.785848 -42.286957)
			(xy 302.770743 -42.367762) (xy 302.748247 -42.446829) (xy 302.718551 -42.523483) (xy 302.681909 -42.59707)
			(xy 302.638634 -42.666962) (xy 302.589094 -42.732563) (xy 302.533713 -42.793313) (xy 302.472963 -42.848694)
			(xy 302.407362 -42.898234) (xy 302.33747 -42.941509) (xy 302.263883 -42.978151) (xy 302.187229 -43.007847)
			(xy 302.108162 -43.030343) (xy 302.027357 -43.045448) (xy 301.945502 -43.053033) (xy 301.9044 -43.053508)
			(xy 301.864854 -43.053073) (xy 301.786073 -43.046064) (xy 301.708224 -43.032091) (xy 301.631923 -43.011266)
			(xy 301.55777 -42.983752) (xy 301.521876 -42.967148) (xy 301.511763 -42.962977) (xy 301.489915 -42.962698)
			(xy 301.479712 -42.96664) (xy 301.437359 -42.984532) (xy 301.349773 -43.012514) (xy 301.25977 -43.031323)
			(xy 301.168308 -43.040759) (xy 301.122334 -43.041316) (xy 301.084049 -43.040947) (xy 301.00776 -43.034403)
			(xy 300.932318 -43.021316) (xy 300.858282 -43.001784) (xy 300.822106 -42.989246) (xy 300.813669 -42.986595)
			(xy 300.795999 -42.986595) (xy 300.787562 -42.989246) (xy 300.751381 -43.001762) (xy 300.677342 -43.021272)
			(xy 300.601902 -43.034355) (xy 300.525617 -43.040913) (xy 300.487334 -43.041316) (xy 300.449049 -43.040947)
			(xy 300.37276 -43.034403) (xy 300.297318 -43.021316) (xy 300.223282 -43.001784) (xy 300.187106 -42.989246)
			(xy 300.178669 -42.986595) (xy 300.160999 -42.986595) (xy 300.152562 -42.989246) (xy 300.116381 -43.001762)
			(xy 300.042342 -43.021272) (xy 299.966902 -43.034355) (xy 299.890617 -43.040913) (xy 299.852334 -43.041316)
			(xy 299.805939 -43.04072) (xy 299.713651 -43.031079) (xy 299.622867 -43.011887) (xy 299.534573 -42.983352)
			(xy 299.491908 -42.965116) (xy 299.481966 -42.96131) (xy 299.460702 -42.96131) (xy 299.45076 -42.965116)
			(xy 299.408093 -42.98335) (xy 299.319803 -43.011897) (xy 299.229019 -43.031093) (xy 299.13673 -43.040729)
			(xy 299.090334 -43.041316) (xy 299.049226 -43.040855) (xy 298.967362 -43.033273) (xy 298.886546 -43.018171)
			(xy 298.807467 -42.995678) (xy 298.730802 -42.965985) (xy 298.657202 -42.929345) (xy 298.587297 -42.886072)
			(xy 298.521682 -42.836534) (xy 298.460917 -42.781154) (xy 298.40552 -42.720404) (xy 298.355965 -42.654803)
			(xy 298.312673 -42.584909) (xy 298.276013 -42.51132) (xy 298.246299 -42.434662) (xy 298.223784 -42.35559)
			(xy 298.20866 -42.274778) (xy 298.201056 -42.192915) (xy 298.200572 -42.151808) (xy 296.591345 -42.151808)
			(xy 296.595261 -42.181541) (xy 296.5958 -42.2148) (xy 296.5958 -44.390144) (xy 307.777633 -44.390144)
			(xy 307.777633 -44.219788) (xy 307.785618 -44.04962) (xy 307.80157 -43.880013) (xy 307.825455 -43.711341)
			(xy 307.857219 -43.543973) (xy 307.896794 -43.378278) (xy 307.944091 -43.21462) (xy 307.999008 -43.053359)
			(xy 308.061423 -42.894849) (xy 308.131199 -42.739439) (xy 308.208182 -42.587471) (xy 308.292204 -42.439277)
			(xy 308.38308 -42.295185) (xy 308.48061 -42.155511) (xy 308.58458 -42.020562) (xy 308.694761 -41.890634)
			(xy 308.81091 -41.766014) (xy 308.932774 -41.646975) (xy 309.060082 -41.533779) (xy 309.192557 -41.426674)
			(xy 309.329907 -41.325897) (xy 309.471829 -41.231668) (xy 309.618011 -41.144195) (xy 309.768134 -41.06367)
			(xy 309.921865 -40.99027) (xy 310.078868 -40.924156) (xy 310.238798 -40.865474) (xy 310.401302 -40.814353)
			(xy 310.566023 -40.770905) (xy 310.732601 -40.735226) (xy 310.900667 -40.707394) (xy 311.069853 -40.68747)
			(xy 311.239787 -40.675498) (xy 311.410096 -40.671505) (xy 311.580405 -40.675498) (xy 311.750339 -40.68747)
			(xy 311.919525 -40.707394) (xy 312.087591 -40.735226) (xy 312.254169 -40.770905) (xy 312.41889 -40.814353)
			(xy 312.581394 -40.865474) (xy 312.741324 -40.924156) (xy 312.898327 -40.99027) (xy 313.052058 -41.06367)
			(xy 313.202181 -41.144195) (xy 313.348363 -41.231668) (xy 313.490285 -41.325897) (xy 313.627635 -41.426674)
			(xy 313.76011 -41.533779) (xy 313.887418 -41.646975) (xy 314.009282 -41.766014) (xy 314.125431 -41.890634)
			(xy 314.235612 -42.020562) (xy 314.339582 -42.155511) (xy 314.437112 -42.295185) (xy 314.527988 -42.439277)
			(xy 314.61201 -42.587471) (xy 314.688993 -42.739439) (xy 314.758769 -42.894849) (xy 314.821184 -43.053359)
			(xy 314.876101 -43.21462) (xy 314.923398 -43.378278) (xy 314.962973 -43.543973) (xy 314.994737 -43.711341)
			(xy 315.018622 -43.880013) (xy 315.034574 -44.04962) (xy 315.042559 -44.219788) (xy 315.043058 -44.304966)
			(xy 315.042559 -44.390144) (xy 315.034574 -44.560312) (xy 315.018622 -44.729919) (xy 314.994737 -44.898591)
			(xy 314.962973 -45.065959) (xy 314.923398 -45.231654) (xy 314.876101 -45.395312) (xy 314.821184 -45.556573)
			(xy 314.758769 -45.715083) (xy 314.688993 -45.870493) (xy 314.61201 -46.022461) (xy 314.527988 -46.170655)
			(xy 314.437112 -46.314747) (xy 314.339582 -46.454421) (xy 314.235612 -46.58937) (xy 314.125431 -46.719298)
			(xy 314.009282 -46.843918) (xy 313.887418 -46.962957) (xy 313.76011 -47.076153) (xy 313.627635 -47.183258)
			(xy 313.490285 -47.284035) (xy 313.348363 -47.378264) (xy 313.202181 -47.465737) (xy 313.052058 -47.546262)
			(xy 312.898327 -47.619662) (xy 312.741324 -47.685776) (xy 312.581394 -47.744458) (xy 312.41889 -47.795579)
			(xy 312.254169 -47.839027) (xy 312.087591 -47.874706) (xy 311.919525 -47.902538) (xy 311.750339 -47.922462)
			(xy 311.580405 -47.934434) (xy 311.410096 -47.938428) (xy 311.239787 -47.934434) (xy 311.069853 -47.922462)
			(xy 310.900667 -47.902538) (xy 310.732601 -47.874706) (xy 310.566023 -47.839027) (xy 310.401302 -47.795579)
			(xy 310.238798 -47.744458) (xy 310.078868 -47.685776) (xy 309.921865 -47.619662) (xy 309.768134 -47.546262)
			(xy 309.618011 -47.465737) (xy 309.471829 -47.378264) (xy 309.329907 -47.284035) (xy 309.192557 -47.183258)
			(xy 309.060082 -47.076153) (xy 308.932774 -46.962957) (xy 308.81091 -46.843918) (xy 308.694761 -46.719298)
			(xy 308.58458 -46.58937) (xy 308.48061 -46.454421) (xy 308.38308 -46.314747) (xy 308.292204 -46.170655)
			(xy 308.208182 -46.022461) (xy 308.131199 -45.870493) (xy 308.061423 -45.715083) (xy 307.999008 -45.556573)
			(xy 307.944091 -45.395312) (xy 307.896794 -45.231654) (xy 307.857219 -45.065959) (xy 307.825455 -44.898591)
			(xy 307.80157 -44.729919) (xy 307.785618 -44.560312) (xy 307.777633 -44.390144) (xy 296.5958 -44.390144)
			(xy 296.5958 -44.90974) (xy 296.596209 -44.919247) (xy 296.603146 -44.936953) (xy 296.616025 -44.950944)
			(xy 296.633097 -44.95932) (xy 296.642536 -44.96054) (xy 296.683779 -44.964355) (xy 296.765362 -44.978688)
			(xy 296.845259 -45.000546) (xy 296.922776 -45.029741) (xy 296.997242 -45.066018) (xy 297.068011 -45.109065)
			(xy 297.13447 -45.158506) (xy 297.196043 -45.213914) (xy 297.252195 -45.274809) (xy 297.30244 -45.340662)
			(xy 297.346343 -45.410903) (xy 297.383522 -45.484923) (xy 297.413657 -45.56208) (xy 297.436484 -45.641705)
			(xy 297.451807 -45.723108) (xy 297.459492 -45.805584) (xy 297.459908 -45.847) (xy 297.459406 -45.889315)
			(xy 297.45137 -45.973562) (xy 297.43537 -46.056665) (xy 297.411551 -46.137874) (xy 297.380127 -46.216453)
			(xy 297.341384 -46.291694) (xy 297.318938 -46.327568) (xy 297.314055 -46.335957) (xy 297.310383 -46.355)
			(xy 297.314055 -46.374043) (xy 297.318938 -46.382432) (xy 297.341377 -46.418311) (xy 297.380128 -46.493548)
			(xy 297.411555 -46.572125) (xy 297.435376 -46.653334) (xy 297.451374 -46.736437) (xy 297.459405 -46.820685)
			(xy 297.459908 -46.863) (xy 297.459456 -46.903901) (xy 297.451969 -46.985358) (xy 297.43703 -47.065783)
			(xy 297.414766 -47.144496) (xy 297.385364 -47.22083) (xy 297.349075 -47.294141) (xy 297.306204 -47.363808)
			(xy 297.257115 -47.429241) (xy 297.230038 -47.4599) (xy 297.222672 -47.467774) (xy 297.216068 -47.488094)
			(xy 297.225212 -47.584106) (xy 297.235626 -47.602648) (xy 297.244262 -47.609252) (xy 297.255736 -47.618434)
			(xy 297.274517 -47.641028) (xy 297.287636 -47.667317) (xy 297.294398 -47.695908) (xy 297.294808 -47.710598)
			(xy 297.294808 -50.488088) (xy 297.294315 -50.504744) (xy 297.285696 -50.536922) (xy 297.269042 -50.565773)
			(xy 297.245489 -50.58933) (xy 297.216641 -50.605988) (xy 297.184464 -50.614612) (xy 297.167808 -50.615088)
			(xy 296.6466 -50.615088) (xy 296.636591 -50.615576) (xy 296.618098 -50.623235) (xy 296.603942 -50.637388)
			(xy 296.596278 -50.65588) (xy 296.5958 -50.665888) (xy 296.5958 -50.715164) (xy 296.595281 -50.748425)
			(xy 296.586598 -50.814377) (xy 296.569376 -50.878631) (xy 296.54391 -50.940085) (xy 296.510637 -50.997688)
			(xy 296.470125 -51.050451) (xy 296.446956 -51.07432) (xy 293.165276 -54.356) (xy 296.671492 -54.356)
			(xy 296.672075 -54.309604) (xy 296.68172 -54.217316) (xy 296.700916 -54.126532) (xy 296.729454 -54.038239)
			(xy 296.747692 -53.995574) (xy 296.751597 -53.985652) (xy 296.751597 -53.964348) (xy 296.747692 -53.954426)
			(xy 296.729447 -53.911764) (xy 296.700903 -53.823471) (xy 296.68171 -53.732686) (xy 296.672077 -53.640396)
			(xy 296.671492 -53.594) (xy 296.672075 -53.547604) (xy 296.68172 -53.455316) (xy 296.700916 -53.364532)
			(xy 296.729454 -53.276239) (xy 296.747692 -53.233574) (xy 296.751597 -53.223652) (xy 296.751597 -53.202348)
			(xy 296.747692 -53.192426) (xy 296.729447 -53.149764) (xy 296.700903 -53.061471) (xy 296.68171 -52.970686)
			(xy 296.672077 -52.878396) (xy 296.671492 -52.832) (xy 296.672075 -52.785604) (xy 296.68172 -52.693316)
			(xy 296.700916 -52.602532) (xy 296.729454 -52.514239) (xy 296.747692 -52.471574) (xy 296.751597 -52.461652)
			(xy 296.751597 -52.440348) (xy 296.747692 -52.430426) (xy 296.729447 -52.387764) (xy 296.700903 -52.299471)
			(xy 296.68171 -52.208686) (xy 296.672077 -52.116396) (xy 296.671492 -52.07) (xy 296.671967 -52.028898)
			(xy 296.679552 -51.947043) (xy 296.694657 -51.866238) (xy 296.717153 -51.787171) (xy 296.746849 -51.710517)
			(xy 296.783491 -51.63693) (xy 296.826766 -51.567038) (xy 296.876306 -51.501437) (xy 296.931687 -51.440687)
			(xy 296.992437 -51.385306) (xy 297.058038 -51.335766) (xy 297.12793 -51.292491) (xy 297.201517 -51.255849)
			(xy 297.278171 -51.226153) (xy 297.357238 -51.203657) (xy 297.438043 -51.188552) (xy 297.519898 -51.180967)
			(xy 297.561 -51.180492) (xy 297.607396 -51.181075) (xy 297.699684 -51.19072) (xy 297.790468 -51.209916)
			(xy 297.878761 -51.238454) (xy 297.921426 -51.256692) (xy 297.931366 -51.260512) (xy 297.952634 -51.260512)
			(xy 297.962574 -51.256692) (xy 298.005236 -51.238447) (xy 298.093529 -51.209903) (xy 298.184314 -51.19071)
			(xy 298.276604 -51.181077) (xy 298.323 -51.180492) (xy 298.364102 -51.180967) (xy 298.445957 -51.188552)
			(xy 298.526762 -51.203657) (xy 298.605829 -51.226153) (xy 298.682483 -51.255849) (xy 298.75607 -51.292491)
			(xy 298.825962 -51.335766) (xy 298.891563 -51.385306) (xy 298.952313 -51.440687) (xy 299.007694 -51.501437)
			(xy 299.057234 -51.567038) (xy 299.100509 -51.63693) (xy 299.137151 -51.710517) (xy 299.166847 -51.787171)
			(xy 299.189343 -51.866238) (xy 299.204448 -51.947043) (xy 299.212033 -52.028898) (xy 299.212508 -52.07)
			(xy 299.211925 -52.116396) (xy 299.20228 -52.208684) (xy 299.183084 -52.299468) (xy 299.154546 -52.387761)
			(xy 299.136308 -52.430426) (xy 299.132403 -52.440348) (xy 299.132403 -52.461652) (xy 299.136308 -52.471574)
			(xy 299.154553 -52.514236) (xy 299.183097 -52.602529) (xy 299.20229 -52.693314) (xy 299.211923 -52.785604)
			(xy 299.212508 -52.832) (xy 299.211925 -52.878396) (xy 299.20228 -52.970684) (xy 299.183084 -53.061468)
			(xy 299.154546 -53.149761) (xy 299.136308 -53.192426) (xy 299.132403 -53.202348) (xy 299.132403 -53.223652)
			(xy 299.136308 -53.233574) (xy 299.154553 -53.276236) (xy 299.183097 -53.364529) (xy 299.20229 -53.455314)
			(xy 299.211923 -53.547604) (xy 299.212508 -53.594) (xy 299.211925 -53.640396) (xy 299.20228 -53.732684)
			(xy 299.183084 -53.823468) (xy 299.154546 -53.911761) (xy 299.136308 -53.954426) (xy 299.132403 -53.964348)
			(xy 299.132403 -53.985652) (xy 299.136308 -53.995574) (xy 299.154553 -54.038236) (xy 299.183097 -54.126529)
			(xy 299.20229 -54.217314) (xy 299.211923 -54.309604) (xy 299.212508 -54.356) (xy 299.212033 -54.397102)
			(xy 299.204448 -54.478957) (xy 299.189343 -54.559762) (xy 299.166847 -54.638829) (xy 299.137151 -54.715483)
			(xy 299.100509 -54.78907) (xy 299.057234 -54.858962) (xy 299.007694 -54.924563) (xy 298.952313 -54.985313)
			(xy 298.891563 -55.040694) (xy 298.825962 -55.090234) (xy 298.75607 -55.133509) (xy 298.682483 -55.170151)
			(xy 298.605829 -55.199847) (xy 298.526762 -55.222343) (xy 298.445957 -55.237448) (xy 298.364102 -55.245033)
			(xy 298.323 -55.245508) (xy 298.276604 -55.244925) (xy 298.184316 -55.23528) (xy 298.093532 -55.216084)
			(xy 298.005239 -55.187546) (xy 297.962574 -55.169308) (xy 297.952634 -55.165488) (xy 297.931366 -55.165488)
			(xy 297.921426 -55.169308) (xy 297.878764 -55.187553) (xy 297.790471 -55.216097) (xy 297.699686 -55.23529)
			(xy 297.607396 -55.244923) (xy 297.561 -55.245508) (xy 297.519898 -55.245033) (xy 297.438043 -55.237448)
			(xy 297.357238 -55.222343) (xy 297.278171 -55.199847) (xy 297.201517 -55.170151) (xy 297.12793 -55.133509)
			(xy 297.058038 -55.090234) (xy 296.992437 -55.040694) (xy 296.931687 -54.985313) (xy 296.876306 -54.924563)
			(xy 296.826766 -54.858962) (xy 296.783491 -54.78907) (xy 296.746849 -54.715483) (xy 296.717153 -54.638829)
			(xy 296.694657 -54.559762) (xy 296.679552 -54.478957) (xy 296.671967 -54.397102) (xy 296.671492 -54.356)
			(xy 293.165276 -54.356) (xy 292.721792 -54.799484) (xy 292.697914 -54.822645) (xy 292.645153 -54.86316)
			(xy 292.587554 -54.896439) (xy 292.526101 -54.921912) (xy 292.461849 -54.939141) (xy 292.395897 -54.947833)
			(xy 292.362636 -54.948328) (xy 282.259024 -54.948328) (xy 282.248961 -54.948766) (xy 282.230379 -54.956503)
			(xy 282.222956 -54.963314) (xy 278.953976 -58.232294) (xy 278.947289 -58.239704) (xy 278.939688 -58.258136)
			(xy 278.93969 -58.278075) (xy 278.947295 -58.296506) (xy 278.953976 -58.303922) (xy 279.843992 -59.193938)
			(xy 279.851387 -59.200792) (xy 279.869986 -59.20854) (xy 279.88006 -59.208924) (xy 298.525184 -59.208924)
			(xy 298.558445 -59.209444) (xy 298.624397 -59.218129) (xy 298.688651 -59.23535) (xy 298.750106 -59.260815)
			(xy 298.807709 -59.294087) (xy 298.860475 -59.334595) (xy 298.88434 -59.357768) (xy 300.12259 -60.596018)
			(xy 300.14575 -60.619896) (xy 300.186264 -60.672657) (xy 300.219542 -60.730257) (xy 300.245012 -60.791709)
			(xy 300.26224 -60.855962) (xy 300.270931 -60.921913) (xy 300.271434 -60.955174) (xy 300.271434 -72.642476)
			(xy 300.271872 -72.652539) (xy 300.279609 -72.671121) (xy 300.28642 -72.678544) (xy 300.487842 -72.879966)
			(xy 310.009801 -72.879966) (xy 310.013811 -72.774063) (xy 310.025819 -72.668767) (xy 310.045756 -72.564681)
			(xy 310.073508 -72.462401) (xy 310.108916 -72.362512) (xy 310.151777 -72.265588) (xy 310.201845 -72.172182)
			(xy 310.258835 -72.082831) (xy 310.322418 -71.998045) (xy 310.392232 -71.918311) (xy 310.467876 -71.844086)
			(xy 310.548916 -71.775793) (xy 310.63489 -71.713826) (xy 310.725304 -71.658538) (xy 310.81964 -71.610246)
			(xy 310.917359 -71.569227) (xy 311.017899 -71.535716) (xy 311.120687 -71.509904) (xy 311.225131 -71.49194)
			(xy 311.330636 -71.481927) (xy 311.436595 -71.479921) (xy 311.542403 -71.485935) (xy 311.647453 -71.499934)
			(xy 311.751143 -71.521837) (xy 311.85288 -71.55152) (xy 311.952081 -71.588811) (xy 312.048177 -71.633499)
			(xy 312.140618 -71.685326) (xy 312.228875 -71.743996) (xy 312.312442 -71.809173) (xy 312.390841 -71.880483)
			(xy 312.463622 -71.957517) (xy 312.530368 -72.039836) (xy 312.590698 -72.126967) (xy 312.644265 -72.218411)
			(xy 312.690763 -72.313644) (xy 312.729925 -72.412121) (xy 312.761528 -72.513278) (xy 312.785389 -72.616536)
			(xy 312.801374 -72.721302) (xy 312.809389 -72.826977) (xy 312.80989 -72.879966) (xy 312.809389 -72.932955)
			(xy 312.801374 -73.03863) (xy 312.785389 -73.143396) (xy 312.761528 -73.246654) (xy 312.729925 -73.347811)
			(xy 312.690763 -73.446288) (xy 312.644265 -73.541521) (xy 312.590698 -73.632965) (xy 312.530368 -73.720096)
			(xy 312.463622 -73.802415) (xy 312.390841 -73.879449) (xy 312.312442 -73.950759) (xy 312.228875 -74.015936)
			(xy 312.140618 -74.074606) (xy 312.048177 -74.126433) (xy 311.952081 -74.171121) (xy 311.85288 -74.208412)
			(xy 311.751143 -74.238095) (xy 311.647453 -74.259998) (xy 311.542403 -74.273997) (xy 311.436595 -74.280011)
			(xy 311.330636 -74.278005) (xy 311.225131 -74.267992) (xy 311.120687 -74.250028) (xy 311.017899 -74.224216)
			(xy 310.917359 -74.190705) (xy 310.81964 -74.149686) (xy 310.725304 -74.101394) (xy 310.63489 -74.046106)
			(xy 310.548916 -73.984139) (xy 310.467876 -73.915846) (xy 310.392232 -73.841621) (xy 310.322418 -73.761887)
			(xy 310.258835 -73.677101) (xy 310.201845 -73.58775) (xy 310.151777 -73.494344) (xy 310.108916 -73.39742)
			(xy 310.073508 -73.297531) (xy 310.045756 -73.195251) (xy 310.025819 -73.091165) (xy 310.013811 -72.985869)
			(xy 310.009801 -72.879966) (xy 300.487842 -72.879966) (xy 300.69409 -73.086214) (xy 300.701484 -73.093071)
			(xy 300.720083 -73.100823) (xy 300.730158 -73.1012) (xy 306.451 -73.1012) (xy 306.48426 -73.101721)
			(xy 306.55021 -73.110409) (xy 306.614461 -73.127634) (xy 306.675912 -73.153103) (xy 306.733511 -73.186379)
			(xy 306.786271 -73.226892) (xy 306.810156 -73.250044) (xy 308.856126 -75.296014) (xy 308.863522 -75.302866)
			(xy 308.882121 -75.310604) (xy 308.892194 -75.311) (xy 319.8876 -75.311) (xy 319.92086 -75.311521)
			(xy 319.98681 -75.320209) (xy 320.051061 -75.337434) (xy 320.112512 -75.362903) (xy 320.170111 -75.396179)
			(xy 320.222871 -75.436692) (xy 320.246756 -75.459844) (xy 321.288156 -76.501244) (xy 321.311312 -76.525124)
			(xy 321.351818 -76.577888) (xy 321.385089 -76.635489) (xy 321.410553 -76.69694) (xy 321.427775 -76.761191)
			(xy 321.436461 -76.827141) (xy 321.437 -76.8604) (xy 321.437 -120.904) (xy 321.436479 -120.93726)
			(xy 321.427791 -121.00321) (xy 321.410566 -121.067461) (xy 321.385097 -121.128912) (xy 321.351821 -121.186511)
			(xy 321.311308 -121.239271) (xy 321.288156 -121.263156) (xy 319.992756 -122.558556) (xy 319.968876 -122.581712)
			(xy 319.916112 -122.622218) (xy 319.858511 -122.655489) (xy 319.79706 -122.680953) (xy 319.732809 -122.698175)
			(xy 319.666859 -122.706861) (xy 319.6336 -122.7074) (xy 304.015394 -122.7074) (xy 304.005324 -122.707824)
			(xy 303.986721 -122.71554) (xy 303.979326 -122.722386) (xy 300.28642 -126.415292) (xy 300.27957 -126.422689)
			(xy 300.27183 -126.441287) (xy 300.271434 -126.45136) (xy 300.271434 -131.730242) (xy 300.27091 -131.763501)
			(xy 300.262218 -131.829449) (xy 300.244989 -131.893698) (xy 300.219518 -131.955146) (xy 300.186241 -132.012742)
			(xy 300.145728 -132.0655) (xy 300.12259 -132.089398) (xy 298.892722 -133.319266) (xy 298.868843 -133.342424)
			(xy 298.816081 -133.382934) (xy 298.758481 -133.416206) (xy 298.697028 -133.441671) (xy 298.632776 -133.458892)
			(xy 298.566826 -133.467575) (xy 298.533566 -133.46811) (xy 279.797256 -133.46811) (xy 279.78719 -133.468541)
			(xy 279.768598 -133.476268) (xy 279.761188 -133.483096) (xy 278.722836 -134.521448) (xy 278.715993 -134.528847)
			(xy 278.708271 -134.547446) (xy 278.70785 -134.557516) (xy 278.70785 -145.276824) (xy 278.708279 -145.286891)
			(xy 278.716005 -145.305485) (xy 278.722836 -145.312892) (xy 279.308814 -145.89887) (xy 279.340818 -145.90395)
			(xy 279.355804 -145.896584) (xy 279.382437 -145.883855) (xy 279.438656 -145.865864) (xy 279.496978 -145.856767)
			(xy 279.526492 -145.856198) (xy 279.556616 -145.856767) (xy 279.616113 -145.86624) (xy 279.673381 -145.884951)
			(xy 279.726993 -145.912436) (xy 279.775617 -145.948009) (xy 279.797256 -145.968974) (xy 279.804656 -145.975814)
			(xy 279.823255 -145.983532) (xy 279.833324 -145.98396) (xy 284.29966 -145.98396) (xy 284.309724 -145.983525)
			(xy 284.328309 -145.97579) (xy 284.335728 -145.968974) (xy 284.355352 -145.949872) (xy 284.399091 -145.916919)
			(xy 284.447092 -145.890559) (xy 284.49837 -145.871333) (xy 284.55187 -145.859637) (xy 284.606492 -145.855712)
			(xy 284.661114 -145.859637) (xy 284.714614 -145.871333) (xy 284.765892 -145.890559) (xy 284.813893 -145.916919)
			(xy 284.857632 -145.949872) (xy 284.877256 -145.968974) (xy 284.884656 -145.975814) (xy 284.903255 -145.983532)
			(xy 284.913324 -145.98396) (xy 289.37966 -145.98396) (xy 289.389724 -145.983525) (xy 289.408309 -145.97579)
			(xy 289.415728 -145.968974) (xy 289.435352 -145.949872) (xy 289.479091 -145.916919) (xy 289.527092 -145.890559)
			(xy 289.57837 -145.871333) (xy 289.63187 -145.859637) (xy 289.686492 -145.855712) (xy 289.741114 -145.859637)
			(xy 289.794614 -145.871333) (xy 289.845892 -145.890559) (xy 289.893893 -145.916919) (xy 289.937632 -145.949872)
			(xy 289.957256 -145.968974) (xy 289.964656 -145.975814) (xy 289.983255 -145.983532) (xy 289.993324 -145.98396)
			(xy 294.45966 -145.98396) (xy 294.469724 -145.983525) (xy 294.488309 -145.97579) (xy 294.495728 -145.968974)
			(xy 294.515352 -145.949872) (xy 294.559091 -145.916919) (xy 294.607092 -145.890559) (xy 294.65837 -145.871333)
			(xy 294.71187 -145.859637) (xy 294.766492 -145.855712) (xy 294.821114 -145.859637) (xy 294.874614 -145.871333)
			(xy 294.925892 -145.890559) (xy 294.973893 -145.916919) (xy 295.017632 -145.949872) (xy 295.037256 -145.968974)
			(xy 295.044656 -145.975814) (xy 295.063255 -145.983532) (xy 295.073324 -145.98396) (xy 299.53966 -145.98396)
			(xy 299.549724 -145.983525) (xy 299.568309 -145.97579) (xy 299.575728 -145.968974) (xy 299.595352 -145.949872)
			(xy 299.639091 -145.916919) (xy 299.687092 -145.890559) (xy 299.73837 -145.871333) (xy 299.79187 -145.859637)
			(xy 299.846492 -145.855712) (xy 299.901114 -145.859637) (xy 299.954614 -145.871333) (xy 300.005892 -145.890559)
			(xy 300.053893 -145.916919) (xy 300.097632 -145.949872) (xy 300.117256 -145.968974) (xy 300.124656 -145.975814)
			(xy 300.143255 -145.983532) (xy 300.153324 -145.98396) (xy 304.61966 -145.98396) (xy 304.629724 -145.983525)
			(xy 304.648309 -145.97579) (xy 304.655728 -145.968974) (xy 304.675352 -145.949872) (xy 304.719091 -145.916919)
			(xy 304.767092 -145.890559) (xy 304.81837 -145.871333) (xy 304.87187 -145.859637) (xy 304.926492 -145.855712)
			(xy 304.981114 -145.859637) (xy 305.034614 -145.871333) (xy 305.085892 -145.890559) (xy 305.133893 -145.916919)
			(xy 305.177632 -145.949872) (xy 305.197256 -145.968974) (xy 305.204656 -145.975814) (xy 305.223255 -145.983532)
			(xy 305.233324 -145.98396) (xy 309.69966 -145.98396) (xy 309.709724 -145.983525) (xy 309.728309 -145.97579)
			(xy 309.735728 -145.968974) (xy 309.755352 -145.949872) (xy 309.799091 -145.916919) (xy 309.847092 -145.890559)
			(xy 309.89837 -145.871333) (xy 309.95187 -145.859637) (xy 310.006492 -145.855712) (xy 310.061114 -145.859637)
			(xy 310.114614 -145.871333) (xy 310.165892 -145.890559) (xy 310.213893 -145.916919) (xy 310.257632 -145.949872)
			(xy 310.277256 -145.968974) (xy 310.284656 -145.975814) (xy 310.303255 -145.983532) (xy 310.313324 -145.98396)
			(xy 314.77966 -145.98396) (xy 314.789724 -145.983525) (xy 314.808309 -145.97579) (xy 314.815728 -145.968974)
			(xy 314.835352 -145.949872) (xy 314.879091 -145.916919) (xy 314.927092 -145.890559) (xy 314.97837 -145.871333)
			(xy 315.03187 -145.859637) (xy 315.086492 -145.855712) (xy 315.141114 -145.859637) (xy 315.194614 -145.871333)
			(xy 315.245892 -145.890559) (xy 315.293893 -145.916919) (xy 315.337632 -145.949872) (xy 315.357256 -145.968974)
			(xy 315.364656 -145.975814) (xy 315.383255 -145.983532) (xy 315.393324 -145.98396) (xy 319.85966 -145.98396)
			(xy 319.869724 -145.983525) (xy 319.888309 -145.97579) (xy 319.895728 -145.968974) (xy 319.915352 -145.949872)
			(xy 319.959091 -145.916919) (xy 320.007092 -145.890559) (xy 320.05837 -145.871333) (xy 320.11187 -145.859637)
			(xy 320.166492 -145.855712) (xy 320.221114 -145.859637) (xy 320.274614 -145.871333) (xy 320.325892 -145.890559)
			(xy 320.373893 -145.916919) (xy 320.417632 -145.949872) (xy 320.437256 -145.968974) (xy 320.444656 -145.975814)
			(xy 320.463255 -145.983532) (xy 320.473324 -145.98396) (xy 323.000116 -145.98396) (xy 323.090878 -145.983456)
			(xy 323.272215 -145.9752) (xy 323.452987 -145.958693) (xy 323.632819 -145.933967) (xy 323.811339 -145.901076)
			(xy 323.988175 -145.860086) (xy 324.16296 -145.811084) (xy 324.335332 -145.75417) (xy 324.504932 -145.689464)
			(xy 324.588378 -145.65376) (xy 324.597867 -145.649024) (xy 324.612172 -145.6334) (xy 324.616064 -145.623534)
			(xy 324.625004 -145.598756) (xy 324.648737 -145.55173) (xy 324.678708 -145.508412) (xy 324.714349 -145.469624)
			(xy 324.754982 -145.436103) (xy 324.799837 -145.408485) (xy 324.848062 -145.387294) (xy 324.898742 -145.372932)
			(xy 324.950914 -145.365672) (xy 324.977252 -145.365216) (xy 325.003105 -145.365667) (xy 325.054335 -145.37268)
			(xy 325.07936 -145.379186) (xy 325.089743 -145.381475) (xy 325.110745 -145.378323) (xy 325.12 -145.37309)
			(xy 325.196841 -145.324184) (xy 325.346483 -145.2203) (xy 325.491221 -145.109687) (xy 325.630752 -144.992575)
			(xy 325.764787 -144.869208) (xy 325.893043 -144.739846) (xy 326.015254 -144.604757) (xy 326.131164 -144.464225)
			(xy 326.240531 -144.318543) (xy 326.343126 -144.168015) (xy 326.438735 -144.012956) (xy 326.527158 -143.85369)
			(xy 326.608211 -143.690549) (xy 326.681723 -143.523875) (xy 326.71512 -143.439134) (xy 326.718374 -143.42906)
			(xy 326.717333 -143.407937) (xy 326.713088 -143.39824) (xy 326.700413 -143.371638) (xy 326.682512 -143.315497)
			(xy 326.673477 -143.257269) (xy 326.672956 -143.227806) (xy 326.67347 -143.199146) (xy 326.682044 -143.142469)
			(xy 326.699 -143.087714) (xy 326.723955 -143.03611) (xy 326.75635 -142.988821) (xy 326.795454 -142.946909)
			(xy 326.840387 -142.911319) (xy 326.86498 -142.89659) (xy 326.873993 -142.890942) (xy 326.886619 -142.873846)
			(xy 326.889364 -142.86357) (xy 326.907773 -142.778483) (xy 326.938051 -142.607027) (xy 326.960811 -142.434412)
			(xy 326.976012 -142.260967) (xy 326.983623 -142.087025) (xy 326.984106 -141.99997) (xy 326.984106 -140.252958)
			(xy 326.983658 -140.242802) (xy 326.975799 -140.224071) (xy 326.968866 -140.216636) (xy 326.949521 -140.196972)
			(xy 326.916123 -140.153071) (xy 326.889395 -140.104818) (xy 326.869893 -140.053219) (xy 326.858026 -139.99935)
			(xy 326.854039 -139.944334) (xy 326.858016 -139.889316) (xy 326.869874 -139.835445) (xy 326.889366 -139.783843)
			(xy 326.916086 -139.735586) (xy 326.949476 -139.691679) (xy 326.968866 -139.67206) (xy 326.97581 -139.664634)
			(xy 326.983658 -139.645897) (xy 326.984106 -139.635738) (xy 326.984106 -135.172958) (xy 326.983658 -135.162802)
			(xy 326.975799 -135.144071) (xy 326.968866 -135.136636) (xy 326.949521 -135.116972) (xy 326.916123 -135.073071)
			(xy 326.889395 -135.024818) (xy 326.869893 -134.973219) (xy 326.858026 -134.91935) (xy 326.854039 -134.864334)
			(xy 326.858016 -134.809316) (xy 326.869874 -134.755445) (xy 326.889366 -134.703843) (xy 326.916086 -134.655586)
			(xy 326.949476 -134.611679) (xy 326.968866 -134.59206) (xy 326.97581 -134.584634) (xy 326.983658 -134.565897)
			(xy 326.984106 -134.555738) (xy 326.984106 -130.092958) (xy 326.983658 -130.082802) (xy 326.975799 -130.064071)
			(xy 326.968866 -130.056636) (xy 326.949521 -130.036972) (xy 326.916123 -129.993071) (xy 326.889395 -129.944818)
			(xy 326.869893 -129.893219) (xy 326.858026 -129.83935) (xy 326.854039 -129.784334) (xy 326.858016 -129.729316)
			(xy 326.869874 -129.675445) (xy 326.889366 -129.623843) (xy 326.916086 -129.575586) (xy 326.949476 -129.531679)
			(xy 326.968866 -129.51206) (xy 326.97581 -129.504634) (xy 326.983658 -129.485897) (xy 326.984106 -129.475738)
			(xy 326.984106 -125.012958) (xy 326.983658 -125.002802) (xy 326.975799 -124.984071) (xy 326.968866 -124.976636)
			(xy 326.949521 -124.956972) (xy 326.916123 -124.913071) (xy 326.889395 -124.864818) (xy 326.869893 -124.813219)
			(xy 326.858026 -124.75935) (xy 326.854039 -124.704334) (xy 326.858016 -124.649316) (xy 326.869874 -124.595445)
			(xy 326.889366 -124.543843) (xy 326.916086 -124.495586) (xy 326.949476 -124.451679) (xy 326.968866 -124.43206)
			(xy 326.97581 -124.424634) (xy 326.983658 -124.405897) (xy 326.984106 -124.395738) (xy 326.984106 -119.932958)
			(xy 326.983658 -119.922802) (xy 326.975799 -119.904071) (xy 326.968866 -119.896636) (xy 326.949521 -119.876972)
			(xy 326.916123 -119.833071) (xy 326.889395 -119.784818) (xy 326.869893 -119.733219) (xy 326.858026 -119.67935)
			(xy 326.854039 -119.624334) (xy 326.858016 -119.569316) (xy 326.869874 -119.515445) (xy 326.889366 -119.463843)
			(xy 326.916086 -119.415586) (xy 326.949476 -119.371679) (xy 326.968866 -119.35206) (xy 326.97581 -119.344634)
			(xy 326.983658 -119.325897) (xy 326.984106 -119.315738) (xy 326.984106 -114.852958) (xy 326.983658 -114.842802)
			(xy 326.975799 -114.824071) (xy 326.968866 -114.816636) (xy 326.949521 -114.796972) (xy 326.916123 -114.753071)
			(xy 326.889395 -114.704818) (xy 326.869893 -114.653219) (xy 326.858026 -114.59935) (xy 326.854039 -114.544334)
			(xy 326.858016 -114.489316) (xy 326.869874 -114.435445) (xy 326.889366 -114.383843) (xy 326.916086 -114.335586)
			(xy 326.949476 -114.291679) (xy 326.968866 -114.27206) (xy 326.97581 -114.264634) (xy 326.983658 -114.245897)
			(xy 326.984106 -114.235738) (xy 326.984106 -109.772958) (xy 326.983658 -109.762802) (xy 326.975799 -109.744071)
			(xy 326.968866 -109.736636) (xy 326.949521 -109.716972) (xy 326.916123 -109.673071) (xy 326.889395 -109.624818)
			(xy 326.869893 -109.573219) (xy 326.858026 -109.51935) (xy 326.854039 -109.464334) (xy 326.858016 -109.409316)
			(xy 326.869874 -109.355445) (xy 326.889366 -109.303843) (xy 326.916086 -109.255586) (xy 326.949476 -109.211679)
			(xy 326.968866 -109.19206) (xy 326.97581 -109.184634) (xy 326.983658 -109.165897) (xy 326.984106 -109.155738)
			(xy 326.984106 -104.692958) (xy 326.983658 -104.682802) (xy 326.975799 -104.664071) (xy 326.968866 -104.656636)
			(xy 326.949521 -104.636972) (xy 326.916123 -104.593071) (xy 326.889395 -104.544818) (xy 326.869893 -104.493219)
			(xy 326.858026 -104.43935) (xy 326.854039 -104.384334) (xy 326.858016 -104.329316) (xy 326.869874 -104.275445)
			(xy 326.889366 -104.223843) (xy 326.916086 -104.175586) (xy 326.949476 -104.131679) (xy 326.968866 -104.11206)
			(xy 326.97581 -104.104634) (xy 326.983658 -104.085897) (xy 326.984106 -104.075738) (xy 326.984106 -99.612958)
			(xy 326.983658 -99.602802) (xy 326.975799 -99.584071) (xy 326.968866 -99.576636) (xy 326.949521 -99.556972)
			(xy 326.916123 -99.513071) (xy 326.889395 -99.464818) (xy 326.869893 -99.413219) (xy 326.858026 -99.35935)
			(xy 326.854039 -99.304334) (xy 326.858016 -99.249316) (xy 326.869874 -99.195445) (xy 326.889366 -99.143843)
			(xy 326.916086 -99.095586) (xy 326.949476 -99.051679) (xy 326.968866 -99.03206) (xy 326.97581 -99.024634)
			(xy 326.983658 -99.005897) (xy 326.984106 -98.995738) (xy 326.984106 -94.532958) (xy 326.983658 -94.522802)
			(xy 326.975799 -94.504071) (xy 326.968866 -94.496636) (xy 326.949521 -94.476972) (xy 326.916123 -94.433071)
			(xy 326.889395 -94.384818) (xy 326.869893 -94.333219) (xy 326.858026 -94.27935) (xy 326.854039 -94.224334)
			(xy 326.858016 -94.169316) (xy 326.869874 -94.115445) (xy 326.889366 -94.063843) (xy 326.916086 -94.015586)
			(xy 326.949476 -93.971679) (xy 326.968866 -93.95206) (xy 326.97581 -93.944634) (xy 326.983658 -93.925897)
			(xy 326.984106 -93.915738) (xy 326.984106 -89.452958) (xy 326.983658 -89.442802) (xy 326.975799 -89.424071)
			(xy 326.968866 -89.416636) (xy 326.949521 -89.396972) (xy 326.916123 -89.353071) (xy 326.889395 -89.304818)
			(xy 326.869893 -89.253219) (xy 326.858026 -89.19935) (xy 326.854039 -89.144334) (xy 326.858016 -89.089316)
			(xy 326.869874 -89.035445) (xy 326.889366 -88.983843) (xy 326.916086 -88.935586) (xy 326.949476 -88.891679)
			(xy 326.968866 -88.87206) (xy 326.97581 -88.864634) (xy 326.983658 -88.845897) (xy 326.984106 -88.835738)
			(xy 326.984106 -84.372958) (xy 326.983658 -84.362802) (xy 326.975799 -84.344071) (xy 326.968866 -84.336636)
			(xy 326.949521 -84.316972) (xy 326.916123 -84.273071) (xy 326.889395 -84.224818) (xy 326.869893 -84.173219)
			(xy 326.858026 -84.11935) (xy 326.854039 -84.064334) (xy 326.858016 -84.009316) (xy 326.869874 -83.955445)
			(xy 326.889366 -83.903843) (xy 326.916086 -83.855586) (xy 326.949476 -83.811679) (xy 326.968866 -83.79206)
			(xy 326.97581 -83.784634) (xy 326.983658 -83.765897) (xy 326.984106 -83.755738) (xy 326.984106 -79.292958)
			(xy 326.983658 -79.282802) (xy 326.975799 -79.264071) (xy 326.968866 -79.256636) (xy 326.949521 -79.236972)
			(xy 326.916123 -79.193071) (xy 326.889395 -79.144818) (xy 326.869893 -79.093219) (xy 326.858026 -79.03935)
			(xy 326.854039 -78.984334) (xy 326.858016 -78.929316) (xy 326.869874 -78.875445) (xy 326.889366 -78.823843)
			(xy 326.916086 -78.775586) (xy 326.949476 -78.731679) (xy 326.968866 -78.71206) (xy 326.97581 -78.704634)
			(xy 326.983658 -78.685897) (xy 326.984106 -78.675738) (xy 326.984106 -74.212958) (xy 326.983658 -74.202802)
			(xy 326.975799 -74.184071) (xy 326.968866 -74.176636) (xy 326.949521 -74.156972) (xy 326.916123 -74.113071)
			(xy 326.889395 -74.064818) (xy 326.869893 -74.013219) (xy 326.858026 -73.95935) (xy 326.854039 -73.904334)
			(xy 326.858016 -73.849316) (xy 326.869874 -73.795445) (xy 326.889366 -73.743843) (xy 326.916086 -73.695586)
			(xy 326.949476 -73.651679) (xy 326.968866 -73.63206) (xy 326.97581 -73.624634) (xy 326.983658 -73.605897)
			(xy 326.984106 -73.595738) (xy 326.984106 -69.132958) (xy 326.983658 -69.122802) (xy 326.975799 -69.104071)
			(xy 326.968866 -69.096636) (xy 326.949521 -69.076972) (xy 326.916123 -69.033071) (xy 326.889395 -68.984818)
			(xy 326.869893 -68.933219) (xy 326.858026 -68.87935) (xy 326.854039 -68.824334) (xy 326.858016 -68.769316)
			(xy 326.869874 -68.715445) (xy 326.889366 -68.663843) (xy 326.916086 -68.615586) (xy 326.949476 -68.571679)
			(xy 326.968866 -68.55206) (xy 326.97581 -68.544634) (xy 326.983658 -68.525897) (xy 326.984106 -68.515738)
			(xy 326.984106 -64.052958) (xy 326.983658 -64.042802) (xy 326.975799 -64.024071) (xy 326.968866 -64.016636)
			(xy 326.949521 -63.996972) (xy 326.916123 -63.953071) (xy 326.889395 -63.904818) (xy 326.869893 -63.853219)
			(xy 326.858026 -63.79935) (xy 326.854039 -63.744334) (xy 326.858016 -63.689316) (xy 326.869874 -63.635445)
			(xy 326.889366 -63.583843) (xy 326.916086 -63.535586) (xy 326.949476 -63.491679) (xy 326.968866 -63.47206)
			(xy 326.97581 -63.464634) (xy 326.983658 -63.445897) (xy 326.984106 -63.435738) (xy 326.984106 -58.972958)
			(xy 326.983658 -58.962802) (xy 326.975799 -58.944071) (xy 326.968866 -58.936636) (xy 326.949521 -58.916972)
			(xy 326.916123 -58.873071) (xy 326.889395 -58.824818) (xy 326.869893 -58.773219) (xy 326.858026 -58.71935)
			(xy 326.854039 -58.664334) (xy 326.858016 -58.609316) (xy 326.869874 -58.555445) (xy 326.889366 -58.503843)
			(xy 326.916086 -58.455586) (xy 326.949476 -58.411679) (xy 326.968866 -58.39206) (xy 326.97581 -58.384634)
			(xy 326.983658 -58.365897) (xy 326.984106 -58.355738) (xy 326.984106 -53.892958) (xy 326.983658 -53.882802)
			(xy 326.975799 -53.864071) (xy 326.968866 -53.856636) (xy 326.949521 -53.836972) (xy 326.916123 -53.793071)
			(xy 326.889395 -53.744818) (xy 326.869893 -53.693219) (xy 326.858026 -53.63935) (xy 326.854039 -53.584334)
			(xy 326.858016 -53.529316) (xy 326.869874 -53.475445) (xy 326.889366 -53.423843) (xy 326.916086 -53.375586)
			(xy 326.949476 -53.331679) (xy 326.968866 -53.31206) (xy 326.97581 -53.304634) (xy 326.983658 -53.285897)
			(xy 326.984106 -53.275738) (xy 326.984106 -48.812958) (xy 326.983658 -48.802802) (xy 326.975799 -48.784071)
			(xy 326.968866 -48.776636) (xy 326.949521 -48.756972) (xy 326.916123 -48.713071) (xy 326.889395 -48.664818)
			(xy 326.869893 -48.613219) (xy 326.858026 -48.55935) (xy 326.854039 -48.504334) (xy 326.858016 -48.449316)
			(xy 326.869874 -48.395445) (xy 326.889366 -48.343843) (xy 326.916086 -48.295586) (xy 326.949476 -48.251679)
			(xy 326.968866 -48.23206) (xy 326.97581 -48.224634) (xy 326.983658 -48.205897) (xy 326.984106 -48.195738)
			(xy 326.984106 -43.732958) (xy 326.983658 -43.722802) (xy 326.975799 -43.704071) (xy 326.968866 -43.696636)
			(xy 326.949521 -43.676972) (xy 326.916123 -43.633071) (xy 326.889395 -43.584818) (xy 326.869893 -43.533219)
			(xy 326.858026 -43.47935) (xy 326.854039 -43.424334) (xy 326.858016 -43.369316) (xy 326.869874 -43.315445)
			(xy 326.889366 -43.263843) (xy 326.916086 -43.215586) (xy 326.949476 -43.171679) (xy 326.968866 -43.15206)
			(xy 326.97581 -43.144634) (xy 326.983658 -43.125897) (xy 326.984106 -43.115738) (xy 326.984106 -38.652958)
			(xy 326.983658 -38.642802) (xy 326.975799 -38.624071) (xy 326.968866 -38.616636) (xy 326.949521 -38.596972)
			(xy 326.916123 -38.553071) (xy 326.889395 -38.504818) (xy 326.869893 -38.453219) (xy 326.858026 -38.39935)
			(xy 326.854039 -38.344334) (xy 326.858016 -38.289316) (xy 326.869874 -38.235445) (xy 326.889366 -38.183843)
			(xy 326.916086 -38.135586) (xy 326.949476 -38.091679) (xy 326.968866 -38.07206) (xy 326.97581 -38.064634)
			(xy 326.983658 -38.045897) (xy 326.984106 -38.035738) (xy 326.984106 -33.572958) (xy 326.983658 -33.562802)
			(xy 326.975799 -33.544071) (xy 326.968866 -33.536636) (xy 326.949521 -33.516972) (xy 326.916123 -33.473071)
			(xy 326.889395 -33.424818) (xy 326.869893 -33.373219) (xy 326.858026 -33.31935) (xy 326.854039 -33.264334)
			(xy 326.858016 -33.209316) (xy 326.869874 -33.155445) (xy 326.889366 -33.103843) (xy 326.916086 -33.055586)
			(xy 326.949476 -33.011679) (xy 326.968866 -32.99206) (xy 326.97581 -32.984634) (xy 326.983658 -32.965897)
			(xy 326.984106 -32.955738) (xy 326.984106 -28.492958) (xy 326.983658 -28.482802) (xy 326.975799 -28.464071)
			(xy 326.968866 -28.456636) (xy 326.949521 -28.436972) (xy 326.916123 -28.393071) (xy 326.889395 -28.344818)
			(xy 326.869893 -28.293219) (xy 326.858026 -28.23935) (xy 326.854039 -28.184334) (xy 326.858016 -28.129316)
			(xy 326.869874 -28.075445) (xy 326.889366 -28.023843) (xy 326.916086 -27.975586) (xy 326.949476 -27.931679)
			(xy 326.968866 -27.91206) (xy 326.97581 -27.904634) (xy 326.983658 -27.885897) (xy 326.984106 -27.875738)
			(xy 326.984106 -23.412958) (xy 326.983658 -23.402802) (xy 326.975799 -23.384071) (xy 326.968866 -23.376636)
			(xy 326.949521 -23.356972) (xy 326.916123 -23.313071) (xy 326.889395 -23.264818) (xy 326.869893 -23.213219)
			(xy 326.858026 -23.15935) (xy 326.854039 -23.104334) (xy 326.858016 -23.049316) (xy 326.869874 -22.995445)
			(xy 326.889366 -22.943843) (xy 326.916086 -22.895586) (xy 326.949476 -22.851679) (xy 326.968866 -22.83206)
			(xy 326.97581 -22.824634) (xy 326.983658 -22.805897) (xy 326.984106 -22.795738) (xy 326.984106 -18.332958)
			(xy 326.983658 -18.322802) (xy 326.975799 -18.304071) (xy 326.968866 -18.296636) (xy 326.949521 -18.276972)
			(xy 326.916123 -18.233071) (xy 326.889395 -18.184818) (xy 326.869893 -18.133219) (xy 326.858026 -18.07935)
			(xy 326.854039 -18.024334) (xy 326.858016 -17.969316) (xy 326.869874 -17.915445) (xy 326.889366 -17.863843)
			(xy 326.916086 -17.815586) (xy 326.949476 -17.771679) (xy 326.968866 -17.75206) (xy 326.97581 -17.744634)
			(xy 326.983658 -17.725897) (xy 326.984106 -17.715738) (xy 326.984106 -13.252958) (xy 326.983658 -13.242802)
			(xy 326.975799 -13.224071) (xy 326.968866 -13.216636) (xy 326.949521 -13.196972) (xy 326.916123 -13.153071)
			(xy 326.889395 -13.104818) (xy 326.869893 -13.053219) (xy 326.858026 -12.99935) (xy 326.854039 -12.944334)
			(xy 326.858016 -12.889316) (xy 326.869874 -12.835445) (xy 326.889366 -12.783843) (xy 326.916086 -12.735586)
			(xy 326.949476 -12.691679) (xy 326.968866 -12.67206) (xy 326.97581 -12.664634) (xy 326.983658 -12.645897)
			(xy 326.984106 -12.635738) (xy 326.984106 -8.172958) (xy 326.983658 -8.162802) (xy 326.975799 -8.144071)
			(xy 326.968866 -8.136636) (xy 326.949521 -8.116972) (xy 326.916123 -8.073071) (xy 326.889395 -8.024818)
			(xy 326.869893 -7.973219) (xy 326.858026 -7.91935) (xy 326.854039 -7.864334) (xy 326.858016 -7.809316)
			(xy 326.869874 -7.755445) (xy 326.889366 -7.703843) (xy 326.916086 -7.655586) (xy 326.949476 -7.611679)
			(xy 326.968866 -7.59206) (xy 326.97581 -7.584634) (xy 326.983658 -7.565897) (xy 326.984106 -7.555738)
			(xy 326.984106 -4.99999) (xy 326.98361 -4.910133) (xy 326.975521 -4.730602) (xy 326.959343 -4.551618)
			(xy 326.935107 -4.373545) (xy 326.902865 -4.196748) (xy 326.86268 -4.021584) (xy 326.814635 -3.848412)
			(xy 326.758828 -3.677583) (xy 326.727566 -3.593338) (xy 326.723304 -3.583534) (xy 326.708341 -3.5683)
			(xy 326.69861 -3.563874) (xy 326.67229 -3.552917) (xy 326.622964 -3.524333) (xy 326.578439 -3.488729)
			(xy 326.539706 -3.446898) (xy 326.507627 -3.399769) (xy 326.482916 -3.348393) (xy 326.466124 -3.293913)
			(xy 326.457622 -3.237541) (xy 326.457056 -3.209036) (xy 326.457672 -3.178331) (xy 326.467498 -3.117713)
			(xy 326.476614 -3.088386) (xy 326.479502 -3.078091) (xy 326.47754 -3.056824) (xy 326.472804 -3.047238)
			(xy 326.429529 -2.971254) (xy 326.337208 -2.822726) (xy 326.238457 -2.678392) (xy 326.133467 -2.538532)
			(xy 326.022439 -2.403414) (xy 325.905589 -2.273299) (xy 325.78314 -2.148438) (xy 325.655329 -2.029072)
			(xy 325.522403 -1.91543) (xy 325.384617 -1.807732) (xy 325.242237 -1.706184) (xy 325.095537 -1.610984)
			(xy 324.9448 -1.522313) (xy 324.790318 -1.440344) (xy 324.711568 -1.402334) (xy 324.701746 -1.398176)
			(xy 324.680442 -1.397665) (xy 324.67042 -1.401318) (xy 324.64725 -1.410425) (xy 324.59914 -1.423224)
			(xy 324.549771 -1.429638) (xy 324.524878 -1.43002) (xy 324.497978 -1.429558) (xy 324.444711 -1.421996)
			(xy 324.393034 -1.407026) (xy 324.343973 -1.384945) (xy 324.298501 -1.35619) (xy 324.25752 -1.321333)
			(xy 324.221842 -1.281063) (xy 324.192175 -1.236181) (xy 324.1802 -1.212088) (xy 324.175132 -1.2027)
			(xy 324.158992 -1.188788) (xy 324.148958 -1.185164) (xy 324.069123 -1.161579) (xy 323.907838 -1.120281)
			(xy 323.744967 -1.085757) (xy 323.580797 -1.058066) (xy 323.415613 -1.037258) (xy 323.249705 -1.023368)
			(xy 323.083361 -1.016421) (xy 323.000116 -1.016) (xy 318.971422 -1.016) (xy 318.961358 -1.016438)
			(xy 318.942774 -1.024172) (xy 318.935354 -1.030986) (xy 318.91571 -1.050208) (xy 318.871891 -1.083381)
			(xy 318.823765 -1.109922) (xy 318.772328 -1.129283) (xy 318.718645 -1.141062) (xy 318.663828 -1.145016)
			(xy 318.609011 -1.141062) (xy 318.555328 -1.129283) (xy 318.503891 -1.109922) (xy 318.455765 -1.083381)
			(xy 318.411946 -1.050208) (xy 318.392302 -1.030986) (xy 318.384908 -1.02413) (xy 318.366309 -1.016381)
			(xy 318.356234 -1.016) (xy 313.891422 -1.016) (xy 313.881358 -1.016438) (xy 313.862774 -1.024172)
			(xy 313.855354 -1.030986) (xy 313.83571 -1.050208) (xy 313.791891 -1.083381) (xy 313.743765 -1.109922)
			(xy 313.692328 -1.129283) (xy 313.638645 -1.141062) (xy 313.583828 -1.145016) (xy 313.529011 -1.141062)
			(xy 313.475328 -1.129283) (xy 313.423891 -1.109922) (xy 313.375765 -1.083381) (xy 313.331946 -1.050208)
			(xy 313.312302 -1.030986) (xy 313.304908 -1.02413) (xy 313.286309 -1.016381) (xy 313.276234 -1.016)
			(xy 308.811422 -1.016) (xy 308.801358 -1.016438) (xy 308.782774 -1.024172) (xy 308.775354 -1.030986)
			(xy 308.75571 -1.050208) (xy 308.711891 -1.083381) (xy 308.663765 -1.109922) (xy 308.612328 -1.129283)
			(xy 308.558645 -1.141062) (xy 308.503828 -1.145016) (xy 308.449011 -1.141062) (xy 308.395328 -1.129283)
			(xy 308.343891 -1.109922) (xy 308.295765 -1.083381) (xy 308.251946 -1.050208) (xy 308.232302 -1.030986)
			(xy 308.224908 -1.02413) (xy 308.206309 -1.016381) (xy 308.196234 -1.016) (xy 303.731422 -1.016)
			(xy 303.721358 -1.016438) (xy 303.702774 -1.024172) (xy 303.695354 -1.030986) (xy 303.67571 -1.050208)
			(xy 303.631891 -1.083381) (xy 303.583765 -1.109922) (xy 303.532328 -1.129283) (xy 303.478645 -1.141062)
			(xy 303.423828 -1.145016) (xy 303.369011 -1.141062) (xy 303.315328 -1.129283) (xy 303.263891 -1.109922)
			(xy 303.215765 -1.083381) (xy 303.171946 -1.050208) (xy 303.152302 -1.030986) (xy 303.144908 -1.02413)
			(xy 303.126309 -1.016381) (xy 303.116234 -1.016) (xy 298.651422 -1.016) (xy 298.641358 -1.016438)
			(xy 298.622774 -1.024172) (xy 298.615354 -1.030986) (xy 298.59571 -1.050208) (xy 298.551891 -1.083381)
			(xy 298.503765 -1.109922) (xy 298.452328 -1.129283) (xy 298.398645 -1.141062) (xy 298.343828 -1.145016)
			(xy 298.289011 -1.141062) (xy 298.235328 -1.129283) (xy 298.183891 -1.109922) (xy 298.135765 -1.083381)
			(xy 298.091946 -1.050208) (xy 298.072302 -1.030986) (xy 298.064908 -1.02413) (xy 298.046309 -1.016381)
			(xy 298.036234 -1.016) (xy 293.571422 -1.016) (xy 293.561358 -1.016438) (xy 293.542774 -1.024172)
			(xy 293.535354 -1.030986) (xy 293.51571 -1.050208) (xy 293.471891 -1.083381) (xy 293.423765 -1.109922)
			(xy 293.372328 -1.129283) (xy 293.318645 -1.141062) (xy 293.263828 -1.145016) (xy 293.209011 -1.141062)
			(xy 293.155328 -1.129283) (xy 293.103891 -1.109922) (xy 293.055765 -1.083381) (xy 293.011946 -1.050208)
			(xy 292.992302 -1.030986) (xy 292.984908 -1.02413) (xy 292.966309 -1.016381) (xy 292.956234 -1.016)
			(xy 288.491422 -1.016) (xy 288.481358 -1.016438) (xy 288.462774 -1.024172) (xy 288.455354 -1.030986)
			(xy 288.43571 -1.050208) (xy 288.391891 -1.083381) (xy 288.343765 -1.109922) (xy 288.292328 -1.129283)
			(xy 288.238645 -1.141062) (xy 288.183828 -1.145016) (xy 288.129011 -1.141062) (xy 288.075328 -1.129283)
			(xy 288.023891 -1.109922) (xy 287.975765 -1.083381) (xy 287.931946 -1.050208) (xy 287.912302 -1.030986)
			(xy 287.904908 -1.02413) (xy 287.886309 -1.016381) (xy 287.876234 -1.016) (xy 283.411422 -1.016)
			(xy 283.401358 -1.016438) (xy 283.382774 -1.024172) (xy 283.375354 -1.030986) (xy 283.35571 -1.050208)
			(xy 283.311891 -1.083381) (xy 283.263765 -1.109922) (xy 283.212328 -1.129283) (xy 283.158645 -1.141062)
			(xy 283.103828 -1.145016) (xy 283.049011 -1.141062) (xy 282.995328 -1.129283) (xy 282.943891 -1.109922)
			(xy 282.895765 -1.083381) (xy 282.851946 -1.050208) (xy 282.832302 -1.030986) (xy 282.824908 -1.02413)
			(xy 282.806309 -1.016381) (xy 282.796234 -1.016) (xy 278.331422 -1.016) (xy 278.321358 -1.016438)
			(xy 278.302774 -1.024172) (xy 278.295354 -1.030986) (xy 278.27571 -1.050208) (xy 278.231891 -1.083381)
			(xy 278.183765 -1.109922) (xy 278.132328 -1.129283) (xy 278.078645 -1.141062) (xy 278.023828 -1.145016)
			(xy 277.969011 -1.141062) (xy 277.915328 -1.129283) (xy 277.863891 -1.109922) (xy 277.815765 -1.083381)
			(xy 277.771946 -1.050208) (xy 277.752302 -1.030986) (xy 277.744908 -1.02413) (xy 277.726309 -1.016381)
			(xy 277.716234 -1.016) (xy 273.251422 -1.016) (xy 273.241358 -1.016438) (xy 273.222774 -1.024172)
			(xy 273.215354 -1.030986) (xy 273.19571 -1.050208) (xy 273.151891 -1.083381) (xy 273.103765 -1.109922)
			(xy 273.052328 -1.129283) (xy 272.998645 -1.141062) (xy 272.943828 -1.145016) (xy 272.889011 -1.141062)
			(xy 272.835328 -1.129283) (xy 272.783891 -1.109922) (xy 272.735765 -1.083381) (xy 272.691946 -1.050208)
			(xy 272.672302 -1.030986) (xy 272.664908 -1.02413) (xy 272.646309 -1.016381) (xy 272.636234 -1.016)
			(xy 268.171422 -1.016) (xy 268.161358 -1.016438) (xy 268.142774 -1.024172) (xy 268.135354 -1.030986)
			(xy 268.11571 -1.050208) (xy 268.071891 -1.083381) (xy 268.023765 -1.109922) (xy 267.972328 -1.129283)
			(xy 267.918645 -1.141062) (xy 267.863828 -1.145016) (xy 267.809011 -1.141062) (xy 267.755328 -1.129283)
			(xy 267.703891 -1.109922) (xy 267.655765 -1.083381) (xy 267.611946 -1.050208) (xy 267.592302 -1.030986)
			(xy 267.584908 -1.02413) (xy 267.566309 -1.016381) (xy 267.556234 -1.016) (xy 263.091422 -1.016)
			(xy 263.081358 -1.016438) (xy 263.062774 -1.024172) (xy 263.055354 -1.030986) (xy 263.03571 -1.050208)
			(xy 262.991891 -1.083381) (xy 262.943765 -1.109922) (xy 262.892328 -1.129283) (xy 262.838645 -1.141062)
			(xy 262.783828 -1.145016) (xy 262.729011 -1.141062) (xy 262.675328 -1.129283) (xy 262.623891 -1.109922)
			(xy 262.575765 -1.083381) (xy 262.531946 -1.050208) (xy 262.512302 -1.030986) (xy 262.504908 -1.02413)
			(xy 262.486309 -1.016381) (xy 262.476234 -1.016) (xy 258.011422 -1.016) (xy 258.001358 -1.016438)
			(xy 257.982774 -1.024172) (xy 257.975354 -1.030986) (xy 257.95571 -1.050208) (xy 257.911891 -1.083381)
			(xy 257.863765 -1.109922) (xy 257.812328 -1.129283) (xy 257.758645 -1.141062) (xy 257.703828 -1.145016)
			(xy 257.649011 -1.141062) (xy 257.595328 -1.129283) (xy 257.543891 -1.109922) (xy 257.495765 -1.083381)
			(xy 257.451946 -1.050208) (xy 257.432302 -1.030986) (xy 257.424908 -1.02413) (xy 257.406309 -1.016381)
			(xy 257.396234 -1.016) (xy 252.931422 -1.016) (xy 252.921358 -1.016438) (xy 252.902774 -1.024172)
			(xy 252.895354 -1.030986) (xy 252.87571 -1.050208) (xy 252.831891 -1.083381) (xy 252.783765 -1.109922)
			(xy 252.732328 -1.129283) (xy 252.678645 -1.141062) (xy 252.623828 -1.145016) (xy 252.569011 -1.141062)
			(xy 252.515328 -1.129283) (xy 252.463891 -1.109922) (xy 252.415765 -1.083381) (xy 252.371946 -1.050208)
			(xy 252.352302 -1.030986) (xy 252.344908 -1.02413) (xy 252.326309 -1.016381) (xy 252.316234 -1.016)
			(xy 247.851422 -1.016) (xy 247.841358 -1.016438) (xy 247.822774 -1.024172) (xy 247.815354 -1.030986)
			(xy 247.79571 -1.050208) (xy 247.751891 -1.083381) (xy 247.703765 -1.109922) (xy 247.652328 -1.129283)
			(xy 247.598645 -1.141062) (xy 247.543828 -1.145016) (xy 247.489011 -1.141062) (xy 247.435328 -1.129283)
			(xy 247.383891 -1.109922) (xy 247.335765 -1.083381) (xy 247.291946 -1.050208) (xy 247.272302 -1.030986)
			(xy 247.264908 -1.02413) (xy 247.246309 -1.016381) (xy 247.236234 -1.016) (xy 242.771422 -1.016)
			(xy 242.761358 -1.016438) (xy 242.742774 -1.024172) (xy 242.735354 -1.030986) (xy 242.71571 -1.050208)
			(xy 242.671891 -1.083381) (xy 242.623765 -1.109922) (xy 242.572328 -1.129283) (xy 242.518645 -1.141062)
			(xy 242.463828 -1.145016) (xy 242.409011 -1.141062) (xy 242.355328 -1.129283) (xy 242.303891 -1.109922)
			(xy 242.255765 -1.083381) (xy 242.211946 -1.050208) (xy 242.192302 -1.030986) (xy 242.184908 -1.02413)
			(xy 242.166309 -1.016381) (xy 242.156234 -1.016) (xy 237.691422 -1.016) (xy 237.681358 -1.016438)
			(xy 237.662774 -1.024172) (xy 237.655354 -1.030986) (xy 237.63571 -1.050208) (xy 237.591891 -1.083381)
			(xy 237.543765 -1.109922) (xy 237.492328 -1.129283) (xy 237.438645 -1.141062) (xy 237.383828 -1.145016)
			(xy 237.329011 -1.141062) (xy 237.275328 -1.129283) (xy 237.223891 -1.109922) (xy 237.175765 -1.083381)
			(xy 237.131946 -1.050208) (xy 237.112302 -1.030986) (xy 237.104908 -1.02413) (xy 237.086309 -1.016381)
			(xy 237.076234 -1.016) (xy 232.611422 -1.016) (xy 232.601358 -1.016438) (xy 232.582774 -1.024172)
			(xy 232.575354 -1.030986) (xy 232.55571 -1.050208) (xy 232.511891 -1.083381) (xy 232.463765 -1.109922)
			(xy 232.412328 -1.129283) (xy 232.358645 -1.141062) (xy 232.303828 -1.145016) (xy 232.249011 -1.141062)
			(xy 232.195328 -1.129283) (xy 232.143891 -1.109922) (xy 232.095765 -1.083381) (xy 232.051946 -1.050208)
			(xy 232.032302 -1.030986) (xy 232.024908 -1.02413) (xy 232.006309 -1.016381) (xy 231.996234 -1.016)
			(xy 227.531422 -1.016) (xy 227.521358 -1.016438) (xy 227.502774 -1.024172) (xy 227.495354 -1.030986)
			(xy 227.47571 -1.050208) (xy 227.431891 -1.083381) (xy 227.383765 -1.109922) (xy 227.332328 -1.129283)
			(xy 227.278645 -1.141062) (xy 227.223828 -1.145016) (xy 227.169011 -1.141062) (xy 227.115328 -1.129283)
			(xy 227.063891 -1.109922) (xy 227.015765 -1.083381) (xy 226.971946 -1.050208) (xy 226.952302 -1.030986)
			(xy 226.944908 -1.02413) (xy 226.926309 -1.016381) (xy 226.916234 -1.016) (xy 222.451422 -1.016)
			(xy 222.441358 -1.016438) (xy 222.422774 -1.024172) (xy 222.415354 -1.030986) (xy 222.39571 -1.050208)
			(xy 222.351891 -1.083381) (xy 222.303765 -1.109922) (xy 222.252328 -1.129283) (xy 222.198645 -1.141062)
			(xy 222.143828 -1.145016) (xy 222.089011 -1.141062) (xy 222.035328 -1.129283) (xy 221.983891 -1.109922)
			(xy 221.935765 -1.083381) (xy 221.891946 -1.050208) (xy 221.872302 -1.030986) (xy 221.864908 -1.02413)
			(xy 221.846309 -1.016381) (xy 221.836234 -1.016) (xy 217.371422 -1.016) (xy 217.361358 -1.016438)
			(xy 217.342774 -1.024172) (xy 217.335354 -1.030986) (xy 217.31571 -1.050208) (xy 217.271891 -1.083381)
			(xy 217.223765 -1.109922) (xy 217.172328 -1.129283) (xy 217.118645 -1.141062) (xy 217.063828 -1.145016)
			(xy 217.009011 -1.141062) (xy 216.955328 -1.129283) (xy 216.903891 -1.109922) (xy 216.855765 -1.083381)
			(xy 216.811946 -1.050208) (xy 216.792302 -1.030986) (xy 216.784908 -1.02413) (xy 216.766309 -1.016381)
			(xy 216.756234 -1.016) (xy 212.291422 -1.016) (xy 212.281358 -1.016438) (xy 212.262774 -1.024172)
			(xy 212.255354 -1.030986) (xy 212.23571 -1.050208) (xy 212.191891 -1.083381) (xy 212.143765 -1.109922)
			(xy 212.092328 -1.129283) (xy 212.038645 -1.141062) (xy 211.983828 -1.145016) (xy 211.929011 -1.141062)
			(xy 211.875328 -1.129283) (xy 211.823891 -1.109922) (xy 211.775765 -1.083381) (xy 211.731946 -1.050208)
			(xy 211.712302 -1.030986) (xy 211.704908 -1.02413) (xy 211.686309 -1.016381) (xy 211.676234 -1.016)
			(xy 207.211422 -1.016) (xy 207.201358 -1.016438) (xy 207.182774 -1.024172) (xy 207.175354 -1.030986)
			(xy 207.15571 -1.050208) (xy 207.111891 -1.083381) (xy 207.063765 -1.109922) (xy 207.012328 -1.129283)
			(xy 206.958645 -1.141062) (xy 206.903828 -1.145016) (xy 206.849011 -1.141062) (xy 206.795328 -1.129283)
			(xy 206.743891 -1.109922) (xy 206.695765 -1.083381) (xy 206.651946 -1.050208) (xy 206.632302 -1.030986)
			(xy 206.624908 -1.02413) (xy 206.606309 -1.016381) (xy 206.596234 -1.016) (xy 202.131422 -1.016)
			(xy 202.121358 -1.016438) (xy 202.102774 -1.024172) (xy 202.095354 -1.030986) (xy 202.07571 -1.050208)
			(xy 202.031891 -1.083381) (xy 201.983765 -1.109922) (xy 201.932328 -1.129283) (xy 201.878645 -1.141062)
			(xy 201.823828 -1.145016) (xy 201.769011 -1.141062) (xy 201.715328 -1.129283) (xy 201.663891 -1.109922)
			(xy 201.615765 -1.083381) (xy 201.571946 -1.050208) (xy 201.552302 -1.030986) (xy 201.544908 -1.02413)
			(xy 201.526309 -1.016381) (xy 201.516234 -1.016) (xy 197.051422 -1.016) (xy 197.041358 -1.016438)
			(xy 197.022774 -1.024172) (xy 197.015354 -1.030986) (xy 196.99571 -1.050208) (xy 196.951891 -1.083381)
			(xy 196.903765 -1.109922) (xy 196.852328 -1.129283) (xy 196.798645 -1.141062) (xy 196.743828 -1.145016)
			(xy 196.689011 -1.141062) (xy 196.635328 -1.129283) (xy 196.583891 -1.109922) (xy 196.535765 -1.083381)
			(xy 196.491946 -1.050208) (xy 196.472302 -1.030986) (xy 196.464908 -1.02413) (xy 196.446309 -1.016381)
			(xy 196.436234 -1.016) (xy 191.971422 -1.016) (xy 191.961358 -1.016438) (xy 191.942774 -1.024172)
			(xy 191.935354 -1.030986) (xy 191.91571 -1.050208) (xy 191.871891 -1.083381) (xy 191.823765 -1.109922)
			(xy 191.772328 -1.129283) (xy 191.718645 -1.141062) (xy 191.663828 -1.145016) (xy 191.609011 -1.141062)
			(xy 191.555328 -1.129283) (xy 191.503891 -1.109922) (xy 191.455765 -1.083381) (xy 191.411946 -1.050208)
			(xy 191.392302 -1.030986) (xy 191.384908 -1.02413) (xy 191.366309 -1.016381) (xy 191.356234 -1.016)
			(xy 186.891422 -1.016) (xy 186.881358 -1.016438) (xy 186.862774 -1.024172) (xy 186.855354 -1.030986)
			(xy 186.83571 -1.050208) (xy 186.791891 -1.083381) (xy 186.743765 -1.109922) (xy 186.692328 -1.129283)
			(xy 186.638645 -1.141062) (xy 186.583828 -1.145016) (xy 186.529011 -1.141062) (xy 186.475328 -1.129283)
			(xy 186.423891 -1.109922) (xy 186.375765 -1.083381) (xy 186.331946 -1.050208) (xy 186.312302 -1.030986)
			(xy 186.304908 -1.02413) (xy 186.286309 -1.016381) (xy 186.276234 -1.016) (xy 181.811422 -1.016)
			(xy 181.801358 -1.016438) (xy 181.782774 -1.024172) (xy 181.775354 -1.030986) (xy 181.75571 -1.050208)
			(xy 181.711891 -1.083381) (xy 181.663765 -1.109922) (xy 181.612328 -1.129283) (xy 181.558645 -1.141062)
			(xy 181.503828 -1.145016) (xy 181.449011 -1.141062) (xy 181.395328 -1.129283) (xy 181.343891 -1.109922)
			(xy 181.295765 -1.083381) (xy 181.251946 -1.050208) (xy 181.232302 -1.030986) (xy 181.224908 -1.02413)
			(xy 181.206309 -1.016381) (xy 181.196234 -1.016) (xy 176.731422 -1.016) (xy 176.721358 -1.016438)
			(xy 176.702774 -1.024172) (xy 176.695354 -1.030986) (xy 176.67571 -1.050208) (xy 176.631891 -1.083381)
			(xy 176.583765 -1.109922) (xy 176.532328 -1.129283) (xy 176.478645 -1.141062) (xy 176.423828 -1.145016)
			(xy 176.369011 -1.141062) (xy 176.315328 -1.129283) (xy 176.263891 -1.109922) (xy 176.215765 -1.083381)
			(xy 176.171946 -1.050208) (xy 176.152302 -1.030986) (xy 176.144908 -1.02413) (xy 176.126309 -1.016381)
			(xy 176.116234 -1.016) (xy 171.651422 -1.016) (xy 171.641358 -1.016438) (xy 171.622774 -1.024172)
			(xy 171.615354 -1.030986) (xy 171.59571 -1.050208) (xy 171.551891 -1.083381) (xy 171.503765 -1.109922)
			(xy 171.452328 -1.129283) (xy 171.398645 -1.141062) (xy 171.343828 -1.145016) (xy 171.289011 -1.141062)
			(xy 171.235328 -1.129283) (xy 171.183891 -1.109922) (xy 171.135765 -1.083381) (xy 171.091946 -1.050208)
			(xy 171.072302 -1.030986) (xy 171.064908 -1.02413) (xy 171.046309 -1.016381) (xy 171.036234 -1.016)
			(xy 166.571422 -1.016) (xy 166.561358 -1.016438) (xy 166.542774 -1.024172) (xy 166.535354 -1.030986)
			(xy 166.51571 -1.050208) (xy 166.471891 -1.083381) (xy 166.423765 -1.109922) (xy 166.372328 -1.129283)
			(xy 166.318645 -1.141062) (xy 166.263828 -1.145016) (xy 166.209011 -1.141062) (xy 166.155328 -1.129283)
			(xy 166.103891 -1.109922) (xy 166.055765 -1.083381) (xy 166.011946 -1.050208) (xy 165.992302 -1.030986)
			(xy 165.984908 -1.02413) (xy 165.966309 -1.016381) (xy 165.956234 -1.016) (xy 161.491422 -1.016)
			(xy 161.481358 -1.016438) (xy 161.462774 -1.024172) (xy 161.455354 -1.030986) (xy 161.43571 -1.050208)
			(xy 161.391891 -1.083381) (xy 161.343765 -1.109922) (xy 161.292328 -1.129283) (xy 161.238645 -1.141062)
			(xy 161.183828 -1.145016) (xy 161.129011 -1.141062) (xy 161.075328 -1.129283) (xy 161.023891 -1.109922)
			(xy 160.975765 -1.083381) (xy 160.931946 -1.050208) (xy 160.912302 -1.030986) (xy 160.904908 -1.02413)
			(xy 160.886309 -1.016381) (xy 160.876234 -1.016) (xy 156.411422 -1.016) (xy 156.401358 -1.016438)
			(xy 156.382774 -1.024172) (xy 156.375354 -1.030986) (xy 156.35571 -1.050208) (xy 156.311891 -1.083381)
			(xy 156.263765 -1.109922) (xy 156.212328 -1.129283) (xy 156.158645 -1.141062) (xy 156.103828 -1.145016)
			(xy 156.049011 -1.141062) (xy 155.995328 -1.129283) (xy 155.943891 -1.109922) (xy 155.895765 -1.083381)
			(xy 155.851946 -1.050208) (xy 155.832302 -1.030986) (xy 155.824908 -1.02413) (xy 155.806309 -1.016381)
			(xy 155.796234 -1.016) (xy 151.331422 -1.016) (xy 151.321358 -1.016438) (xy 151.302774 -1.024172)
			(xy 151.295354 -1.030986) (xy 151.27571 -1.050208) (xy 151.231891 -1.083381) (xy 151.183765 -1.109922)
			(xy 151.132328 -1.129283) (xy 151.078645 -1.141062) (xy 151.023828 -1.145016) (xy 150.969011 -1.141062)
			(xy 150.915328 -1.129283) (xy 150.863891 -1.109922) (xy 150.815765 -1.083381) (xy 150.771946 -1.050208)
			(xy 150.752302 -1.030986) (xy 150.744908 -1.02413) (xy 150.726309 -1.016381) (xy 150.716234 -1.016)
			(xy 146.251422 -1.016) (xy 146.241358 -1.016438) (xy 146.222774 -1.024172) (xy 146.215354 -1.030986)
			(xy 146.19571 -1.050208) (xy 146.151891 -1.083381) (xy 146.103765 -1.109922) (xy 146.052328 -1.129283)
			(xy 145.998645 -1.141062) (xy 145.943828 -1.145016) (xy 145.889011 -1.141062) (xy 145.835328 -1.129283)
			(xy 145.783891 -1.109922) (xy 145.735765 -1.083381) (xy 145.691946 -1.050208) (xy 145.672302 -1.030986)
			(xy 145.664908 -1.02413) (xy 145.646309 -1.016381) (xy 145.636234 -1.016) (xy 141.171422 -1.016)
			(xy 141.161358 -1.016438) (xy 141.142774 -1.024172) (xy 141.135354 -1.030986) (xy 141.11571 -1.050208)
			(xy 141.071891 -1.083381) (xy 141.023765 -1.109922) (xy 140.972328 -1.129283) (xy 140.918645 -1.141062)
			(xy 140.863828 -1.145016) (xy 140.809011 -1.141062) (xy 140.755328 -1.129283) (xy 140.703891 -1.109922)
			(xy 140.655765 -1.083381) (xy 140.611946 -1.050208) (xy 140.592302 -1.030986) (xy 140.584908 -1.02413)
			(xy 140.566309 -1.016381) (xy 140.556234 -1.016) (xy 136.091422 -1.016) (xy 136.081358 -1.016438)
			(xy 136.062774 -1.024172) (xy 136.055354 -1.030986) (xy 136.03571 -1.050208) (xy 135.991891 -1.083381)
			(xy 135.943765 -1.109922) (xy 135.892328 -1.129283) (xy 135.838645 -1.141062) (xy 135.783828 -1.145016)
			(xy 135.729011 -1.141062) (xy 135.675328 -1.129283) (xy 135.623891 -1.109922) (xy 135.575765 -1.083381)
			(xy 135.531946 -1.050208) (xy 135.512302 -1.030986) (xy 135.504908 -1.02413) (xy 135.486309 -1.016381)
			(xy 135.476234 -1.016) (xy 131.011422 -1.016) (xy 131.001358 -1.016438) (xy 130.982774 -1.024172)
			(xy 130.975354 -1.030986) (xy 130.95571 -1.050208) (xy 130.911891 -1.083381) (xy 130.863765 -1.109922)
			(xy 130.812328 -1.129283) (xy 130.758645 -1.141062) (xy 130.703828 -1.145016) (xy 130.649011 -1.141062)
			(xy 130.595328 -1.129283) (xy 130.543891 -1.109922) (xy 130.495765 -1.083381) (xy 130.451946 -1.050208)
			(xy 130.432302 -1.030986) (xy 130.424908 -1.02413) (xy 130.406309 -1.016381) (xy 130.396234 -1.016)
			(xy 125.931422 -1.016) (xy 125.921358 -1.016438) (xy 125.902774 -1.024172) (xy 125.895354 -1.030986)
			(xy 125.87571 -1.050208) (xy 125.831891 -1.083381) (xy 125.783765 -1.109922) (xy 125.732328 -1.129283)
			(xy 125.678645 -1.141062) (xy 125.623828 -1.145016) (xy 125.569011 -1.141062) (xy 125.515328 -1.129283)
			(xy 125.463891 -1.109922) (xy 125.415765 -1.083381) (xy 125.371946 -1.050208) (xy 125.352302 -1.030986)
			(xy 125.344908 -1.02413) (xy 125.326309 -1.016381) (xy 125.316234 -1.016) (xy 120.851422 -1.016)
			(xy 120.841358 -1.016438) (xy 120.822774 -1.024172) (xy 120.815354 -1.030986) (xy 120.79571 -1.050208)
			(xy 120.751891 -1.083381) (xy 120.703765 -1.109922) (xy 120.652328 -1.129283) (xy 120.598645 -1.141062)
			(xy 120.543828 -1.145016) (xy 120.489011 -1.141062) (xy 120.435328 -1.129283) (xy 120.383891 -1.109922)
			(xy 120.335765 -1.083381) (xy 120.291946 -1.050208) (xy 120.272302 -1.030986) (xy 120.264908 -1.02413)
			(xy 120.246309 -1.016381) (xy 120.236234 -1.016) (xy 115.771422 -1.016) (xy 115.761358 -1.016438)
			(xy 115.742774 -1.024172) (xy 115.735354 -1.030986) (xy 115.71571 -1.050208) (xy 115.671891 -1.083381)
			(xy 115.623765 -1.109922) (xy 115.572328 -1.129283) (xy 115.518645 -1.141062) (xy 115.463828 -1.145016)
			(xy 115.409011 -1.141062) (xy 115.355328 -1.129283) (xy 115.303891 -1.109922) (xy 115.255765 -1.083381)
			(xy 115.211946 -1.050208) (xy 115.192302 -1.030986) (xy 115.184908 -1.02413) (xy 115.166309 -1.016381)
			(xy 115.156234 -1.016) (xy 110.691422 -1.016) (xy 110.681358 -1.016438) (xy 110.662774 -1.024172)
			(xy 110.655354 -1.030986) (xy 110.63571 -1.050208) (xy 110.591891 -1.083381) (xy 110.543765 -1.109922)
			(xy 110.492328 -1.129283) (xy 110.438645 -1.141062) (xy 110.383828 -1.145016) (xy 110.329011 -1.141062)
			(xy 110.275328 -1.129283) (xy 110.223891 -1.109922) (xy 110.175765 -1.083381) (xy 110.131946 -1.050208)
			(xy 110.112302 -1.030986) (xy 110.104908 -1.02413) (xy 110.086309 -1.016381) (xy 110.076234 -1.016)
			(xy 105.611422 -1.016) (xy 105.601358 -1.016438) (xy 105.582774 -1.024172) (xy 105.575354 -1.030986)
			(xy 105.55571 -1.050208) (xy 105.511891 -1.083381) (xy 105.463765 -1.109922) (xy 105.412328 -1.129283)
			(xy 105.358645 -1.141062) (xy 105.303828 -1.145016) (xy 105.249011 -1.141062) (xy 105.195328 -1.129283)
			(xy 105.143891 -1.109922) (xy 105.095765 -1.083381) (xy 105.051946 -1.050208) (xy 105.032302 -1.030986)
			(xy 105.024908 -1.02413) (xy 105.006309 -1.016381) (xy 104.996234 -1.016) (xy 100.531422 -1.016)
			(xy 100.521358 -1.016438) (xy 100.502774 -1.024172) (xy 100.495354 -1.030986) (xy 100.47571 -1.050208)
			(xy 100.431891 -1.083381) (xy 100.383765 -1.109922) (xy 100.332328 -1.129283) (xy 100.278645 -1.141062)
			(xy 100.223828 -1.145016) (xy 100.169011 -1.141062) (xy 100.115328 -1.129283) (xy 100.063891 -1.109922)
			(xy 100.015765 -1.083381) (xy 99.971946 -1.050208) (xy 99.952302 -1.030986) (xy 99.944908 -1.02413)
			(xy 99.926309 -1.016381) (xy 99.916234 -1.016) (xy 95.451422 -1.016) (xy 95.441358 -1.016438) (xy 95.422774 -1.024172)
			(xy 95.415354 -1.030986) (xy 95.39571 -1.050208) (xy 95.351891 -1.083381) (xy 95.303765 -1.109922)
			(xy 95.252328 -1.129283) (xy 95.198645 -1.141062) (xy 95.143828 -1.145016) (xy 95.089011 -1.141062)
			(xy 95.035328 -1.129283) (xy 94.983891 -1.109922) (xy 94.935765 -1.083381) (xy 94.891946 -1.050208)
			(xy 94.872302 -1.030986) (xy 94.864908 -1.02413) (xy 94.846309 -1.016381) (xy 94.836234 -1.016) (xy 90.371422 -1.016)
			(xy 90.361358 -1.016438) (xy 90.342774 -1.024172) (xy 90.335354 -1.030986) (xy 90.31571 -1.050208)
			(xy 90.271891 -1.083381) (xy 90.223765 -1.109922) (xy 90.172328 -1.129283) (xy 90.118645 -1.141062)
			(xy 90.063828 -1.145016) (xy 90.009011 -1.141062) (xy 89.955328 -1.129283) (xy 89.903891 -1.109922)
			(xy 89.855765 -1.083381) (xy 89.811946 -1.050208) (xy 89.792302 -1.030986) (xy 89.784908 -1.02413)
			(xy 89.766309 -1.016381) (xy 89.756234 -1.016) (xy 85.291422 -1.016) (xy 85.281358 -1.016438) (xy 85.262774 -1.024172)
			(xy 85.255354 -1.030986) (xy 85.23571 -1.050208) (xy 85.191891 -1.083381) (xy 85.143765 -1.109922)
			(xy 85.092328 -1.129283) (xy 85.038645 -1.141062) (xy 84.983828 -1.145016) (xy 84.929011 -1.141062)
			(xy 84.875328 -1.129283) (xy 84.823891 -1.109922) (xy 84.775765 -1.083381) (xy 84.731946 -1.050208)
			(xy 84.712302 -1.030986) (xy 84.704908 -1.02413) (xy 84.686309 -1.016381) (xy 84.676234 -1.016) (xy 80.211422 -1.016)
			(xy 80.201358 -1.016438) (xy 80.182774 -1.024172) (xy 80.175354 -1.030986) (xy 80.15571 -1.050208)
			(xy 80.111891 -1.083381) (xy 80.063765 -1.109922) (xy 80.012328 -1.129283) (xy 79.958645 -1.141062)
			(xy 79.903828 -1.145016) (xy 79.849011 -1.141062) (xy 79.795328 -1.129283) (xy 79.743891 -1.109922)
			(xy 79.695765 -1.083381) (xy 79.651946 -1.050208) (xy 79.632302 -1.030986) (xy 79.624908 -1.02413)
			(xy 79.606309 -1.016381) (xy 79.596234 -1.016) (xy 75.131422 -1.016) (xy 75.121358 -1.016438) (xy 75.102774 -1.024172)
			(xy 75.095354 -1.030986) (xy 75.07571 -1.050208) (xy 75.031891 -1.083381) (xy 74.983765 -1.109922)
			(xy 74.932328 -1.129283) (xy 74.878645 -1.141062) (xy 74.823828 -1.145016) (xy 74.769011 -1.141062)
			(xy 74.715328 -1.129283) (xy 74.663891 -1.109922) (xy 74.615765 -1.083381) (xy 74.571946 -1.050208)
			(xy 74.552302 -1.030986) (xy 74.544908 -1.02413) (xy 74.526309 -1.016381) (xy 74.516234 -1.016) (xy 70.051422 -1.016)
			(xy 70.041358 -1.016438) (xy 70.022774 -1.024172) (xy 70.015354 -1.030986) (xy 69.99571 -1.050208)
			(xy 69.951891 -1.083381) (xy 69.903765 -1.109922) (xy 69.852328 -1.129283) (xy 69.798645 -1.141062)
			(xy 69.743828 -1.145016) (xy 69.689011 -1.141062) (xy 69.635328 -1.129283) (xy 69.583891 -1.109922)
			(xy 69.535765 -1.083381) (xy 69.491946 -1.050208) (xy 69.472302 -1.030986) (xy 69.464908 -1.02413)
			(xy 69.446309 -1.016381) (xy 69.436234 -1.016) (xy 64.971422 -1.016) (xy 64.961358 -1.016438) (xy 64.942774 -1.024172)
			(xy 64.935354 -1.030986) (xy 64.91571 -1.050208) (xy 64.871891 -1.083381) (xy 64.823765 -1.109922)
			(xy 64.772328 -1.129283) (xy 64.718645 -1.141062) (xy 64.663828 -1.145016) (xy 64.609011 -1.141062)
			(xy 64.555328 -1.129283) (xy 64.503891 -1.109922) (xy 64.455765 -1.083381) (xy 64.411946 -1.050208)
			(xy 64.392302 -1.030986) (xy 64.384908 -1.02413) (xy 64.366309 -1.016381) (xy 64.356234 -1.016) (xy 59.891422 -1.016)
			(xy 59.881358 -1.016438) (xy 59.862774 -1.024172) (xy 59.855354 -1.030986) (xy 59.83571 -1.050208)
			(xy 59.791891 -1.083381) (xy 59.743765 -1.109922) (xy 59.692328 -1.129283) (xy 59.638645 -1.141062)
			(xy 59.583828 -1.145016) (xy 59.529011 -1.141062) (xy 59.475328 -1.129283) (xy 59.423891 -1.109922)
			(xy 59.375765 -1.083381) (xy 59.331946 -1.050208) (xy 59.312302 -1.030986) (xy 59.304908 -1.02413)
			(xy 59.286309 -1.016381) (xy 59.276234 -1.016) (xy 54.811422 -1.016) (xy 54.801358 -1.016438) (xy 54.782774 -1.024172)
			(xy 54.775354 -1.030986) (xy 54.75571 -1.050208) (xy 54.711891 -1.083381) (xy 54.663765 -1.109922)
			(xy 54.612328 -1.129283) (xy 54.558645 -1.141062) (xy 54.503828 -1.145016) (xy 54.449011 -1.141062)
			(xy 54.395328 -1.129283) (xy 54.343891 -1.109922) (xy 54.295765 -1.083381) (xy 54.251946 -1.050208)
			(xy 54.232302 -1.030986) (xy 54.224908 -1.02413) (xy 54.206309 -1.016381) (xy 54.196234 -1.016) (xy 49.731422 -1.016)
			(xy 49.721358 -1.016438) (xy 49.702774 -1.024172) (xy 49.695354 -1.030986) (xy 49.67571 -1.050208)
			(xy 49.631891 -1.083381) (xy 49.583765 -1.109922) (xy 49.532328 -1.129283) (xy 49.478645 -1.141062)
			(xy 49.423828 -1.145016) (xy 49.369011 -1.141062) (xy 49.315328 -1.129283) (xy 49.263891 -1.109922)
			(xy 49.215765 -1.083381) (xy 49.171946 -1.050208) (xy 49.152302 -1.030986) (xy 49.144908 -1.02413)
			(xy 49.126309 -1.016381) (xy 49.116234 -1.016) (xy 44.651422 -1.016) (xy 44.641358 -1.016438) (xy 44.622774 -1.024172)
			(xy 44.615354 -1.030986) (xy 44.59571 -1.050208) (xy 44.551891 -1.083381) (xy 44.503765 -1.109922)
			(xy 44.452328 -1.129283) (xy 44.398645 -1.141062) (xy 44.343828 -1.145016) (xy 44.289011 -1.141062)
			(xy 44.235328 -1.129283) (xy 44.183891 -1.109922) (xy 44.135765 -1.083381) (xy 44.091946 -1.050208)
			(xy 44.072302 -1.030986) (xy 44.064908 -1.02413) (xy 44.046309 -1.016381) (xy 44.036234 -1.016) (xy 39.571422 -1.016)
			(xy 39.561358 -1.016438) (xy 39.542774 -1.024172) (xy 39.535354 -1.030986) (xy 39.51571 -1.050208)
			(xy 39.471891 -1.083381) (xy 39.423765 -1.109922) (xy 39.372328 -1.129283) (xy 39.318645 -1.141062)
			(xy 39.263828 -1.145016) (xy 39.209011 -1.141062) (xy 39.155328 -1.129283) (xy 39.103891 -1.109922)
			(xy 39.055765 -1.083381) (xy 39.011946 -1.050208) (xy 38.992302 -1.030986) (xy 38.984908 -1.02413)
			(xy 38.966309 -1.016381) (xy 38.956234 -1.016) (xy 34.491422 -1.016) (xy 34.481358 -1.016438) (xy 34.462774 -1.024172)
			(xy 34.455354 -1.030986) (xy 34.43571 -1.050208) (xy 34.391891 -1.083381) (xy 34.343765 -1.109922)
			(xy 34.292328 -1.129283) (xy 34.238645 -1.141062) (xy 34.183828 -1.145016) (xy 34.129011 -1.141062)
			(xy 34.075328 -1.129283) (xy 34.023891 -1.109922) (xy 33.975765 -1.083381) (xy 33.931946 -1.050208)
			(xy 33.912302 -1.030986) (xy 33.904908 -1.02413) (xy 33.886309 -1.016381) (xy 33.876234 -1.016) (xy 29.411422 -1.016)
			(xy 29.401358 -1.016438) (xy 29.382774 -1.024172) (xy 29.375354 -1.030986) (xy 29.35571 -1.050208)
			(xy 29.311891 -1.083381) (xy 29.263765 -1.109922) (xy 29.212328 -1.129283) (xy 29.158645 -1.141062)
			(xy 29.103828 -1.145016) (xy 29.049011 -1.141062) (xy 28.995328 -1.129283) (xy 28.943891 -1.109922)
			(xy 28.895765 -1.083381) (xy 28.851946 -1.050208) (xy 28.832302 -1.030986) (xy 28.824908 -1.02413)
			(xy 28.806309 -1.016381) (xy 28.796234 -1.016) (xy 24.331422 -1.016) (xy 24.321358 -1.016438) (xy 24.302774 -1.024172)
			(xy 24.295354 -1.030986) (xy 24.27571 -1.050208) (xy 24.231891 -1.083381) (xy 24.183765 -1.109922)
			(xy 24.132328 -1.129283) (xy 24.078645 -1.141062) (xy 24.023828 -1.145016) (xy 23.969011 -1.141062)
			(xy 23.915328 -1.129283) (xy 23.863891 -1.109922) (xy 23.815765 -1.083381) (xy 23.771946 -1.050208)
			(xy 23.752302 -1.030986) (xy 23.744908 -1.02413) (xy 23.726309 -1.016381) (xy 23.716234 -1.016) (xy 19.251422 -1.016)
			(xy 19.241358 -1.016438) (xy 19.222774 -1.024172) (xy 19.215354 -1.030986) (xy 19.19571 -1.050208)
			(xy 19.151891 -1.083381) (xy 19.103765 -1.109922) (xy 19.052328 -1.129283) (xy 18.998645 -1.141062)
			(xy 18.943828 -1.145016) (xy 18.889011 -1.141062) (xy 18.835328 -1.129283) (xy 18.783891 -1.109922)
			(xy 18.735765 -1.083381) (xy 18.691946 -1.050208) (xy 18.672302 -1.030986) (xy 18.664908 -1.02413)
			(xy 18.646309 -1.016381) (xy 18.636234 -1.016) (xy 14.171422 -1.016) (xy 14.161358 -1.016438) (xy 14.142774 -1.024172)
			(xy 14.135354 -1.030986) (xy 14.11571 -1.050208) (xy 14.071891 -1.083381) (xy 14.023765 -1.109922)
			(xy 13.972328 -1.129283) (xy 13.918645 -1.141062) (xy 13.863828 -1.145016) (xy 13.809011 -1.141062)
			(xy 13.755328 -1.129283) (xy 13.703891 -1.109922) (xy 13.655765 -1.083381) (xy 13.611946 -1.050208)
			(xy 13.592302 -1.030986) (xy 13.584908 -1.02413) (xy 13.566309 -1.016381) (xy 13.556234 -1.016) (xy 9.091422 -1.016)
			(xy 9.081358 -1.016438) (xy 9.062774 -1.024172) (xy 9.055354 -1.030986) (xy 9.03571 -1.050208) (xy 8.991891 -1.083381)
			(xy 8.943765 -1.109922) (xy 8.892328 -1.129283) (xy 8.838645 -1.141062) (xy 8.783828 -1.145016) (xy 8.729011 -1.141062)
			(xy 8.675328 -1.129283) (xy 8.623891 -1.109922) (xy 8.575765 -1.083381) (xy 8.531946 -1.050208) (xy 8.512302 -1.030986)
			(xy 8.504908 -1.02413) (xy 8.486309 -1.016381) (xy 8.476234 -1.016) (xy 4.99999 -1.016) (xy 4.911869 -1.016489)
			(xy 4.735799 -1.024283) (xy 4.560245 -1.039852) (xy 4.385551 -1.063166) (xy 4.212059 -1.094177) (xy 4.125976 -1.113028)
			(xy 4.11582 -1.115919) (xy 4.0989 -1.128516) (xy 4.09321 -1.137412) (xy 4.078515 -1.162024) (xy 4.042904 -1.206939)
			(xy 4.00098 -1.246029) (xy 3.953685 -1.278413) (xy 3.902081 -1.303366) (xy 3.847327 -1.320326) (xy 3.790654 -1.328912)
			(xy 3.761994 -1.329436) (xy 3.73286 -1.328887) (xy 3.675272 -1.320014) (xy 3.61971 -1.30246) (xy 3.593338 -1.290066)
			(xy 3.583614 -1.285902) (xy 3.562501 -1.285002) (xy 3.552444 -1.288288) (xy 3.46867 -1.321501) (xy 3.303889 -1.394516)
			(xy 3.142578 -1.474907) (xy 2.985068 -1.562511) (xy 2.83168 -1.657147) (xy 2.682728 -1.758623) (xy 2.538518 -1.86673)
			(xy 2.399343 -1.981248) (xy 2.265489 -2.101942) (xy 2.13723 -2.228565) (xy 2.014828 -2.360859) (xy 1.898533 -2.498552)
			(xy 1.788584 -2.641363) (xy 1.685205 -2.789) (xy 1.588607 -2.941161) (xy 1.498989 -3.097534) (xy 1.416534 -3.257799)
			(xy 1.34141 -3.421629) (xy 1.273772 -3.588689) (xy 1.213756 -3.758636) (xy 1.161488 -3.931123) (xy 1.117072 -4.105798)
			(xy 1.0806 -4.282302) (xy 1.0666 -4.36987) (xy 242.877075 -4.36987) (xy 242.877075 -4.24073) (xy 242.885025 -4.111835)
			(xy 242.900895 -3.983675) (xy 242.924624 -3.856734) (xy 242.956123 -3.731495) (xy 242.995272 -3.608432)
			(xy 243.041923 -3.488013) (xy 243.095898 -3.370694) (xy 243.156993 -3.25692) (xy 243.224976 -3.147123)
			(xy 243.29959 -3.04172) (xy 243.380551 -2.94111) (xy 243.467551 -2.845675) (xy 243.560262 -2.755776)
			(xy 243.658332 -2.671755) (xy 243.761387 -2.593931) (xy 243.869038 -2.522599) (xy 243.980877 -2.458029)
			(xy 244.096478 -2.400467) (xy 244.215403 -2.35013) (xy 244.337202 -2.30721) (xy 244.461412 -2.271869)
			(xy 244.587561 -2.244242) (xy 244.715173 -2.224433) (xy 244.843762 -2.212517) (xy 244.97284 -2.208541)
			(xy 245.101918 -2.212517) (xy 245.230507 -2.224433) (xy 245.358119 -2.244242) (xy 245.484268 -2.271869)
			(xy 245.608478 -2.30721) (xy 245.730277 -2.35013) (xy 245.849202 -2.400467) (xy 245.964803 -2.458029)
			(xy 246.076642 -2.522599) (xy 246.184293 -2.593931) (xy 246.287348 -2.671755) (xy 246.385418 -2.755776)
			(xy 246.478129 -2.845675) (xy 246.565129 -2.94111) (xy 246.64609 -3.04172) (xy 246.720704 -3.147123)
			(xy 246.788687 -3.25692) (xy 246.849782 -3.370694) (xy 246.903757 -3.488013) (xy 246.950408 -3.608432)
			(xy 246.989557 -3.731495) (xy 247.021056 -3.856734) (xy 247.044785 -3.983675) (xy 247.060655 -4.111835)
			(xy 247.068605 -4.24073) (xy 247.069102 -4.3053) (xy 247.068605 -4.36987) (xy 247.060655 -4.498765)
			(xy 247.044785 -4.626925) (xy 247.021056 -4.753866) (xy 246.989557 -4.879105) (xy 246.950408 -5.002168)
			(xy 246.903757 -5.122587) (xy 246.849782 -5.239906) (xy 246.788687 -5.35368) (xy 246.720704 -5.463477)
			(xy 246.64609 -5.56888) (xy 246.565129 -5.66949) (xy 246.478129 -5.764925) (xy 246.385418 -5.854824)
			(xy 246.287348 -5.938845) (xy 246.184293 -6.016669) (xy 246.076642 -6.088001) (xy 245.964803 -6.152571)
			(xy 245.849202 -6.210133) (xy 245.730277 -6.26047) (xy 245.608478 -6.30339) (xy 245.484268 -6.338731)
			(xy 245.358119 -6.366358) (xy 245.230507 -6.386167) (xy 245.101918 -6.398083) (xy 244.97284 -6.40206)
			(xy 244.843762 -6.398083) (xy 244.715173 -6.386167) (xy 244.587561 -6.366358) (xy 244.461412 -6.338731)
			(xy 244.337202 -6.30339) (xy 244.215403 -6.26047) (xy 244.096478 -6.210133) (xy 243.980877 -6.152571)
			(xy 243.869038 -6.088001) (xy 243.761387 -6.016669) (xy 243.658332 -5.938845) (xy 243.560262 -5.854824)
			(xy 243.467551 -5.764925) (xy 243.380551 -5.66949) (xy 243.29959 -5.56888) (xy 243.224976 -5.463477)
			(xy 243.156993 -5.35368) (xy 243.095898 -5.239906) (xy 243.041923 -5.122587) (xy 242.995272 -5.002168)
			(xy 242.956123 -4.879105) (xy 242.924624 -4.753866) (xy 242.900895 -4.626925) (xy 242.885025 -4.498765)
			(xy 242.877075 -4.36987) (xy 1.0666 -4.36987) (xy 1.052147 -4.460275) (xy 1.031771 -4.639352) (xy 1.025144 -4.729226)
			(xy 1.024848 -4.739861) (xy 1.03208 -4.759851) (xy 1.039114 -4.767834) (xy 1.058824 -4.789242) (xy 1.092179 -4.836924)
			(xy 1.117897 -4.889122) (xy 1.135381 -4.944623) (xy 1.144222 -5.002137) (xy 1.144778 -5.031232) (xy 1.14422 -5.06149)
			(xy 1.134708 -5.121253) (xy 1.115877 -5.178764) (xy 1.088201 -5.23258) (xy 1.052374 -5.281351) (xy 1.03124 -5.303012)
			(xy 1.024327 -5.310384) (xy 1.01647 -5.328985) (xy 1.016 -5.33908) (xy 1.016 -8.533384) (xy 1.016484 -8.543476)
			(xy 1.024338 -8.562074) (xy 1.03124 -8.569452) (xy 1.052367 -8.591119) (xy 1.088186 -8.639892) (xy 1.115859 -8.693708)
			(xy 1.134692 -8.751216) (xy 1.144214 -8.810975) (xy 1.144778 -8.841232) (xy 1.14422 -8.87149) (xy 1.134708 -8.931253)
			(xy 1.115877 -8.988764) (xy 1.088201 -9.04258) (xy 1.052374 -9.091351) (xy 1.03124 -9.113012) (xy 1.024327 -9.120384)
			(xy 1.01647 -9.138985) (xy 1.016 -9.14908) (xy 1.016 -11.811) (xy 161.213292 -11.811) (xy 161.21368 -11.772716)
			(xy 161.220219 -11.696427) (xy 161.2333 -11.620985) (xy 161.252827 -11.546948) (xy 161.265362 -11.510772)
			(xy 161.268013 -11.502335) (xy 161.268013 -11.484665) (xy 161.265362 -11.476228) (xy 161.252837 -11.44005)
			(xy 161.233329 -11.36601) (xy 161.220249 -11.290569) (xy 161.213694 -11.214283) (xy 161.213292 -11.176)
			(xy 161.213787 -11.132867) (xy 161.222145 -11.047006) (xy 161.238773 -10.962358) (xy 161.263515 -10.879715)
			(xy 161.296139 -10.799856) (xy 161.336337 -10.723528) (xy 161.383734 -10.651448) (xy 161.437884 -10.584294)
			(xy 161.498278 -10.522696) (xy 161.564351 -10.467231) (xy 161.63548 -10.41842) (xy 161.711 -10.376723)
			(xy 161.7902 -10.342529) (xy 161.872338 -10.316161) (xy 161.956642 -10.297865) (xy 161.999422 -10.292334)
			(xy 162.010643 -10.290369) (xy 162.029893 -10.278242) (xy 162.036506 -10.268966) (xy 162.058636 -10.234762)
			(xy 162.108294 -10.170172) (xy 162.163649 -10.110392) (xy 162.224237 -10.055923) (xy 162.289549 -10.007219)
			(xy 162.35904 -9.964689) (xy 162.432128 -9.928689) (xy 162.508201 -9.899521) (xy 162.586621 -9.877428)
			(xy 162.666732 -9.862596) (xy 162.747864 -9.855149) (xy 162.7886 -9.854692) (xy 162.829702 -9.855167)
			(xy 162.911557 -9.862752) (xy 162.992362 -9.877857) (xy 163.071429 -9.900353) (xy 163.148083 -9.930049)
			(xy 163.22167 -9.966691) (xy 163.291562 -10.009966) (xy 163.357163 -10.059506) (xy 163.417913 -10.114887)
			(xy 163.473294 -10.175637) (xy 163.522834 -10.241238) (xy 163.566109 -10.31113) (xy 163.602751 -10.384717)
			(xy 163.632447 -10.461371) (xy 163.654943 -10.540438) (xy 163.670048 -10.621243) (xy 163.677633 -10.703098)
			(xy 163.678108 -10.7442) (xy 163.677552 -10.788906) (xy 163.668575 -10.877868) (xy 163.650722 -10.96548)
			(xy 163.624174 -11.050861) (xy 163.589197 -11.133148) (xy 163.546144 -11.211513) (xy 163.495449 -11.285166)
			(xy 163.437624 -11.353364) (xy 163.40582 -11.384788) (xy 163.397946 -11.392408) (xy 163.390072 -11.41222)
			(xy 163.393374 -11.509502) (xy 163.402772 -11.528806) (xy 163.411154 -11.535918) (xy 163.44386 -11.564051)
			(xy 163.50427 -11.625646) (xy 163.558433 -11.692801) (xy 163.605841 -11.764883) (xy 163.646049 -11.841217)
			(xy 163.678677 -11.921084) (xy 163.703421 -12.003735) (xy 163.720046 -12.088393) (xy 163.728399 -12.174262)
			(xy 163.728908 -12.2174) (xy 163.728433 -12.258502) (xy 163.720848 -12.340357) (xy 163.705743 -12.421162)
			(xy 163.683247 -12.500229) (xy 163.653551 -12.576883) (xy 163.616909 -12.65047) (xy 163.573634 -12.720362)
			(xy 163.524094 -12.785963) (xy 163.468713 -12.846713) (xy 163.407963 -12.902094) (xy 163.342362 -12.951634)
			(xy 163.27247 -12.994909) (xy 163.198883 -13.031551) (xy 163.122229 -13.061247) (xy 163.043162 -13.083743)
			(xy 162.962357 -13.098848) (xy 162.880502 -13.106433) (xy 162.8394 -13.106908) (xy 162.79634 -13.10644)
			(xy 162.710622 -13.098119) (xy 162.626109 -13.081554) (xy 162.543592 -13.056902) (xy 162.463843 -13.024392)
			(xy 162.387608 -12.984328) (xy 162.315601 -12.937087) (xy 162.248496 -12.883108) (xy 162.18692 -12.822899)
			(xy 162.131449 -12.757022) (xy 162.10661 -12.721844) (xy 162.099372 -12.712425) (xy 162.078566 -12.701028)
			(xy 162.066732 -12.7) (xy 162.02424 -12.697737) (xy 161.939934 -12.686166) (xy 161.857118 -12.666598)
			(xy 161.776548 -12.639212) (xy 161.698961 -12.604258) (xy 161.625066 -12.562056) (xy 161.555538 -12.512991)
			(xy 161.491013 -12.457512) (xy 161.432079 -12.396125) (xy 161.379276 -12.329392) (xy 161.333087 -12.257922)
			(xy 161.293932 -12.182368) (xy 161.26217 -12.103421) (xy 161.23809 -12.021802) (xy 161.221914 -11.938257)
			(xy 161.213789 -11.853548) (xy 161.213292 -11.811) (xy 1.016 -11.811) (xy 1.016 -14.883384) (xy 1.016484 -14.893476)
			(xy 1.024338 -14.912074) (xy 1.03124 -14.919452) (xy 1.052367 -14.941119) (xy 1.088186 -14.989892)
			(xy 1.115859 -15.043708) (xy 1.134692 -15.101216) (xy 1.144214 -15.160975) (xy 1.144778 -15.191232)
			(xy 1.14422 -15.22149) (xy 1.134708 -15.281253) (xy 1.115877 -15.338764) (xy 1.088201 -15.39258)
			(xy 1.052374 -15.441351) (xy 1.03124 -15.463012) (xy 1.024327 -15.470384) (xy 1.01647 -15.488985)
			(xy 1.016 -15.49908) (xy 1.016 -16.070072) (xy 1.01651 -16.133628) (xy 1.024651 -16.260479) (xy 1.040895 -16.386548)
			(xy 1.065177 -16.511319) (xy 1.097396 -16.63428) (xy 1.13742 -16.754926) (xy 1.185085 -16.872762)
			(xy 1.240196 -16.987306) (xy 1.302526 -17.098087) (xy 1.37182 -17.20465) (xy 1.447793 -17.306559)
			(xy 1.530134 -17.403396) (xy 1.618505 -17.494763) (xy 1.712544 -17.580285) (xy 1.811864 -17.659613)
			(xy 1.916059 -17.732419) (xy 2.024701 -17.798407) (xy 2.137345 -17.857304) (xy 2.253527 -17.90887)
			(xy 2.372772 -17.952892) (xy 2.494591 -17.989191) (xy 2.618483 -18.017617) (xy 2.743942 -18.038054)
			(xy 2.870451 -18.050418) (xy 2.933954 -18.05305) (xy 2.944435 -18.052797) (xy 2.963841 -18.044921)
			(xy 2.971546 -18.03781) (xy 2.993199 -18.016773) (xy 3.041911 -17.981118) (xy 3.095629 -17.953576)
			(xy 3.153014 -17.934837) (xy 3.212634 -17.925366) (xy 3.242818 -17.92478) (xy 3.273121 -17.925365)
			(xy 3.332964 -17.934952) (xy 3.390538 -17.953881) (xy 3.444394 -17.981678) (xy 3.493177 -18.017641)
			(xy 3.514852 -18.038826) (xy 3.522277 -18.045777) (xy 3.541012 -18.053648) (xy 3.551174 -18.054066)
			(xy 9.600184 -18.054066) (xy 9.654303 -18.054531) (xy 9.762265 -18.062241) (xy 9.869402 -18.077633)
			(xy 9.975168 -18.100629) (xy 10.079024 -18.131112) (xy 10.180441 -18.168927) (xy 10.278901 -18.21388)
			(xy 10.373903 -18.265744) (xy 10.464964 -18.324253) (xy 10.551618 -18.389109) (xy 10.633424 -18.459983)
			(xy 10.709966 -18.536511) (xy 10.780853 -18.618306) (xy 10.845723 -18.704949) (xy 10.904248 -18.796)
			(xy 10.956127 -18.890994) (xy 11.001097 -18.989446) (xy 11.038928 -19.090857) (xy 11.069429 -19.194708)
			(xy 11.092443 -19.30047) (xy 11.107852 -19.407604) (xy 11.11558 -19.515565) (xy 11.116056 -19.569684)
			(xy 11.116056 -20.997348) (xy 276.478996 -20.997348) (xy 276.478996 -20.912652) (xy 276.487047 -20.828338)
			(xy 276.503076 -20.745172) (xy 276.526937 -20.663905) (xy 276.558416 -20.585275) (xy 276.597227 -20.509994)
			(xy 276.643017 -20.438742) (xy 276.695373 -20.372166) (xy 276.753821 -20.310868) (xy 276.817831 -20.255403)
			(xy 276.886823 -20.206274) (xy 276.960173 -20.163925) (xy 277.037216 -20.128741) (xy 277.117255 -20.101039)
			(xy 277.199564 -20.081071) (xy 277.283399 -20.069018) (xy 277.368 -20.064988) (xy 277.452601 -20.069018)
			(xy 277.536436 -20.081071) (xy 277.618745 -20.101039) (xy 277.698784 -20.128741) (xy 277.775827 -20.163925)
			(xy 277.849177 -20.206274) (xy 277.918169 -20.255403) (xy 277.982179 -20.310868) (xy 278.040627 -20.372166)
			(xy 278.092983 -20.438742) (xy 278.138773 -20.509994) (xy 278.177584 -20.585275) (xy 278.209063 -20.663905)
			(xy 278.232924 -20.745172) (xy 278.248953 -20.828338) (xy 278.257004 -20.912652) (xy 278.257508 -20.955)
			(xy 278.257004 -20.997348) (xy 278.248953 -21.081662) (xy 278.232924 -21.164828) (xy 278.209063 -21.246095)
			(xy 278.177584 -21.324725) (xy 278.138773 -21.400006) (xy 278.092983 -21.471258) (xy 278.040627 -21.537834)
			(xy 277.982179 -21.599132) (xy 277.918169 -21.654597) (xy 277.849177 -21.703726) (xy 277.775827 -21.746075)
			(xy 277.698784 -21.781259) (xy 277.618745 -21.808961) (xy 277.536436 -21.828929) (xy 277.452601 -21.840982)
			(xy 277.368 -21.845013) (xy 277.283399 -21.840982) (xy 277.199564 -21.828929) (xy 277.117255 -21.808961)
			(xy 277.037216 -21.781259) (xy 276.960173 -21.746075) (xy 276.886823 -21.703726) (xy 276.817831 -21.654597)
			(xy 276.753821 -21.599132) (xy 276.695373 -21.537834) (xy 276.643017 -21.471258) (xy 276.597227 -21.400006)
			(xy 276.558416 -21.324725) (xy 276.526937 -21.246095) (xy 276.503076 -21.164828) (xy 276.487047 -21.081662)
			(xy 276.478996 -20.997348) (xy 11.116056 -20.997348) (xy 11.116056 -25.329903) (xy 12.90965 -25.329903)
			(xy 12.913613 -25.189472) (xy 12.925487 -25.049488) (xy 12.945237 -24.910397) (xy 12.972799 -24.77264)
			(xy 13.008084 -24.636657) (xy 13.050982 -24.50288) (xy 13.101355 -24.371734) (xy 13.159043 -24.243638)
			(xy 13.223863 -24.118999) (xy 13.295608 -23.998213) (xy 13.374049 -23.881665) (xy 13.458938 -23.769726)
			(xy 13.550004 -23.662752) (xy 13.646958 -23.561083) (xy 13.74949 -23.465043) (xy 13.857275 -23.374937)
			(xy 13.969969 -23.291053) (xy 14.087214 -23.213657) (xy 14.208637 -23.142996) (xy 14.333851 -23.079294)
			(xy 14.462458 -23.022755) (xy 14.594049 -22.973557) (xy 14.728204 -22.931858) (xy 14.864498 -22.89779)
			(xy 15.002496 -22.871462) (xy 15.141758 -22.852958) (xy 15.281843 -22.842336) (xy 15.422304 -22.83963)
			(xy 15.562693 -22.844849) (xy 15.702565 -22.857976) (xy 15.841475 -22.87897) (xy 15.978979 -22.907763)
			(xy 16.114641 -22.944264) (xy 16.248029 -22.988357) (xy 16.378718 -23.039902) (xy 16.506293 -23.098734)
			(xy 16.630347 -23.164666) (xy 16.750486 -23.237489) (xy 16.866328 -23.316971) (xy 16.977503 -23.402858)
			(xy 17.083658 -23.494878) (xy 17.184455 -23.592737) (xy 17.232376 -23.644098) (xy 17.241266 -23.65375)
			(xy 17.264888 -23.661878) (xy 17.3736 -23.645368) (xy 17.393666 -23.630382) (xy 17.399 -23.618698)
			(xy 17.438143 -23.536826) (xy 17.522872 -23.376323) (xy 17.614769 -23.219815) (xy 17.713645 -23.067619)
			(xy 17.819299 -22.920048) (xy 17.931515 -22.777404) (xy 18.050063 -22.639976) (xy 18.174701 -22.508047)
			(xy 18.305175 -22.381886) (xy 18.441218 -22.261751) (xy 18.582551 -22.147887) (xy 18.728885 -22.040528)
			(xy 18.879923 -21.939892) (xy 19.035355 -21.846185) (xy 19.194863 -21.759599) (xy 19.358121 -21.68031)
			(xy 19.524796 -21.608481) (xy 19.694548 -21.544259) (xy 19.867028 -21.487775) (xy 20.041885 -21.439144)
			(xy 20.218761 -21.398465) (xy 20.397295 -21.365823) (xy 20.577122 -21.341282) (xy 20.757875 -21.324895)
			(xy 20.939183 -21.316693) (xy 21.02993 -21.316188) (xy 21.120001 -21.316693) (xy 21.299962 -21.324775)
			(xy 21.479379 -21.340923) (xy 21.657891 -21.365104) (xy 21.835139 -21.39727) (xy 22.010765 -21.437355)
			(xy 22.184415 -21.48528) (xy 22.355741 -21.540947) (xy 22.524396 -21.604244) (xy 22.690042 -21.675045)
			(xy 22.852345 -21.753206) (xy 23.010977 -21.838569) (xy 23.16562 -21.930964) (xy 23.315962 -22.030204)
			(xy 23.461701 -22.136089) (xy 23.602542 -22.248406) (xy 23.738202 -22.366929) (xy 23.868408 -22.491418)
			(xy 23.992897 -22.621624) (xy 24.11142 -22.757284) (xy 24.223737 -22.898125) (xy 24.329622 -23.043864)
			(xy 24.428862 -23.194206) (xy 24.521257 -23.348849) (xy 24.60662 -23.507481) (xy 24.684781 -23.669784)
			(xy 24.755582 -23.83543) (xy 24.818879 -24.004085) (xy 24.874546 -24.175411) (xy 24.922471 -24.349061)
			(xy 24.962556 -24.524687) (xy 24.994722 -24.701935) (xy 25.018903 -24.880447) (xy 25.035051 -25.059864)
			(xy 25.043133 -25.239825) (xy 25.043133 -25.329896) (xy 25.159471 -25.329896) (xy 25.16346 -25.188998)
			(xy 25.175414 -25.048551) (xy 25.195294 -24.909006) (xy 25.223037 -24.770809) (xy 25.258555 -24.634403)
			(xy 25.301732 -24.500224) (xy 25.352432 -24.368704) (xy 25.410492 -24.240262) (xy 25.475724 -24.115311)
			(xy 25.547922 -23.99425) (xy 25.626853 -23.877468) (xy 25.712264 -23.765339) (xy 25.803883 -23.658221)
			(xy 25.901415 -23.556458) (xy 26.004547 -23.460376) (xy 26.112951 -23.370283) (xy 26.226278 -23.286466)
			(xy 26.344165 -23.209196) (xy 26.466235 -23.138719) (xy 26.592097 -23.07526) (xy 26.721347 -23.019025)
			(xy 26.853572 -22.970191) (xy 26.988348 -22.928916) (xy 27.125243 -22.895333) (xy 27.263819 -22.869548)
			(xy 27.403632 -22.851644) (xy 27.544234 -22.841679) (xy 27.685174 -22.839684) (xy 27.826002 -22.845667)
			(xy 27.966265 -22.859607) (xy 28.105515 -22.88146) (xy 28.243306 -22.911156) (xy 28.379196 -22.9486)
			(xy 28.51275 -22.993672) (xy 28.64354 -23.046228) (xy 28.73385 -23.0886) (xy 271.702788 -23.0886)
			(xy 271.706818 -23.003999) (xy 271.718871 -22.920164) (xy 271.738839 -22.837855) (xy 271.766541 -22.757816)
			(xy 271.801725 -22.680773) (xy 271.844074 -22.607423) (xy 271.893203 -22.538431) (xy 271.948668 -22.474421)
			(xy 272.009966 -22.415973) (xy 272.076542 -22.363617) (xy 272.147794 -22.317827) (xy 272.223075 -22.279016)
			(xy 272.301705 -22.247537) (xy 272.382972 -22.223676) (xy 272.466138 -22.207647) (xy 272.550452 -22.199596)
			(xy 272.5928 -22.199092) (xy 272.635115 -22.199595) (xy 272.719363 -22.207626) (xy 272.802466 -22.223624)
			(xy 272.883675 -22.247445) (xy 272.962252 -22.278872) (xy 273.037489 -22.317623) (xy 273.073368 -22.340062)
			(xy 273.081757 -22.344945) (xy 273.1008 -22.348616) (xy 273.119843 -22.344945) (xy 273.128232 -22.340062)
			(xy 273.164106 -22.317616) (xy 273.239347 -22.278873) (xy 273.317926 -22.247449) (xy 273.399135 -22.22363)
			(xy 273.482238 -22.20763) (xy 273.566485 -22.199594) (xy 273.6088 -22.199092) (xy 273.651148 -22.199596)
			(xy 273.735462 -22.207647) (xy 273.818628 -22.223676) (xy 273.899895 -22.247537) (xy 273.978525 -22.279016)
			(xy 274.053806 -22.317827) (xy 274.125058 -22.363617) (xy 274.191634 -22.415973) (xy 274.252932 -22.474421)
			(xy 274.308397 -22.538431) (xy 274.357526 -22.607423) (xy 274.399875 -22.680773) (xy 274.435059 -22.757816)
			(xy 274.462761 -22.837855) (xy 274.482729 -22.920164) (xy 274.494782 -23.003999) (xy 274.498813 -23.0886)
			(xy 274.494782 -23.173201) (xy 274.482729 -23.257036) (xy 274.462761 -23.339345) (xy 274.435059 -23.419384)
			(xy 274.399875 -23.496427) (xy 274.357526 -23.569777) (xy 274.308397 -23.638769) (xy 274.252932 -23.702779)
			(xy 274.191634 -23.761227) (xy 274.125058 -23.813583) (xy 274.053806 -23.859373) (xy 273.978525 -23.898184)
			(xy 273.899895 -23.929663) (xy 273.818628 -23.953524) (xy 273.735462 -23.969553) (xy 273.651148 -23.977604)
			(xy 273.6088 -23.978108) (xy 273.566485 -23.977605) (xy 273.482237 -23.969574) (xy 273.399134 -23.953576)
			(xy 273.317925 -23.929755) (xy 273.239348 -23.898328) (xy 273.164111 -23.859577) (xy 273.128232 -23.837138)
			(xy 273.119843 -23.832255) (xy 273.1008 -23.828584) (xy 273.081757 -23.832255) (xy 273.073368 -23.837138)
			(xy 273.037494 -23.859584) (xy 272.962253 -23.898327) (xy 272.883674 -23.929751) (xy 272.802465 -23.95357)
			(xy 272.719362 -23.96957) (xy 272.635115 -23.977606) (xy 272.5928 -23.978108) (xy 272.550452 -23.977604)
			(xy 272.466138 -23.969553) (xy 272.382972 -23.953524) (xy 272.301705 -23.929663) (xy 272.223075 -23.898184)
			(xy 272.147794 -23.859373) (xy 272.076542 -23.813583) (xy 272.009966 -23.761227) (xy 271.948668 -23.702779)
			(xy 271.893203 -23.638769) (xy 271.844074 -23.569777) (xy 271.801725 -23.496427) (xy 271.766541 -23.419384)
			(xy 271.738839 -23.339345) (xy 271.718871 -23.257036) (xy 271.706818 -23.173201) (xy 271.702788 -23.0886)
			(xy 28.73385 -23.0886) (xy 28.771147 -23.106099) (xy 28.895163 -23.173094) (xy 29.015189 -23.246997)
			(xy 29.130843 -23.327573) (xy 29.241752 -23.414562) (xy 29.347563 -23.507687) (xy 29.447935 -23.606649)
			(xy 29.542548 -23.711131) (xy 29.631099 -23.820799) (xy 29.713303 -23.935301) (xy 29.788897 -24.05427)
			(xy 29.85764 -24.177325) (xy 29.919311 -24.304072) (xy 29.973712 -24.434105) (xy 30.02067 -24.567008)
			(xy 30.060033 -24.702354) (xy 30.091676 -24.839711) (xy 30.115498 -24.978638) (xy 30.131421 -25.11869)
			(xy 30.139396 -25.259419) (xy 30.139894 -25.329896) (xy 30.139396 -25.400373) (xy 30.131421 -25.541102)
			(xy 30.125683 -25.59157) (xy 42.354235 -25.59157) (xy 42.354235 -25.46243) (xy 42.362185 -25.333535)
			(xy 42.378055 -25.205375) (xy 42.401784 -25.078434) (xy 42.433283 -24.953195) (xy 42.472432 -24.830132)
			(xy 42.519083 -24.709713) (xy 42.573058 -24.592394) (xy 42.634153 -24.47862) (xy 42.702136 -24.368823)
			(xy 42.77675 -24.26342) (xy 42.857711 -24.16281) (xy 42.944711 -24.067375) (xy 43.037422 -23.977476)
			(xy 43.135492 -23.893455) (xy 43.238547 -23.815631) (xy 43.346198 -23.744299) (xy 43.458037 -23.679729)
			(xy 43.573638 -23.622167) (xy 43.692563 -23.57183) (xy 43.814362 -23.52891) (xy 43.938572 -23.493569)
			(xy 44.064721 -23.465942) (xy 44.192333 -23.446133) (xy 44.320922 -23.434217) (xy 44.45 -23.430241)
			(xy 44.579078 -23.434217) (xy 44.707667 -23.446133) (xy 44.835279 -23.465942) (xy 44.961428 -23.493569)
			(xy 45.085638 -23.52891) (xy 45.207437 -23.57183) (xy 45.326362 -23.622167) (xy 45.441963 -23.679729)
			(xy 45.553802 -23.744299) (xy 45.661453 -23.815631) (xy 45.764508 -23.893455) (xy 45.862578 -23.977476)
			(xy 45.955289 -24.067375) (xy 46.042289 -24.16281) (xy 46.12325 -24.26342) (xy 46.197864 -24.368823)
			(xy 46.265847 -24.47862) (xy 46.326942 -24.592394) (xy 46.380917 -24.709713) (xy 46.427568 -24.830132)
			(xy 46.466717 -24.953195) (xy 46.498216 -25.078434) (xy 46.521945 -25.205375) (xy 46.537815 -25.333535)
			(xy 46.545765 -25.46243) (xy 46.546262 -25.527) (xy 46.545765 -25.59157) (xy 46.537815 -25.720465)
			(xy 46.521945 -25.848625) (xy 46.498216 -25.975566) (xy 46.466717 -26.100805) (xy 46.427568 -26.223868)
			(xy 46.380917 -26.344287) (xy 46.326942 -26.461606) (xy 46.265847 -26.57538) (xy 46.197864 -26.685177)
			(xy 46.12325 -26.79058) (xy 46.042289 -26.89119) (xy 45.955289 -26.986625) (xy 45.862578 -27.076524)
			(xy 45.764508 -27.160545) (xy 45.661453 -27.238369) (xy 45.553802 -27.309701) (xy 45.441963 -27.374271)
			(xy 45.326362 -27.431833) (xy 45.207437 -27.48217) (xy 45.085638 -27.52509) (xy 44.961428 -27.560431)
			(xy 44.835279 -27.588058) (xy 44.707667 -27.607867) (xy 44.579078 -27.619783) (xy 44.45 -27.62376)
			(xy 44.320922 -27.619783) (xy 44.192333 -27.607867) (xy 44.064721 -27.588058) (xy 43.938572 -27.560431)
			(xy 43.814362 -27.52509) (xy 43.692563 -27.48217) (xy 43.573638 -27.431833) (xy 43.458037 -27.374271)
			(xy 43.346198 -27.309701) (xy 43.238547 -27.238369) (xy 43.135492 -27.160545) (xy 43.037422 -27.076524)
			(xy 42.944711 -26.986625) (xy 42.857711 -26.89119) (xy 42.77675 -26.79058) (xy 42.702136 -26.685177)
			(xy 42.634153 -26.57538) (xy 42.573058 -26.461606) (xy 42.519083 -26.344287) (xy 42.472432 -26.223868)
			(xy 42.433283 -26.100805) (xy 42.401784 -25.975566) (xy 42.378055 -25.848625) (xy 42.362185 -25.720465)
			(xy 42.354235 -25.59157) (xy 30.125683 -25.59157) (xy 30.115498 -25.681154) (xy 30.091676 -25.820081)
			(xy 30.060033 -25.957438) (xy 30.02067 -26.092784) (xy 29.973712 -26.225687) (xy 29.919311 -26.35572)
			(xy 29.85764 -26.482467) (xy 29.788897 -26.605522) (xy 29.713303 -26.724491) (xy 29.631099 -26.838993)
			(xy 29.542548 -26.948661) (xy 29.447935 -27.053143) (xy 29.347563 -27.152105) (xy 29.241752 -27.24523)
			(xy 29.130843 -27.332219) (xy 29.015189 -27.412795) (xy 28.895163 -27.486698) (xy 28.771147 -27.553693)
			(xy 28.64354 -27.613564) (xy 28.51275 -27.66612) (xy 28.379196 -27.711192) (xy 28.243306 -27.748636)
			(xy 28.105515 -27.778332) (xy 27.966265 -27.800185) (xy 27.826002 -27.814125) (xy 27.685174 -27.820108)
			(xy 27.544234 -27.818113) (xy 27.403632 -27.808148) (xy 27.263819 -27.790244) (xy 27.125243 -27.764459)
			(xy 26.988348 -27.730876) (xy 26.853572 -27.689601) (xy 26.721347 -27.640767) (xy 26.592097 -27.584532)
			(xy 26.466235 -27.521073) (xy 26.344165 -27.450596) (xy 26.226278 -27.373326) (xy 26.112951 -27.289509)
			(xy 26.004547 -27.199416) (xy 25.901415 -27.103334) (xy 25.803883 -27.001571) (xy 25.712264 -26.894453)
			(xy 25.626853 -26.782324) (xy 25.547922 -26.665542) (xy 25.475724 -26.544481) (xy 25.410492 -26.41953)
			(xy 25.352432 -26.291088) (xy 25.301732 -26.159568) (xy 25.258555 -26.025389) (xy 25.223037 -25.888983)
			(xy 25.195294 -25.750786) (xy 25.175414 -25.611241) (xy 25.16346 -25.470794) (xy 25.159471 -25.329896)
			(xy 25.043133 -25.329896) (xy 25.043133 -25.419967) (xy 25.035051 -25.599928) (xy 25.018903 -25.779345)
			(xy 24.994722 -25.957857) (xy 24.962556 -26.135105) (xy 24.922471 -26.310731) (xy 24.874546 -26.484381)
			(xy 24.818879 -26.655707) (xy 24.755582 -26.824362) (xy 24.684781 -26.990008) (xy 24.60662 -27.152311)
			(xy 24.521257 -27.310943) (xy 24.428862 -27.465586) (xy 24.329622 -27.615928) (xy 24.223737 -27.761667)
			(xy 24.11142 -27.902508) (xy 23.992897 -28.038168) (xy 23.868408 -28.168374) (xy 23.738202 -28.292863)
			(xy 23.602542 -28.411386) (xy 23.461701 -28.523703) (xy 23.315962 -28.629588) (xy 23.16562 -28.728828)
			(xy 23.010977 -28.821223) (xy 22.852345 -28.906586) (xy 22.690042 -28.984747) (xy 22.524396 -29.055548)
			(xy 22.355741 -29.118845) (xy 22.184415 -29.174512) (xy 22.010765 -29.222437) (xy 21.835139 -29.262522)
			(xy 21.657891 -29.294688) (xy 21.479379 -29.318869) (xy 21.299962 -29.335017) (xy 21.120001 -29.343099)
			(xy 21.02993 -29.343604) (xy 20.939184 -29.343097) (xy 20.757877 -29.334889) (xy 20.577127 -29.318497)
			(xy 20.397302 -29.293952) (xy 20.21877 -29.261305) (xy 20.041895 -29.220623) (xy 19.867041 -29.171989)
			(xy 19.694562 -29.115502) (xy 19.524813 -29.051278) (xy 19.35814 -28.979448) (xy 19.194884 -28.900158)
			(xy 19.035377 -28.813572) (xy 18.879947 -28.719865) (xy 18.728911 -28.61923) (xy 18.582577 -28.511871)
			(xy 18.441244 -28.398009) (xy 18.305202 -28.277876) (xy 18.174728 -28.151717) (xy 18.050089 -28.01979)
			(xy 17.93154 -27.882366) (xy 17.819322 -27.739724) (xy 17.713666 -27.592156) (xy 17.614787 -27.439964)
			(xy 17.522887 -27.283459) (xy 17.438154 -27.12296) (xy 17.399 -27.041094) (xy 17.393666 -27.02941)
			(xy 17.3736 -27.014424) (xy 17.264888 -26.997914) (xy 17.241266 -27.006042) (xy 17.232376 -27.015694)
			(xy 17.184459 -27.067059) (xy 17.083662 -27.164918) (xy 16.977507 -27.256938) (xy 16.866332 -27.342826)
			(xy 16.750491 -27.422308) (xy 16.630352 -27.495131) (xy 16.506298 -27.561063) (xy 16.378724 -27.619896)
			(xy 16.248035 -27.671441) (xy 16.114647 -27.715534) (xy 15.978985 -27.752036) (xy 15.841481 -27.780829)
			(xy 15.702571 -27.801823) (xy 15.562699 -27.814951) (xy 15.42231 -27.82017) (xy 15.281849 -27.817465)
			(xy 15.141764 -27.806843) (xy 15.002501 -27.788339) (xy 14.864504 -27.762011) (xy 14.72821 -27.727944)
			(xy 14.594054 -27.686245) (xy 14.462464 -27.637048) (xy 14.333856 -27.580508) (xy 14.208642 -27.516807)
			(xy 14.087219 -27.446146) (xy 13.969974 -27.36875) (xy 13.857279 -27.284866) (xy 13.749494 -27.194761)
			(xy 13.646962 -27.098721) (xy 13.550008 -26.997053) (xy 13.458942 -26.890079) (xy 13.374053 -26.77814)
			(xy 13.295611 -26.661592) (xy 13.223866 -26.540806) (xy 13.159046 -26.416167) (xy 13.101357 -26.288071)
			(xy 13.050984 -26.156926) (xy 13.008086 -26.023149) (xy 12.9728 -25.887166) (xy 12.945238 -25.749409)
			(xy 12.925488 -25.610318) (xy 12.913613 -25.470334) (xy 12.90965 -25.329903) (xy 11.116056 -25.329903)
			(xy 11.116056 -31.070296) (xy 11.115549 -31.124408) (xy 11.107784 -31.232354) (xy 11.09234 -31.339471)
			(xy 11.069298 -31.445214) (xy 11.038775 -31.549045) (xy 11.000925 -31.650435) (xy 10.955943 -31.748869)
			(xy 10.904055 -31.843844) (xy 10.845528 -31.934878) (xy 10.780658 -32.021506) (xy 10.709777 -32.103289)
			(xy 10.633244 -32.179809) (xy 10.55145 -32.250677) (xy 10.464811 -32.315532) (xy 10.373767 -32.374044)
			(xy 10.278783 -32.425915) (xy 10.180343 -32.470882) (xy 10.078946 -32.508715) (xy 9.97511 -32.539221)
			(xy 9.869363 -32.562245) (xy 9.762243 -32.577671) (xy 9.654296 -32.585419) (xy 9.600184 -32.585914)
			(xy 7.23519 -32.585914) (xy 7.225032 -32.586357) (xy 7.206294 -32.59421) (xy 7.198868 -32.601154)
			(xy 7.179211 -32.620456) (xy 7.135338 -32.653776) (xy 7.087129 -32.680439) (xy 7.035586 -32.69989)
			(xy 6.981782 -32.711725) (xy 6.926834 -32.715697) (xy 6.871886 -32.711725) (xy 6.818082 -32.69989)
			(xy 6.766539 -32.680439) (xy 6.71833 -32.653776) (xy 6.674457 -32.620456) (xy 6.6548 -32.601154)
			(xy 6.647377 -32.594201) (xy 6.62864 -32.586336) (xy 6.618478 -32.585914) (xy 2.999994 -32.585914)
			(xy 2.941974 -32.586335) (xy 2.826132 -32.593118) (xy 2.710885 -32.606662) (xy 2.596627 -32.626918)
			(xy 2.483748 -32.653819) (xy 2.372634 -32.687272) (xy 2.318004 -32.706818) (xy 2.307685 -32.711166)
			(xy 2.29187 -32.726979) (xy 2.287524 -32.737298) (xy 2.27703 -32.764482) (xy 2.248986 -32.815559)
			(xy 2.213504 -32.861779) (xy 2.171408 -32.902068) (xy 2.123677 -32.935489) (xy 2.07142 -32.961267)
			(xy 2.015852 -32.978801) (xy 1.958264 -32.987684) (xy 1.92913 -32.98825) (xy 1.907867 -32.987973)
			(xy 1.865604 -32.983261) (xy 1.844802 -32.978852) (xy 1.83385 -32.976902) (xy 1.812117 -32.981524)
			(xy 1.802892 -32.987742) (xy 1.754489 -33.024952) (xy 1.661833 -33.104473) (xy 1.574243 -33.189542)
			(xy 1.492051 -33.279838) (xy 1.415567 -33.375017) (xy 1.345082 -33.474719) (xy 1.280862 -33.578569)
			(xy 1.223151 -33.686171) (xy 1.172167 -33.797118) (xy 1.128102 -33.910992) (xy 1.091125 -34.027359)
			(xy 1.061374 -34.145781) (xy 1.038963 -34.265808) (xy 1.023976 -34.386987) (xy 1.01647 -34.508857)
			(xy 1.016 -34.569908) (xy 1.016 -36.582604) (xy 1.016488 -36.592694) (xy 1.024347 -36.611287) (xy 1.03124 -36.618672)
			(xy 1.052367 -36.640339) (xy 1.088186 -36.689112) (xy 1.115859 -36.742928) (xy 1.134692 -36.800436)
			(xy 1.144214 -36.860195) (xy 1.144778 -36.890452) (xy 1.14422 -36.92071) (xy 1.134708 -36.980473)
			(xy 1.115877 -37.037984) (xy 1.088201 -37.0918) (xy 1.052374 -37.140571) (xy 1.03124 -37.162232)
			(xy 1.02433 -37.169605) (xy 1.01648 -37.188206) (xy 1.016 -37.1983) (xy 1.016 -41.662604) (xy 1.016488 -41.672694)
			(xy 1.024347 -41.691287) (xy 1.03124 -41.698672) (xy 1.052367 -41.720339) (xy 1.088186 -41.769112)
			(xy 1.115859 -41.822928) (xy 1.134692 -41.880436) (xy 1.144214 -41.940195) (xy 1.144778 -41.970452)
			(xy 1.14422 -42.00071) (xy 1.134708 -42.060473) (xy 1.115877 -42.117984) (xy 1.088201 -42.1718) (xy 1.052374 -42.220571)
			(xy 1.03124 -42.242232) (xy 1.02433 -42.249605) (xy 1.01648 -42.268206) (xy 1.016 -42.2783) (xy 1.016 -46.742604)
			(xy 1.016488 -46.752694) (xy 1.024347 -46.771287) (xy 1.03124 -46.778672) (xy 1.052367 -46.800339)
			(xy 1.088186 -46.849112) (xy 1.115859 -46.902928) (xy 1.134692 -46.960436) (xy 1.144214 -47.020195)
			(xy 1.144778 -47.050452) (xy 1.14422 -47.08071) (xy 1.134708 -47.140473) (xy 1.115877 -47.197984)
			(xy 1.088201 -47.2518) (xy 1.052374 -47.300571) (xy 1.03124 -47.322232) (xy 1.02433 -47.329605) (xy 1.01648 -47.348206)
			(xy 1.016 -47.3583) (xy 1.016 -51.822604) (xy 1.016488 -51.832694) (xy 1.024347 -51.851287) (xy 1.03124 -51.858672)
			(xy 1.052367 -51.880339) (xy 1.088186 -51.929112) (xy 1.115859 -51.982928) (xy 1.134692 -52.040436)
			(xy 1.144214 -52.100195) (xy 1.144778 -52.130452) (xy 1.14422 -52.16071) (xy 1.134708 -52.220473)
			(xy 1.115877 -52.277984) (xy 1.088201 -52.3318) (xy 1.052374 -52.380571) (xy 1.03124 -52.402232)
			(xy 1.02433 -52.409605) (xy 1.01648 -52.428206) (xy 1.016 -52.4383) (xy 1.016 -54.399942) (xy 3.446023 -54.399942)
			(xy 3.450044 -54.28608) (xy 3.462086 -54.172786) (xy 3.482091 -54.060624) (xy 3.509957 -53.950152)
			(xy 3.545546 -53.84192) (xy 3.588681 -53.736469) (xy 3.639147 -53.634323) (xy 3.696693 -53.535992)
			(xy 3.761032 -53.441964) (xy 3.831843 -53.352709) (xy 3.908773 -53.268672) (xy 3.99144 -53.19027)
			(xy 4.079431 -53.117895) (xy 4.172308 -53.051907) (xy 4.269609 -52.992635) (xy 4.370848 -52.940374)
			(xy 4.475522 -52.895384) (xy 4.583108 -52.85789) (xy 4.693071 -52.828079) (xy 4.804864 -52.806098)
			(xy 4.917928 -52.792058) (xy 5.0317 -52.786028) (xy 5.145615 -52.788039) (xy 5.259104 -52.79808)
			(xy 5.371603 -52.816102) (xy 5.482549 -52.842014) (xy 5.591392 -52.875688) (xy 5.697588 -52.916955)
			(xy 5.800608 -52.965611) (xy 5.89994 -53.021412) (xy 5.995089 -53.084081) (xy 6.085579 -53.153306)
			(xy 6.170961 -53.228741) (xy 6.25081 -53.310012) (xy 6.324727 -53.396712) (xy 6.392343 -53.48841)
			(xy 6.453324 -53.584649) (xy 6.507363 -53.684951) (xy 6.554193 -53.788814) (xy 6.59358 -53.895722)
			(xy 6.625327 -54.005142) (xy 6.649277 -54.116528) (xy 6.665311 -54.229327) (xy 6.673347 -54.342976)
			(xy 6.67385 -54.399942) (xy 6.673347 -54.456908) (xy 6.665311 -54.570557) (xy 6.649277 -54.683356)
			(xy 6.625327 -54.794742) (xy 6.59358 -54.904162) (xy 6.554193 -55.01107) (xy 6.507363 -55.114933)
			(xy 6.453324 -55.215235) (xy 6.392343 -55.311474) (xy 6.324727 -55.403172) (xy 6.25081 -55.489872)
			(xy 6.170961 -55.571143) (xy 6.085579 -55.646578) (xy 5.995089 -55.715803) (xy 5.89994 -55.778472)
			(xy 5.800608 -55.834273) (xy 5.697588 -55.882929) (xy 5.591392 -55.924196) (xy 5.482549 -55.95787)
			(xy 5.371603 -55.983782) (xy 5.259104 -56.001804) (xy 5.145615 -56.011845) (xy 5.0317 -56.013856)
			(xy 4.917928 -56.007826) (xy 4.804864 -55.993786) (xy 4.693071 -55.971805) (xy 4.583108 -55.941994)
			(xy 4.475522 -55.9045) (xy 4.370848 -55.85951) (xy 4.269609 -55.807249) (xy 4.172308 -55.747977)
			(xy 4.079431 -55.681989) (xy 3.99144 -55.609614) (xy 3.908773 -55.531212) (xy 3.831843 -55.447175)
			(xy 3.761032 -55.35792) (xy 3.696693 -55.263892) (xy 3.639147 -55.165561) (xy 3.588681 -55.063415)
			(xy 3.545546 -54.957964) (xy 3.509957 -54.849732) (xy 3.482091 -54.73926) (xy 3.462086 -54.627098)
			(xy 3.450044 -54.513804) (xy 3.446023 -54.399942) (xy 1.016 -54.399942) (xy 1.016 -56.902604) (xy 1.016488 -56.912694)
			(xy 1.024347 -56.931287) (xy 1.03124 -56.938672) (xy 1.052367 -56.960339) (xy 1.088186 -57.009112)
			(xy 1.115859 -57.062928) (xy 1.134692 -57.120436) (xy 1.144214 -57.180195) (xy 1.144778 -57.210452)
			(xy 1.14422 -57.24071) (xy 1.134708 -57.300473) (xy 1.115877 -57.357984) (xy 1.088201 -57.4118) (xy 1.052374 -57.460571)
			(xy 1.03124 -57.482232) (xy 1.02433 -57.489605) (xy 1.01648 -57.508206) (xy 1.016 -57.5183) (xy 1.016 -61.982604)
			(xy 1.016488 -61.992694) (xy 1.024347 -62.011287) (xy 1.03124 -62.018672) (xy 1.052367 -62.040339)
			(xy 1.088186 -62.089112) (xy 1.115859 -62.142928) (xy 1.134692 -62.200436) (xy 1.144214 -62.260195)
			(xy 1.144778 -62.290452) (xy 1.14422 -62.32071) (xy 1.134708 -62.380473) (xy 1.115877 -62.437984)
			(xy 1.088201 -62.4918) (xy 1.052374 -62.540571) (xy 1.03124 -62.562232) (xy 1.02433 -62.569605) (xy 1.01648 -62.588206)
			(xy 1.016 -62.5983) (xy 1.016 -67.062604) (xy 1.016488 -67.072694) (xy 1.024347 -67.091287) (xy 1.03124 -67.098672)
			(xy 1.052367 -67.120339) (xy 1.088186 -67.169112) (xy 1.115859 -67.222928) (xy 1.134692 -67.280436)
			(xy 1.144214 -67.340195) (xy 1.144778 -67.370452) (xy 1.14422 -67.40071) (xy 1.134708 -67.460473)
			(xy 1.115877 -67.517984) (xy 1.088201 -67.5718) (xy 1.052374 -67.620571) (xy 1.03124 -67.642232)
			(xy 1.02433 -67.649605) (xy 1.01648 -67.668206) (xy 1.016 -67.6783) (xy 1.016 -72.142604) (xy 1.016488 -72.152694)
			(xy 1.024347 -72.171287) (xy 1.03124 -72.178672) (xy 1.052367 -72.200339) (xy 1.088186 -72.249112)
			(xy 1.115859 -72.302928) (xy 1.134692 -72.360436) (xy 1.144214 -72.420195) (xy 1.144778 -72.450452)
			(xy 1.14422 -72.48071) (xy 1.134708 -72.540473) (xy 1.115877 -72.597984) (xy 1.088201 -72.6518) (xy 1.052374 -72.700571)
			(xy 1.03124 -72.722232) (xy 1.02433 -72.729605) (xy 1.01648 -72.748206) (xy 1.016 -72.7583) (xy 1.016 -77.222604)
			(xy 1.016488 -77.232694) (xy 1.024347 -77.251287) (xy 1.03124 -77.258672) (xy 1.052367 -77.280339)
			(xy 1.088186 -77.329112) (xy 1.115859 -77.382928) (xy 1.134692 -77.440436) (xy 1.144214 -77.500195)
			(xy 1.144778 -77.530452) (xy 1.14422 -77.56071) (xy 1.134708 -77.620473) (xy 1.115877 -77.677984)
			(xy 1.088201 -77.7318) (xy 1.052374 -77.780571) (xy 1.03124 -77.802232) (xy 1.02433 -77.809605) (xy 1.01648 -77.828206)
			(xy 1.016 -77.8383) (xy 1.016 -82.302604) (xy 1.016488 -82.312694) (xy 1.024347 -82.331287) (xy 1.03124 -82.338672)
			(xy 1.052367 -82.360339) (xy 1.088186 -82.409112) (xy 1.115859 -82.462928) (xy 1.134692 -82.520436)
			(xy 1.144214 -82.580195) (xy 1.144778 -82.610452) (xy 1.14422 -82.64071) (xy 1.134708 -82.700473)
			(xy 1.115877 -82.757984) (xy 1.088201 -82.8118) (xy 1.052374 -82.860571) (xy 1.03124 -82.882232)
			(xy 1.02433 -82.889605) (xy 1.01648 -82.908206) (xy 1.016 -82.9183) (xy 1.016 -83.749896) (xy 11.118856 -83.749896)
			(xy 11.122874 -83.648894) (xy 11.134905 -83.54853) (xy 11.154871 -83.44944) (xy 11.182647 -83.352249)
			(xy 11.218058 -83.257572) (xy 11.260878 -83.166008) (xy 11.310838 -83.078135) (xy 11.367621 -82.994509)
			(xy 11.430869 -82.91566) (xy 11.500181 -82.842084) (xy 11.57512 -82.774248) (xy 11.655212 -82.71258)
			(xy 11.73995 -82.657471) (xy 11.828799 -82.609268) (xy 11.921196 -82.568277) (xy 12.016559 -82.534756)
			(xy 12.114283 -82.508918) (xy 12.21375 -82.490925) (xy 12.314333 -82.480893) (xy 12.415396 -82.478883)
			(xy 12.516298 -82.484909) (xy 12.616402 -82.498932) (xy 12.715076 -82.520865) (xy 12.811696 -82.550568)
			(xy 12.90565 -82.587854) (xy 12.996345 -82.632486) (xy 13.083207 -82.684183) (xy 13.165687 -82.742618)
			(xy 13.243264 -82.807421) (xy 13.315446 -82.878183) (xy 13.381779 -82.954456) (xy 13.441842 -83.035758)
			(xy 13.495256 -83.121575) (xy 13.541683 -83.211364) (xy 13.580829 -83.304558) (xy 13.612447 -83.400568)
			(xy 13.636337 -83.498786) (xy 13.652348 -83.598592) (xy 13.660379 -83.699355) (xy 13.660882 -83.749896)
			(xy 13.660379 -83.800437) (xy 13.652348 -83.9012) (xy 13.636337 -84.001006) (xy 13.612447 -84.099224)
			(xy 13.580829 -84.195234) (xy 13.541683 -84.288428) (xy 13.495256 -84.378217) (xy 13.441842 -84.464034)
			(xy 13.381779 -84.545336) (xy 13.315446 -84.621609) (xy 13.243264 -84.692371) (xy 13.165687 -84.757174)
			(xy 13.083207 -84.815609) (xy 12.996345 -84.867306) (xy 12.90565 -84.911938) (xy 12.811696 -84.949224)
			(xy 12.715076 -84.978927) (xy 12.616402 -85.00086) (xy 12.516298 -85.014883) (xy 12.415396 -85.020909)
			(xy 12.314333 -85.018899) (xy 12.21375 -85.008867) (xy 12.114283 -84.990874) (xy 12.016559 -84.965036)
			(xy 11.921196 -84.931515) (xy 11.828799 -84.890524) (xy 11.73995 -84.842321) (xy 11.655212 -84.787212)
			(xy 11.57512 -84.725544) (xy 11.500181 -84.657708) (xy 11.430869 -84.584132) (xy 11.367621 -84.505283)
			(xy 11.310838 -84.421657) (xy 11.260878 -84.333784) (xy 11.218058 -84.24222) (xy 11.182647 -84.147543)
			(xy 11.154871 -84.050352) (xy 11.134905 -83.951262) (xy 11.122874 -83.850898) (xy 11.118856 -83.749896)
			(xy 1.016 -83.749896) (xy 1.016 -87.382604) (xy 1.016488 -87.392694) (xy 1.024347 -87.411287) (xy 1.03124 -87.418672)
			(xy 1.052367 -87.440339) (xy 1.088186 -87.489112) (xy 1.115859 -87.542928) (xy 1.121416 -87.559896)
			(xy 9.849612 -87.559896) (xy 9.850066 -87.509996) (xy 9.857896 -87.410503) (xy 9.873509 -87.311931)
			(xy 9.896807 -87.214889) (xy 9.927648 -87.119973) (xy 9.96584 -87.02777) (xy 10.011149 -86.938847)
			(xy 10.063296 -86.853754) (xy 10.121957 -86.773014) (xy 10.186773 -86.697126) (xy 10.257344 -86.626557)
			(xy 10.333233 -86.561743) (xy 10.413974 -86.503082) (xy 10.499068 -86.450938) (xy 10.587992 -86.40563)
			(xy 10.680196 -86.36744) (xy 10.775112 -86.336601) (xy 10.872155 -86.313304) (xy 10.970727 -86.297693)
			(xy 11.07022 -86.289865) (xy 11.12012 -86.289388) (xy 11.17137 -86.289896) (xy 11.273537 -86.298164)
			(xy 11.374705 -86.314636) (xy 11.474217 -86.339204) (xy 11.571427 -86.371709) (xy 11.665703 -86.411939)
			(xy 11.756431 -86.459633) (xy 11.843023 -86.514481) (xy 11.924914 -86.576126) (xy 12.001573 -86.644168)
			(xy 12.072502 -86.718164) (xy 12.13724 -86.797634) (xy 12.195365 -86.88206) (xy 12.2465 -86.970895)
			(xy 12.290312 -87.06356) (xy 12.326518 -87.159453) (xy 12.35488 -87.257951) (xy 12.375216 -87.358414)
			(xy 12.387393 -87.460189) (xy 12.389866 -87.511382) (xy 12.390707 -87.520861) (xy 12.398315 -87.538282)
			(xy 12.411745 -87.551735) (xy 12.429153 -87.559373) (xy 12.438634 -87.56015) (xy 12.489829 -87.562618)
			(xy 12.59161 -87.574781) (xy 12.692079 -87.595106) (xy 12.790584 -87.623459) (xy 12.886484 -87.659657)
			(xy 12.979156 -87.703465) (xy 13.067997 -87.754597) (xy 13.152429 -87.812721) (xy 13.231903 -87.877459)
			(xy 13.305903 -87.94839) (xy 13.373947 -88.025052) (xy 13.435592 -88.106949) (xy 13.490439 -88.193546)
			(xy 13.53813 -88.28428) (xy 13.578355 -88.378562) (xy 13.610852 -88.475779) (xy 13.635411 -88.575298)
			(xy 13.651871 -88.676472) (xy 13.660126 -88.778644) (xy 13.660628 -88.829896) (xy 13.660114 -88.879795)
			(xy 13.652285 -88.979284) (xy 13.636673 -89.077853) (xy 13.613377 -89.174893) (xy 13.582538 -89.269806)
			(xy 13.544348 -89.362006) (xy 13.499042 -89.450927) (xy 13.446898 -89.536018) (xy 13.38824 -89.616756)
			(xy 13.323427 -89.692643) (xy 13.252861 -89.763211) (xy 13.176975 -89.828025) (xy 13.096238 -89.886685)
			(xy 13.011148 -89.93883) (xy 12.922228 -89.984138) (xy 12.830028 -90.02233) (xy 12.735116 -90.05317)
			(xy 12.638076 -90.076469) (xy 12.539508 -90.092082) (xy 12.440019 -90.099913) (xy 12.39012 -90.100404)
			(xy 12.33887 -90.099894) (xy 12.236704 -90.091626) (xy 12.135535 -90.075154) (xy 12.036023 -90.050586)
			(xy 11.938813 -90.018081) (xy 11.844537 -89.977851) (xy 11.753809 -89.930157) (xy 11.667218 -89.875309)
			(xy 11.585327 -89.813664) (xy 11.508667 -89.745623) (xy 11.437738 -89.671626) (xy 11.373001 -89.592157)
			(xy 11.314876 -89.507731) (xy 11.263741 -89.418896) (xy 11.219928 -89.326232) (xy 11.183723 -89.230338)
			(xy 11.15536 -89.13184) (xy 11.135024 -89.031377) (xy 11.122847 -88.929603) (xy 11.120374 -88.87841)
			(xy 11.119594 -88.868921) (xy 11.111973 -88.851491) (xy 11.098523 -88.838037) (xy 11.081095 -88.830409)
			(xy 11.071606 -88.829642) (xy 11.020411 -88.827172) (xy 10.918631 -88.815009) (xy 10.818161 -88.794684)
			(xy 10.719656 -88.766331) (xy 10.623756 -88.730133) (xy 10.531084 -88.686326) (xy 10.442244 -88.635194)
			(xy 10.357812 -88.57707) (xy 10.278337 -88.512332) (xy 10.204338 -88.441401) (xy 10.136294 -88.364738)
			(xy 10.074648 -88.282842) (xy 10.019802 -88.196246) (xy 9.972111 -88.105511) (xy 9.931886 -88.011229)
			(xy 9.899388 -87.914013) (xy 9.87483 -87.814494) (xy 9.858369 -87.71332) (xy 9.850114 -87.611148)
			(xy 9.849612 -87.559896) (xy 1.121416 -87.559896) (xy 1.134692 -87.600436) (xy 1.144214 -87.660195)
			(xy 1.144778 -87.690452) (xy 1.14422 -87.72071) (xy 1.134708 -87.780473) (xy 1.115877 -87.837984)
			(xy 1.088201 -87.8918) (xy 1.052374 -87.940571) (xy 1.03124 -87.962232) (xy 1.02433 -87.969605) (xy 1.01648 -87.988206)
			(xy 1.016 -87.9983) (xy 1.016 -92.462604) (xy 1.016488 -92.472694) (xy 1.024347 -92.491287) (xy 1.03124 -92.498672)
			(xy 1.052367 -92.520339) (xy 1.088186 -92.569112) (xy 1.115859 -92.622928) (xy 1.134692 -92.680436)
			(xy 1.144214 -92.740195) (xy 1.144778 -92.770452) (xy 1.14422 -92.80071) (xy 1.134708 -92.860473)
			(xy 1.115877 -92.917984) (xy 1.088201 -92.9718) (xy 1.052374 -93.020571) (xy 1.03124 -93.042232)
			(xy 1.02433 -93.049605) (xy 1.01648 -93.068206) (xy 1.016 -93.0783) (xy 1.016 -93.399864) (xy 3.446023 -93.399864)
			(xy 3.450044 -93.286002) (xy 3.462086 -93.172708) (xy 3.482091 -93.060546) (xy 3.509957 -92.950074)
			(xy 3.545546 -92.841842) (xy 3.588681 -92.736391) (xy 3.639147 -92.634245) (xy 3.696693 -92.535914)
			(xy 3.761032 -92.441886) (xy 3.831843 -92.352631) (xy 3.908773 -92.268594) (xy 3.99144 -92.190192)
			(xy 4.079431 -92.117817) (xy 4.172308 -92.051829) (xy 4.269609 -91.992557) (xy 4.370848 -91.940296)
			(xy 4.475522 -91.895306) (xy 4.583108 -91.857812) (xy 4.693071 -91.828001) (xy 4.804864 -91.80602)
			(xy 4.917928 -91.79198) (xy 5.0317 -91.78595) (xy 5.145615 -91.787961) (xy 5.259104 -91.798002) (xy 5.371603 -91.816024)
			(xy 5.482549 -91.841936) (xy 5.591392 -91.87561) (xy 5.697588 -91.916877) (xy 5.800608 -91.965533)
			(xy 5.89994 -92.021334) (xy 5.995089 -92.084003) (xy 6.085579 -92.153228) (xy 6.170961 -92.228663)
			(xy 6.25081 -92.309934) (xy 6.324727 -92.396634) (xy 6.392343 -92.488332) (xy 6.453324 -92.584571)
			(xy 6.507363 -92.684873) (xy 6.554193 -92.788736) (xy 6.59358 -92.895644) (xy 6.625327 -93.005064)
			(xy 6.649277 -93.11645) (xy 6.665311 -93.229249) (xy 6.673347 -93.342898) (xy 6.67385 -93.399864)
			(xy 6.673347 -93.45683) (xy 6.665311 -93.570479) (xy 6.649277 -93.683278) (xy 6.625327 -93.794664)
			(xy 6.59358 -93.904084) (xy 6.554193 -94.010992) (xy 6.507363 -94.114855) (xy 6.453324 -94.215157)
			(xy 6.392343 -94.311396) (xy 6.324727 -94.403094) (xy 6.25081 -94.489794) (xy 6.170961 -94.571065)
			(xy 6.085579 -94.6465) (xy 5.995089 -94.715725) (xy 5.89994 -94.778394) (xy 5.800608 -94.834195)
			(xy 5.697588 -94.882851) (xy 5.591392 -94.924118) (xy 5.482549 -94.957792) (xy 5.371603 -94.983704)
			(xy 5.259104 -95.001726) (xy 5.145615 -95.011767) (xy 5.0317 -95.013778) (xy 4.917928 -95.007748)
			(xy 4.804864 -94.993708) (xy 4.693071 -94.971727) (xy 4.583108 -94.941916) (xy 4.475522 -94.904422)
			(xy 4.370848 -94.859432) (xy 4.269609 -94.807171) (xy 4.172308 -94.747899) (xy 4.079431 -94.681911)
			(xy 3.99144 -94.609536) (xy 3.908773 -94.531134) (xy 3.831843 -94.447097) (xy 3.761032 -94.357842)
			(xy 3.696693 -94.263814) (xy 3.639147 -94.165483) (xy 3.588681 -94.063337) (xy 3.545546 -93.957886)
			(xy 3.509957 -93.849654) (xy 3.482091 -93.739182) (xy 3.462086 -93.62702) (xy 3.450044 -93.513726)
			(xy 3.446023 -93.399864) (xy 1.016 -93.399864) (xy 1.016 -97.542604) (xy 1.016488 -97.552694) (xy 1.024347 -97.571287)
			(xy 1.03124 -97.578672) (xy 1.052367 -97.600339) (xy 1.088186 -97.649112) (xy 1.115859 -97.702928)
			(xy 1.134692 -97.760436) (xy 1.144214 -97.820195) (xy 1.144778 -97.850452) (xy 1.14422 -97.88071)
			(xy 1.134708 -97.940473) (xy 1.115877 -97.997984) (xy 1.088201 -98.0518) (xy 1.052374 -98.100571)
			(xy 1.03124 -98.122232) (xy 1.02433 -98.129605) (xy 1.01648 -98.148206) (xy 1.016 -98.1583) (xy 1.016 -102.622604)
			(xy 1.016488 -102.632694) (xy 1.024347 -102.651287) (xy 1.03124 -102.658672) (xy 1.052367 -102.680339)
			(xy 1.088186 -102.729112) (xy 1.115859 -102.782928) (xy 1.134692 -102.840436) (xy 1.144214 -102.900195)
			(xy 1.144778 -102.930452) (xy 1.14422 -102.96071) (xy 1.134708 -103.020473) (xy 1.115877 -103.077984)
			(xy 1.088201 -103.1318) (xy 1.052374 -103.180571) (xy 1.03124 -103.202232) (xy 1.02433 -103.209605)
			(xy 1.01648 -103.228206) (xy 1.016 -103.2383) (xy 1.016 -107.702604) (xy 1.016488 -107.712694) (xy 1.024347 -107.731287)
			(xy 1.03124 -107.738672) (xy 1.052367 -107.760339) (xy 1.088186 -107.809112) (xy 1.115859 -107.862928)
			(xy 1.134692 -107.920436) (xy 1.144214 -107.980195) (xy 1.144778 -108.010452) (xy 1.14422 -108.04071)
			(xy 1.134708 -108.100473) (xy 1.115877 -108.157984) (xy 1.088201 -108.2118) (xy 1.052374 -108.260571)
			(xy 1.03124 -108.282232) (xy 1.02433 -108.289605) (xy 1.01648 -108.308206) (xy 1.016 -108.3183) (xy 1.016 -112.782604)
			(xy 1.016488 -112.792694) (xy 1.024347 -112.811287) (xy 1.03124 -112.818672) (xy 1.052367 -112.840339)
			(xy 1.088186 -112.889112) (xy 1.115859 -112.942928) (xy 1.134692 -113.000436) (xy 1.144214 -113.060195)
			(xy 1.144778 -113.090452) (xy 1.144233 -113.119857) (xy 1.135208 -113.177971) (xy 1.117373 -113.234013)
			(xy 1.091152 -113.286655) (xy 1.057166 -113.334651) (xy 1.037082 -113.356136) (xy 1.029812 -113.364294)
			(xy 1.022446 -113.38484) (xy 1.022858 -113.39576) (xy 1.028733 -113.45964) (xy 1.047693 -113.586525)
			(xy 1.074811 -113.711921) (xy 1.109976 -113.835302) (xy 1.153039 -113.956152) (xy 1.203822 -114.073968)
			(xy 1.262111 -114.188256) (xy 1.327664 -114.298539) (xy 1.400205 -114.404356) (xy 1.479432 -114.505264)
			(xy 1.565014 -114.600842) (xy 1.656593 -114.69069) (xy 1.753787 -114.774433) (xy 1.856188 -114.851721)
			(xy 1.96337 -114.92223) (xy 2.074883 -114.985666) (xy 2.190263 -115.041764) (xy 2.309026 -115.09029)
			(xy 2.430676 -115.131039) (xy 2.554706 -115.163844) (xy 2.680596 -115.188565) (xy 2.80782 -115.2051)
			(xy 2.935847 -115.21338) (xy 2.999994 -115.213892) (xy 4.658868 -115.213892) (xy 4.669021 -115.213438)
			(xy 4.687744 -115.205571) (xy 4.69519 -115.198652) (xy 4.71486 -115.179269) (xy 4.758786 -115.145802)
			(xy 4.807078 -115.119018) (xy 4.858727 -115.099476) (xy 4.912654 -115.087585) (xy 4.967732 -115.083594)
			(xy 5.02281 -115.087585) (xy 5.076737 -115.099476) (xy 5.128386 -115.119018) (xy 5.176678 -115.145802)
			(xy 5.220604 -115.179269) (xy 5.240274 -115.198652) (xy 5.247696 -115.205608) (xy 5.266433 -115.213483)
			(xy 5.276596 -115.213892) (xy 9.59993 -115.213892) (xy 9.65371 -115.214361) (xy 9.761 -115.221987)
			(xy 9.814306 -115.229132) (xy 9.823018 -115.229996) (xy 9.840158 -115.226485) (xy 9.847834 -115.222274)
			(xy 9.870283 -115.209203) (xy 9.917966 -115.188588) (xy 9.968004 -115.174632) (xy 10.019472 -115.167592)
			(xy 10.045446 -115.167156) (xy 10.072291 -115.167616) (xy 10.12545 -115.175145) (xy 10.177029 -115.190048)
			(xy 10.226012 -115.212032) (xy 10.271431 -115.240662) (xy 10.31239 -115.275373) (xy 10.348082 -115.315481)
			(xy 10.377802 -115.360195) (xy 10.400964 -115.408631) (xy 10.409428 -115.43411) (xy 10.412375 -115.442322)
			(xy 10.422897 -115.456224) (xy 10.430002 -115.461288) (xy 10.474676 -115.491073) (xy 10.560151 -115.556071)
			(xy 10.640813 -115.626955) (xy 10.716256 -115.703369) (xy 10.786103 -115.784929) (xy 10.850004 -115.871228)
			(xy 10.907638 -115.961832) (xy 10.958716 -116.056287) (xy 11.002983 -116.15412) (xy 11.040216 -116.254839)
			(xy 11.070229 -116.357941) (xy 11.09287 -116.462909) (xy 11.108028 -116.569215) (xy 11.115625 -116.676327)
			(xy 11.116056 -116.730018) (xy 11.116056 -128.230376) (xy 11.115549 -128.284488) (xy 11.107784 -128.392434)
			(xy 11.09234 -128.499551) (xy 11.069298 -128.605294) (xy 11.038775 -128.709125) (xy 11.000925 -128.810515)
			(xy 10.955943 -128.908949) (xy 10.904055 -129.003924) (xy 10.845528 -129.094958) (xy 10.780658 -129.181586)
			(xy 10.709777 -129.263369) (xy 10.633244 -129.339889) (xy 10.55145 -129.410757) (xy 10.464811 -129.475612)
			(xy 10.373767 -129.534124) (xy 10.278783 -129.585995) (xy 10.180343 -129.630962) (xy 10.078946 -129.668795)
			(xy 9.97511 -129.699301) (xy 9.869363 -129.722325) (xy 9.762243 -129.737751) (xy 9.654296 -129.745499)
			(xy 9.600184 -129.745994) (xy 2.999994 -129.745994) (xy 2.965868 -129.746109) (xy 2.897653 -129.748394)
			(xy 2.863596 -129.750566) (xy 2.852512 -129.7519) (xy 2.833 -129.762695) (xy 2.826004 -129.771394)
			(xy 2.807914 -129.795223) (xy 2.765561 -129.837473) (xy 2.717128 -129.87259) (xy 2.663806 -129.899713)
			(xy 2.606903 -129.918175) (xy 2.547814 -129.927524) (xy 2.517902 -129.928112) (xy 2.485712 -129.92744)
			(xy 2.422243 -129.916639) (xy 2.36148 -129.895361) (xy 2.33299 -129.88036) (xy 2.323018 -129.87547)
			(xy 2.300888 -129.873898) (xy 2.290318 -129.877312) (xy 2.231743 -129.900284) (xy 2.117325 -129.952655)
			(xy 2.006457 -130.012171) (xy 1.899583 -130.078594) (xy 1.797133 -130.151656) (xy 1.699519 -130.231064)
			(xy 1.607134 -130.316498) (xy 1.520349 -130.407616) (xy 1.439513 -130.50405) (xy 1.364951 -130.605413)
			(xy 1.296962 -130.711298) (xy 1.23582 -130.821279) (xy 1.181771 -130.934913) (xy 1.135033 -131.051745)
			(xy 1.095792 -131.171303) (xy 1.064207 -131.293108) (xy 1.040404 -131.41667) (xy 1.02448 -131.541491)
			(xy 1.016499 -131.667071) (xy 1.016 -131.729988) (xy 1.016 -132.863082) (xy 1.016518 -132.873354)
			(xy 1.024631 -132.892234) (xy 1.031748 -132.899658) (xy 1.051625 -132.919393) (xy 1.085964 -132.963644)
			(xy 1.113467 -133.012437) (xy 1.133546 -133.064726) (xy 1.145768 -133.119388) (xy 1.149872 -133.175249)
			(xy 1.145768 -133.23111) (xy 1.133547 -133.285771) (xy 1.113469 -133.33806) (xy 1.085965 -133.386854)
			(xy 1.051627 -133.431105) (xy 1.031748 -133.450838) (xy 1.02463 -133.458263) (xy 1.016511 -133.47714)
			(xy 1.016 -133.487414) (xy 1.016 -139.213082) (xy 1.016518 -139.223354) (xy 1.024631 -139.242234)
			(xy 1.031748 -139.249658) (xy 1.051625 -139.269393) (xy 1.085964 -139.313644) (xy 1.113467 -139.362437)
			(xy 1.133546 -139.414726) (xy 1.145768 -139.469388) (xy 1.149872 -139.525249) (xy 1.145768 -139.58111)
			(xy 1.133547 -139.635771) (xy 1.113469 -139.68806) (xy 1.085965 -139.736854) (xy 1.051627 -139.781105)
			(xy 1.031748 -139.800838) (xy 1.02463 -139.808263) (xy 1.016511 -139.82714) (xy 1.016 -139.837414)
			(xy 1.016 -141.99997) (xy 1.016478 -142.088013) (xy 1.024245 -142.263928) (xy 1.039778 -142.439328)
			(xy 1.063047 -142.61387) (xy 1.094007 -142.787213) (xy 1.132596 -142.959019) (xy 1.17874 -143.128952)
			(xy 1.232349 -143.296679) (xy 1.26238 -143.379444) (xy 1.266533 -143.389476) (xy 1.281664 -143.405019)
			(xy 1.29159 -143.409416) (xy 1.318068 -143.420261) (xy 1.367699 -143.448732) (xy 1.412517 -143.484301)
			(xy 1.451516 -143.526168) (xy 1.483821 -143.573393) (xy 1.508705 -143.624915) (xy 1.52561 -143.679578)
			(xy 1.534156 -143.736153) (xy 1.534668 -143.764762) (xy 1.534011 -143.797079) (xy 1.523158 -143.860796)
			(xy 1.513078 -143.891508) (xy 1.509865 -143.90186) (xy 1.511582 -143.923444) (xy 1.51638 -143.933164)
			(xy 1.560488 -144.011605) (xy 1.654834 -144.164874) (xy 1.756006 -144.313727) (xy 1.863798 -144.457858)
			(xy 1.977988 -144.596974) (xy 2.098345 -144.730792) (xy 2.224622 -144.859037) (xy 2.356562 -144.981449)
			(xy 2.493895 -145.097777) (xy 2.636342 -145.207785) (xy 2.783612 -145.311247) (xy 2.935404 -145.407952)
			(xy 3.091408 -145.497704) (xy 3.251307 -145.580319) (xy 3.414774 -145.655629) (xy 3.581474 -145.723479)
			(xy 3.751069 -145.783732) (xy 3.923212 -145.836264) (xy 4.097552 -145.880968) (xy 4.273732 -145.917754)
			(xy 4.451395 -145.946545) (xy 4.630176 -145.967283) (xy 4.809711 -145.979927) (xy 4.89966 -145.98269)
			(xy 4.909963 -145.98247) (xy 4.929095 -145.974865) (xy 4.936744 -145.967958) (xy 4.958357 -145.947175)
			(xy 5.00686 -145.911929) (xy 5.060278 -145.884703) (xy 5.117297 -145.866165) (xy 5.176514 -145.856772)
			(xy 5.206492 -145.856198) (xy 5.236616 -145.856767) (xy 5.296113 -145.86624) (xy 5.353381 -145.884951)
			(xy 5.406993 -145.912436) (xy 5.455617 -145.948009) (xy 5.477256 -145.968974) (xy 5.484656 -145.975814)
			(xy 5.503255 -145.983532) (xy 5.513324 -145.98396)
		)
		(stroke
			(width 0)
			(type solid)
		)
		(fill yes)
		(layer "In5.Cu")
		(net "GND")
	)
	(gr_poly
		(pts
			(xy 237.996984 -145.98396) (xy 238.007479 -145.983431) (xy 238.026715 -145.975027) (xy 238.041004 -145.959648)
			(xy 238.04499 -145.949924) (xy 238.04499 -145.94967) (xy 238.059208 -145.909656) (xy 238.094243 -145.832295)
			(xy 238.136493 -145.758626) (xy 238.185573 -145.689319) (xy 238.241035 -145.625006) (xy 238.302374 -145.566273)
			(xy 238.369033 -145.513653) (xy 238.440404 -145.467627) (xy 238.515837 -145.428613) (xy 238.594645 -145.396967)
			(xy 238.67611 -145.372977) (xy 238.759492 -145.356861) (xy 238.84403 -145.348766) (xy 238.928954 -145.348766)
			(xy 239.013492 -145.356861) (xy 239.096874 -145.372977) (xy 239.178339 -145.396967) (xy 239.257147 -145.428613)
			(xy 239.33258 -145.467627) (xy 239.403951 -145.513653) (xy 239.47061 -145.566273) (xy 239.531949 -145.625006)
			(xy 239.587411 -145.689319) (xy 239.636491 -145.758626) (xy 239.678741 -145.832295) (xy 239.713776 -145.909656)
			(xy 239.727994 -145.94967) (xy 239.727994 -145.949924) (xy 239.731946 -145.959668) (xy 239.746235 -145.975063)
			(xy 239.765497 -145.983442) (xy 239.776 -145.98396) (xy 243.076984 -145.98396) (xy 243.087479 -145.983431)
			(xy 243.106715 -145.975027) (xy 243.121004 -145.959648) (xy 243.12499 -145.949924) (xy 243.12499 -145.94967)
			(xy 243.139208 -145.909656) (xy 243.174243 -145.832295) (xy 243.216493 -145.758626) (xy 243.265573 -145.689319)
			(xy 243.321035 -145.625006) (xy 243.382374 -145.566273) (xy 243.449033 -145.513653) (xy 243.520404 -145.467627)
			(xy 243.595837 -145.428613) (xy 243.674645 -145.396967) (xy 243.75611 -145.372977) (xy 243.839492 -145.356861)
			(xy 243.92403 -145.348766) (xy 244.008954 -145.348766) (xy 244.093492 -145.356861) (xy 244.176874 -145.372977)
			(xy 244.258339 -145.396967) (xy 244.337147 -145.428613) (xy 244.41258 -145.467627) (xy 244.483951 -145.513653)
			(xy 244.55061 -145.566273) (xy 244.611949 -145.625006) (xy 244.667411 -145.689319) (xy 244.716491 -145.758626)
			(xy 244.758741 -145.832295) (xy 244.793776 -145.909656) (xy 244.807994 -145.94967) (xy 244.807994 -145.949924)
			(xy 244.811946 -145.959668) (xy 244.826235 -145.975063) (xy 244.845497 -145.983442) (xy 244.856 -145.98396)
			(xy 248.156984 -145.98396) (xy 248.167479 -145.983431) (xy 248.186715 -145.975027) (xy 248.201004 -145.959648)
			(xy 248.20499 -145.949924) (xy 248.20499 -145.94967) (xy 248.219208 -145.909656) (xy 248.254243 -145.832295)
			(xy 248.296493 -145.758626) (xy 248.345573 -145.689319) (xy 248.401035 -145.625006) (xy 248.462374 -145.566273)
			(xy 248.529033 -145.513653) (xy 248.600404 -145.467627) (xy 248.675837 -145.428613) (xy 248.754645 -145.396967)
			(xy 248.83611 -145.372977) (xy 248.919492 -145.356861) (xy 249.00403 -145.348766) (xy 249.088954 -145.348766)
			(xy 249.173492 -145.356861) (xy 249.256874 -145.372977) (xy 249.338339 -145.396967) (xy 249.417147 -145.428613)
			(xy 249.49258 -145.467627) (xy 249.563951 -145.513653) (xy 249.63061 -145.566273) (xy 249.691949 -145.625006)
			(xy 249.747411 -145.689319) (xy 249.796491 -145.758626) (xy 249.838741 -145.832295) (xy 249.873776 -145.909656)
			(xy 249.887994 -145.94967) (xy 249.887994 -145.949924) (xy 249.891946 -145.959668) (xy 249.906235 -145.975063)
			(xy 249.925497 -145.983442) (xy 249.936 -145.98396) (xy 253.236984 -145.98396) (xy 253.247479 -145.983431)
			(xy 253.266715 -145.975027) (xy 253.281004 -145.959648) (xy 253.28499 -145.949924) (xy 253.28499 -145.94967)
			(xy 253.299208 -145.909656) (xy 253.334243 -145.832295) (xy 253.376493 -145.758626) (xy 253.425573 -145.689319)
			(xy 253.481035 -145.625006) (xy 253.542374 -145.566273) (xy 253.609033 -145.513653) (xy 253.680404 -145.467627)
			(xy 253.755837 -145.428613) (xy 253.834645 -145.396967) (xy 253.91611 -145.372977) (xy 253.999492 -145.356861)
			(xy 254.08403 -145.348766) (xy 254.168954 -145.348766) (xy 254.253492 -145.356861) (xy 254.336874 -145.372977)
			(xy 254.418339 -145.396967) (xy 254.497147 -145.428613) (xy 254.57258 -145.467627) (xy 254.643951 -145.513653)
			(xy 254.71061 -145.566273) (xy 254.771949 -145.625006) (xy 254.827411 -145.689319) (xy 254.876491 -145.758626)
			(xy 254.918741 -145.832295) (xy 254.953776 -145.909656) (xy 254.967994 -145.94967) (xy 254.967994 -145.949924)
			(xy 254.971946 -145.959668) (xy 254.986235 -145.975063) (xy 255.005497 -145.983442) (xy 255.016 -145.98396)
			(xy 258.316984 -145.98396) (xy 258.327479 -145.983431) (xy 258.346715 -145.975027) (xy 258.361004 -145.959648)
			(xy 258.36499 -145.949924) (xy 258.36499 -145.94967) (xy 258.379208 -145.909656) (xy 258.414243 -145.832295)
			(xy 258.456493 -145.758626) (xy 258.505573 -145.689319) (xy 258.561035 -145.625006) (xy 258.622374 -145.566273)
			(xy 258.689033 -145.513653) (xy 258.760404 -145.467627) (xy 258.835837 -145.428613) (xy 258.914645 -145.396967)
			(xy 258.99611 -145.372977) (xy 259.079492 -145.356861) (xy 259.16403 -145.348766) (xy 259.248954 -145.348766)
			(xy 259.333492 -145.356861) (xy 259.416874 -145.372977) (xy 259.498339 -145.396967) (xy 259.577147 -145.428613)
			(xy 259.65258 -145.467627) (xy 259.723951 -145.513653) (xy 259.79061 -145.566273) (xy 259.851949 -145.625006)
			(xy 259.907411 -145.689319) (xy 259.956491 -145.758626) (xy 259.998741 -145.832295) (xy 260.033776 -145.909656)
			(xy 260.047994 -145.94967) (xy 260.047994 -145.949924) (xy 260.051946 -145.959668) (xy 260.066235 -145.975063)
			(xy 260.085497 -145.983442) (xy 260.096 -145.98396) (xy 263.396984 -145.98396) (xy 263.407479 -145.983431)
			(xy 263.426715 -145.975027) (xy 263.441004 -145.959648) (xy 263.44499 -145.949924) (xy 263.44499 -145.94967)
			(xy 263.459208 -145.909656) (xy 263.494243 -145.832295) (xy 263.536493 -145.758626) (xy 263.585573 -145.689319)
			(xy 263.641035 -145.625006) (xy 263.702374 -145.566273) (xy 263.769033 -145.513653) (xy 263.840404 -145.467627)
			(xy 263.915837 -145.428613) (xy 263.994645 -145.396967) (xy 264.07611 -145.372977) (xy 264.159492 -145.356861)
			(xy 264.24403 -145.348766) (xy 264.328954 -145.348766) (xy 264.413492 -145.356861) (xy 264.496874 -145.372977)
			(xy 264.578339 -145.396967) (xy 264.657147 -145.428613) (xy 264.73258 -145.467627) (xy 264.803951 -145.513653)
			(xy 264.87061 -145.566273) (xy 264.931949 -145.625006) (xy 264.987411 -145.689319) (xy 265.036491 -145.758626)
			(xy 265.078741 -145.832295) (xy 265.113776 -145.909656) (xy 265.127994 -145.94967) (xy 265.127994 -145.949924)
			(xy 265.131946 -145.959668) (xy 265.146235 -145.975063) (xy 265.165497 -145.983442) (xy 265.176 -145.98396)
			(xy 268.476984 -145.98396) (xy 268.487479 -145.983431) (xy 268.506715 -145.975027) (xy 268.521004 -145.959648)
			(xy 268.52499 -145.949924) (xy 268.52499 -145.94967) (xy 268.539208 -145.909656) (xy 268.574243 -145.832295)
			(xy 268.616493 -145.758626) (xy 268.665573 -145.689319) (xy 268.721035 -145.625006) (xy 268.782374 -145.566273)
			(xy 268.849033 -145.513653) (xy 268.920404 -145.467627) (xy 268.995837 -145.428613) (xy 269.074645 -145.396967)
			(xy 269.15611 -145.372977) (xy 269.239492 -145.356861) (xy 269.32403 -145.348766) (xy 269.408954 -145.348766)
			(xy 269.493492 -145.356861) (xy 269.576874 -145.372977) (xy 269.658339 -145.396967) (xy 269.737147 -145.428613)
			(xy 269.81258 -145.467627) (xy 269.883951 -145.513653) (xy 269.95061 -145.566273) (xy 270.011949 -145.625006)
			(xy 270.067411 -145.689319) (xy 270.116491 -145.758626) (xy 270.158741 -145.832295) (xy 270.193776 -145.909656)
			(xy 270.207994 -145.94967) (xy 270.207994 -145.949924) (xy 270.211946 -145.959668) (xy 270.226235 -145.975063)
			(xy 270.245497 -145.983442) (xy 270.256 -145.98396) (xy 273.556984 -145.98396) (xy 273.567479 -145.983431)
			(xy 273.586715 -145.975027) (xy 273.601004 -145.959648) (xy 273.60499 -145.949924) (xy 273.60499 -145.94967)
			(xy 273.619208 -145.909656) (xy 273.654243 -145.832295) (xy 273.696493 -145.758626) (xy 273.745573 -145.689319)
			(xy 273.801035 -145.625006) (xy 273.862374 -145.566273) (xy 273.929033 -145.513653) (xy 274.000404 -145.467627)
			(xy 274.075837 -145.428613) (xy 274.154645 -145.396967) (xy 274.23611 -145.372977) (xy 274.319492 -145.356861)
			(xy 274.40403 -145.348766) (xy 274.488954 -145.348766) (xy 274.573492 -145.356861) (xy 274.656874 -145.372977)
			(xy 274.738339 -145.396967) (xy 274.817147 -145.428613) (xy 274.89258 -145.467627) (xy 274.963951 -145.513653)
			(xy 275.03061 -145.566273) (xy 275.091949 -145.625006) (xy 275.147411 -145.689319) (xy 275.196491 -145.758626)
			(xy 275.238741 -145.832295) (xy 275.273776 -145.909656) (xy 275.287994 -145.94967) (xy 275.287994 -145.949924)
			(xy 275.291946 -145.959668) (xy 275.306235 -145.975063) (xy 275.325497 -145.983442) (xy 275.336 -145.98396)
			(xy 276.984714 -145.98396) (xy 276.994782 -145.983533) (xy 277.013379 -145.975811) (xy 277.020782 -145.968974)
			(xy 277.676864 -145.312892) (xy 277.683713 -145.305495) (xy 277.69145 -145.286896) (xy 277.69185 -145.276824)
			(xy 277.69185 -134.557516) (xy 277.69141 -134.547454) (xy 277.683669 -134.528876) (xy 277.676864 -134.521448)
			(xy 276.638512 -133.483096) (xy 276.631114 -133.476248) (xy 276.612516 -133.46851) (xy 276.602444 -133.46811)
			(xy 269.48511 -133.46811) (xy 269.45185 -133.467589) (xy 269.385899 -133.458903) (xy 269.321647 -133.441679)
			(xy 269.260194 -133.416211) (xy 269.202594 -133.382936) (xy 269.149833 -133.342424) (xy 269.125954 -133.319266)
			(xy 268.322044 -132.515356) (xy 268.298888 -132.491476) (xy 268.258382 -132.438712) (xy 268.225111 -132.381111)
			(xy 268.199647 -132.31966) (xy 268.182425 -132.255409) (xy 268.173739 -132.189459) (xy 268.1732 -132.1562)
			(xy 268.1732 -128.016) (xy 268.173721 -127.98274) (xy 268.182409 -127.91679) (xy 268.199634 -127.852539)
			(xy 268.225103 -127.791088) (xy 268.258379 -127.733489) (xy 268.298892 -127.680729) (xy 268.322044 -127.656844)
			(xy 269.058644 -126.920244) (xy 269.082524 -126.897088) (xy 269.135288 -126.856582) (xy 269.192889 -126.823311)
			(xy 269.25434 -126.797847) (xy 269.318591 -126.780625) (xy 269.384541 -126.771939) (xy 269.4178 -126.7714)
			(xy 272.793206 -126.7714) (xy 272.803276 -126.770976) (xy 272.821879 -126.76326) (xy 272.829274 -126.756414)
			(xy 273.162014 -126.423674) (xy 273.168866 -126.416278) (xy 273.176604 -126.397679) (xy 273.177 -126.387606)
			(xy 273.177 -121.516394) (xy 273.176576 -121.506324) (xy 273.16886 -121.487721) (xy 273.162014 -121.480326)
			(xy 272.753074 -121.071386) (xy 272.745678 -121.064534) (xy 272.727079 -121.056796) (xy 272.717006 -121.0564)
			(xy 269.2654 -121.0564) (xy 269.23214 -121.055879) (xy 269.16619 -121.047191) (xy 269.101939 -121.029966)
			(xy 269.040488 -121.004497) (xy 268.982889 -120.971221) (xy 268.930129 -120.930708) (xy 268.906244 -120.907556)
			(xy 268.322044 -120.323356) (xy 268.298888 -120.299476) (xy 268.258382 -120.246712) (xy 268.225111 -120.189111)
			(xy 268.199647 -120.12766) (xy 268.182425 -120.063409) (xy 268.173739 -119.997459) (xy 268.1732 -119.9642)
			(xy 268.1732 -116.0018) (xy 268.173721 -115.96854) (xy 268.182409 -115.90259) (xy 268.199634 -115.838339)
			(xy 268.225103 -115.776888) (xy 268.258379 -115.719289) (xy 268.298892 -115.666529) (xy 268.322044 -115.642644)
			(xy 268.957044 -115.007644) (xy 268.980924 -114.984488) (xy 269.033688 -114.943982) (xy 269.091289 -114.910711)
			(xy 269.15274 -114.885247) (xy 269.216991 -114.868025) (xy 269.282941 -114.859339) (xy 269.3162 -114.8588)
			(xy 272.640806 -114.8588) (xy 272.650876 -114.858376) (xy 272.669479 -114.85066) (xy 272.676874 -114.843814)
			(xy 273.162014 -114.358674) (xy 273.168866 -114.351278) (xy 273.176604 -114.332679) (xy 273.177 -114.322606)
			(xy 273.177 -109.451394) (xy 273.176576 -109.441324) (xy 273.16886 -109.422721) (xy 273.162014 -109.415326)
			(xy 272.499074 -108.752386) (xy 272.491678 -108.745534) (xy 272.473079 -108.737796) (xy 272.463006 -108.7374)
			(xy 269.3924 -108.7374) (xy 269.35914 -108.736879) (xy 269.29319 -108.728191) (xy 269.228939 -108.710966)
			(xy 269.167488 -108.685497) (xy 269.109889 -108.652221) (xy 269.057129 -108.611708) (xy 269.033244 -108.588556)
			(xy 268.322044 -107.877356) (xy 268.298888 -107.853476) (xy 268.258382 -107.800712) (xy 268.225111 -107.743111)
			(xy 268.199647 -107.68166) (xy 268.182425 -107.617409) (xy 268.173739 -107.551459) (xy 268.1732 -107.5182)
			(xy 268.1732 -105.751122) (xy 268.17372 -105.717861) (xy 268.182405 -105.65191) (xy 268.199628 -105.587657)
			(xy 268.225095 -105.526204) (xy 268.25837 -105.468603) (xy 268.298882 -105.415841) (xy 268.322044 -105.391966)
			(xy 268.766798 -104.947212) (xy 268.790676 -104.924051) (xy 268.843436 -104.883534) (xy 268.901036 -104.850255)
			(xy 268.962488 -104.824781) (xy 269.026741 -104.807551) (xy 269.092693 -104.798858) (xy 269.125954 -104.798368)
			(xy 270.22298 -104.798368) (xy 270.23203 -104.797992) (xy 270.249 -104.791691) (xy 270.262734 -104.779899)
			(xy 270.271529 -104.764077) (xy 270.273272 -104.755188) (xy 270.280023 -104.713566) (xy 270.300381 -104.631735)
			(xy 270.328392 -104.552197) (xy 270.363803 -104.475668) (xy 270.406298 -104.402832) (xy 270.455495 -104.334345)
			(xy 270.510952 -104.270821) (xy 270.572171 -104.212829) (xy 270.638604 -104.160892) (xy 270.709653 -104.115474)
			(xy 270.784681 -104.076983) (xy 270.863015 -104.045765) (xy 270.943952 -104.0221) (xy 271.026765 -104.0062)
			(xy 271.110711 -103.998208) (xy 271.152874 -103.99776) (xy 271.173926 -103.997901) (xy 271.215981 -103.999935)
			(xy 271.236948 -104.001824) (xy 271.24787 -104.00284) (xy 271.267682 -103.996236) (xy 271.331436 -103.938324)
			(xy 271.338989 -103.93073) (xy 271.347665 -103.911174) (xy 271.3482 -103.900478) (xy 271.3482 -102.9716)
			(xy 271.348721 -102.93834) (xy 271.357409 -102.87239) (xy 271.374634 -102.808139) (xy 271.400103 -102.746688)
			(xy 271.433379 -102.689089) (xy 271.473892 -102.636329) (xy 271.497044 -102.612444) (xy 271.979644 -102.129844)
			(xy 272.003524 -102.106688) (xy 272.056288 -102.066182) (xy 272.113889 -102.032911) (xy 272.17534 -102.007447)
			(xy 272.239591 -101.990225) (xy 272.305541 -101.981539) (xy 272.3388 -101.981) (xy 272.945606 -101.981)
			(xy 272.955676 -101.980576) (xy 272.974279 -101.97286) (xy 272.981674 -101.966014) (xy 273.162014 -101.785674)
			(xy 273.168866 -101.778278) (xy 273.176604 -101.759679) (xy 273.177 -101.749606) (xy 273.177 -98.021394)
			(xy 273.176576 -98.011324) (xy 273.16886 -97.992721) (xy 273.162014 -97.985326) (xy 272.690844 -97.514156)
			(xy 272.667688 -97.490276) (xy 272.627182 -97.437512) (xy 272.593911 -97.379911) (xy 272.568447 -97.31846)
			(xy 272.551225 -97.254209) (xy 272.542539 -97.188259) (xy 272.542 -97.155) (xy 272.542 -94.706694)
			(xy 272.541576 -94.696624) (xy 272.53386 -94.678021) (xy 272.527014 -94.670626) (xy 272.359374 -94.502986)
			(xy 272.351978 -94.496134) (xy 272.333379 -94.488396) (xy 272.323306 -94.488) (xy 269.067026 -94.488)
			(xy 269.033765 -94.48748) (xy 268.967813 -94.478796) (xy 268.90356 -94.461573) (xy 268.842107 -94.436106)
			(xy 268.784506 -94.402832) (xy 268.731744 -94.36232) (xy 268.70787 -94.339156) (xy 268.322044 -93.95333)
			(xy 268.298889 -93.929449) (xy 268.258386 -93.876685) (xy 268.225118 -93.819084) (xy 268.199657 -93.757632)
			(xy 268.182438 -93.693382) (xy 268.173756 -93.627433) (xy 268.1732 -93.594174) (xy 268.1732 -91.3638)
			(xy 268.173721 -91.33054) (xy 268.182409 -91.26459) (xy 268.199634 -91.200339) (xy 268.225103 -91.138888)
			(xy 268.258379 -91.081289) (xy 268.298892 -91.028529) (xy 268.322044 -91.004644) (xy 269.134844 -90.191844)
			(xy 269.158724 -90.168688) (xy 269.211488 -90.128182) (xy 269.269089 -90.094911) (xy 269.33054 -90.069447)
			(xy 269.394791 -90.052225) (xy 269.460741 -90.043539) (xy 269.494 -90.043) (xy 272.945606 -90.043)
			(xy 272.955676 -90.042576) (xy 272.974279 -90.03486) (xy 272.981674 -90.028014) (xy 273.162014 -89.847674)
			(xy 273.168866 -89.840278) (xy 273.176604 -89.821679) (xy 273.177 -89.811606) (xy 273.177 -85.956394)
			(xy 273.176576 -85.946324) (xy 273.16886 -85.927721) (xy 273.162014 -85.920326) (xy 272.727674 -85.485986)
			(xy 272.720278 -85.479134) (xy 272.701679 -85.471396) (xy 272.691606 -85.471) (xy 269.367 -85.471)
			(xy 269.33374 -85.470479) (xy 269.26779 -85.461791) (xy 269.203539 -85.444566) (xy 269.142088 -85.419097)
			(xy 269.084489 -85.385821) (xy 269.031729 -85.345308) (xy 269.007844 -85.322156) (xy 268.322044 -84.636356)
			(xy 268.298888 -84.612476) (xy 268.258382 -84.559712) (xy 268.225111 -84.502111) (xy 268.199647 -84.44066)
			(xy 268.182425 -84.376409) (xy 268.173739 -84.310459) (xy 268.1732 -84.2772) (xy 268.1732 -79.9338)
			(xy 268.173721 -79.90054) (xy 268.182409 -79.83459) (xy 268.199634 -79.770339) (xy 268.225103 -79.708888)
			(xy 268.258379 -79.651289) (xy 268.298892 -79.598529) (xy 268.322044 -79.574644) (xy 269.084044 -78.812644)
			(xy 269.107924 -78.789488) (xy 269.160688 -78.748982) (xy 269.218289 -78.715711) (xy 269.27974 -78.690247)
			(xy 269.343991 -78.673025) (xy 269.409941 -78.664339) (xy 269.4432 -78.6638) (xy 272.767806 -78.6638)
			(xy 272.777876 -78.663376) (xy 272.796479 -78.65566) (xy 272.803874 -78.648814) (xy 273.162014 -78.290674)
			(xy 273.168866 -78.283278) (xy 273.176604 -78.264679) (xy 273.177 -78.254606) (xy 273.177 -72.240394)
			(xy 273.176576 -72.230324) (xy 273.16886 -72.211721) (xy 273.162014 -72.204326) (xy 272.753074 -71.795386)
			(xy 272.745678 -71.788534) (xy 272.727079 -71.780796) (xy 272.717006 -71.7804) (xy 269.5194 -71.7804)
			(xy 269.48614 -71.779879) (xy 269.42019 -71.771191) (xy 269.355939 -71.753966) (xy 269.294488 -71.728497)
			(xy 269.236889 -71.695221) (xy 269.184129 -71.654708) (xy 269.160244 -71.631556) (xy 268.322044 -70.793356)
			(xy 268.298888 -70.769476) (xy 268.258382 -70.716712) (xy 268.225111 -70.659111) (xy 268.199647 -70.59766)
			(xy 268.182425 -70.533409) (xy 268.173739 -70.467459) (xy 268.1732 -70.4342) (xy 268.1732 -67.2338)
			(xy 268.173721 -67.20054) (xy 268.182409 -67.13459) (xy 268.199634 -67.070339) (xy 268.225103 -67.008888)
			(xy 268.258379 -66.951289) (xy 268.298892 -66.898529) (xy 268.322044 -66.874644) (xy 269.033244 -66.163444)
			(xy 269.057124 -66.140288) (xy 269.109888 -66.099782) (xy 269.167489 -66.066511) (xy 269.22894 -66.041047)
			(xy 269.293191 -66.023825) (xy 269.359141 -66.015139) (xy 269.3924 -66.0146) (xy 275.241258 -66.0146)
			(xy 275.251323 -66.014166) (xy 275.269913 -66.006437) (xy 275.277326 -65.999614) (xy 275.419566 -65.857374)
			(xy 275.426412 -65.849976) (xy 275.434143 -65.831377) (xy 275.434552 -65.821306) (xy 275.434552 -51.47437)
			(xy 275.434403 -51.468502) (xy 275.431712 -51.457078) (xy 275.429218 -51.451764) (xy 275.411205 -51.414661)
			(xy 275.381335 -51.337775) (xy 275.358718 -51.258453) (xy 275.343546 -51.177376) (xy 275.33595 -51.095242)
			(xy 275.335492 -51.054) (xy 275.336077 -51.007604) (xy 275.34571 -50.915314) (xy 275.364903 -50.824529)
			(xy 275.393447 -50.736236) (xy 275.411692 -50.693574) (xy 275.415498 -50.683632) (xy 275.415498 -50.662368)
			(xy 275.411692 -50.652426) (xy 275.393477 -50.609821) (xy 275.364965 -50.521652) (xy 275.345769 -50.430998)
			(xy 275.336098 -50.33884) (xy 275.335492 -50.292508) (xy 275.335492 -50.292) (xy 275.335967 -50.250898)
			(xy 275.343552 -50.169043) (xy 275.358657 -50.088238) (xy 275.381153 -50.009171) (xy 275.410849 -49.932517)
			(xy 275.447491 -49.85893) (xy 275.490766 -49.789038) (xy 275.540306 -49.723437) (xy 275.595687 -49.662687)
			(xy 275.656437 -49.607306) (xy 275.722038 -49.557766) (xy 275.79193 -49.514491) (xy 275.865517 -49.477849)
			(xy 275.942171 -49.448153) (xy 276.021238 -49.425657) (xy 276.102043 -49.410552) (xy 276.183898 -49.402967)
			(xy 276.225 -49.402492) (xy 276.267492 -49.402987) (xy 276.352088 -49.41109) (xy 276.435526 -49.427223)
			(xy 276.517046 -49.451239) (xy 276.595904 -49.482919) (xy 276.671382 -49.521973) (xy 276.742792 -49.568047)
			(xy 276.776434 -49.594008) (xy 276.783963 -49.59938) (xy 276.801613 -49.604863) (xy 276.820062 -49.603754)
			(xy 276.836928 -49.596195) (xy 276.843744 -49.589944) (xy 280.120344 -46.313344) (xy 280.144224 -46.290188)
			(xy 280.196988 -46.249682) (xy 280.254589 -46.216411) (xy 280.31604 -46.190947) (xy 280.380291 -46.173725)
			(xy 280.446241 -46.165039) (xy 280.4795 -46.1645) (xy 288.855404 -46.1645) (xy 288.868135 -46.163793)
			(xy 288.890521 -46.151658) (xy 288.898076 -46.141386) (xy 288.920334 -46.107781) (xy 288.970039 -46.044318)
			(xy 289.025281 -45.985613) (xy 289.085607 -45.932146) (xy 289.150524 -45.884356) (xy 289.219498 -45.842636)
			(xy 289.291964 -45.807326) (xy 289.367327 -45.778718) (xy 289.444969 -45.757046) (xy 289.524254 -45.742487)
			(xy 289.604531 -45.735161) (xy 289.644836 -45.734732) (xy 289.645344 -45.734732) (xy 289.6845 -45.735172)
			(xy 289.762506 -45.742081) (xy 289.839603 -45.755815) (xy 289.915197 -45.776267) (xy 289.988702 -45.803281)
			(xy 290.024312 -45.819568) (xy 290.034699 -45.823803) (xy 290.057105 -45.823803) (xy 290.067492 -45.819568)
			(xy 290.103095 -45.803263) (xy 290.176598 -45.776239) (xy 290.252193 -45.755782) (xy 290.329294 -45.742052)
			(xy 290.407303 -45.735154) (xy 290.44646 -45.734732) (xy 290.446968 -45.734732) (xy 290.487272 -45.735196)
			(xy 290.567547 -45.742515) (xy 290.64683 -45.757068) (xy 290.724471 -45.778736) (xy 290.799833 -45.807342)
			(xy 290.872297 -45.84265) (xy 290.941268 -45.884371) (xy 291.00618 -45.932162) (xy 291.066502 -45.985631)
			(xy 291.121737 -46.04434) (xy 291.171433 -46.107806) (xy 291.193728 -46.141386) (xy 291.198591 -46.148317)
			(xy 291.211927 -46.158731) (xy 291.227938 -46.164206) (xy 291.2364 -46.1645) (xy 293.340536 -46.1645)
			(xy 293.349969 -46.164132) (xy 293.367563 -46.157321) (xy 293.381495 -46.1446) (xy 293.386002 -46.136306)
			(xy 293.426642 -46.054772) (xy 293.430425 -46.046184) (xy 293.432154 -46.027516) (xy 293.427056 -46.009473)
			(xy 293.421816 -46.001686) (xy 293.397467 -45.968611) (xy 293.354269 -45.898751) (xy 293.317694 -45.825207)
			(xy 293.288053 -45.748605) (xy 293.265598 -45.669597) (xy 293.250522 -45.588856) (xy 293.242951 -45.507068)
			(xy 293.242492 -45.466) (xy 293.242996 -45.423652) (xy 293.251047 -45.339338) (xy 293.267076 -45.256172)
			(xy 293.290937 -45.174905) (xy 293.322416 -45.096275) (xy 293.361227 -45.020994) (xy 293.407017 -44.949742)
			(xy 293.459373 -44.883166) (xy 293.517821 -44.821868) (xy 293.581831 -44.766403) (xy 293.650823 -44.717274)
			(xy 293.724173 -44.674925) (xy 293.801216 -44.639741) (xy 293.881255 -44.612039) (xy 293.963564 -44.592071)
			(xy 294.047399 -44.580018) (xy 294.132 -44.575988) (xy 294.216601 -44.580018) (xy 294.300436 -44.592071)
			(xy 294.382745 -44.612039) (xy 294.462784 -44.639741) (xy 294.539827 -44.674925) (xy 294.613177 -44.717274)
			(xy 294.682169 -44.766403) (xy 294.746179 -44.821868) (xy 294.804627 -44.883166) (xy 294.856983 -44.949742)
			(xy 294.902773 -45.020994) (xy 294.941584 -45.096275) (xy 294.973063 -45.174905) (xy 294.996924 -45.256172)
			(xy 295.012953 -45.339338) (xy 295.021004 -45.423652) (xy 295.021508 -45.466) (xy 295.021035 -45.507068)
			(xy 295.013466 -45.588855) (xy 294.998391 -45.669596) (xy 294.975939 -45.748604) (xy 294.946301 -45.825206)
			(xy 294.909729 -45.898752) (xy 294.866536 -45.968613) (xy 294.842184 -46.001686) (xy 294.836896 -46.009445)
			(xy 294.831807 -46.027501) (xy 294.833577 -46.046176) (xy 294.837358 -46.054772) (xy 294.877998 -46.136306)
			(xy 294.882586 -46.144535) (xy 294.896501 -46.157212) (xy 294.914052 -46.164016) (xy 294.923464 -46.1645)
			(xy 295.030906 -46.1645) (xy 295.040976 -46.164076) (xy 295.059579 -46.15636) (xy 295.066974 -46.149514)
			(xy 295.564814 -45.651674) (xy 295.571666 -45.644278) (xy 295.579404 -45.625679) (xy 295.5798 -45.615606)
			(xy 295.5798 -42.446194) (xy 295.579376 -42.436124) (xy 295.57166 -42.417521) (xy 295.564814 -42.410126)
			(xy 294.571674 -41.416986) (xy 294.564278 -41.410134) (xy 294.545679 -41.402396) (xy 294.535606 -41.402)
			(xy 293.60368 -41.402) (xy 293.594337 -41.40247) (xy 293.576916 -41.409246) (xy 293.563057 -41.421789)
			(xy 293.558468 -41.42994) (xy 293.51732 -41.510966) (xy 293.513485 -41.519533) (xy 293.511648 -41.538195)
			(xy 293.516648 -41.556268) (xy 293.521892 -41.564052) (xy 293.545557 -41.596846) (xy 293.587523 -41.665983)
			(xy 293.623044 -41.738643) (xy 293.651825 -41.814225) (xy 293.67363 -41.892108) (xy 293.688279 -41.971647)
			(xy 293.695651 -42.052188) (xy 293.696136 -42.092626) (xy 293.695632 -42.134987) (xy 293.687579 -42.219324)
			(xy 293.671545 -42.302514) (xy 293.647677 -42.383804) (xy 293.616189 -42.462456) (xy 293.577367 -42.537759)
			(xy 293.531564 -42.609031) (xy 293.479193 -42.675627) (xy 293.420728 -42.736942) (xy 293.3567 -42.792423)
			(xy 293.287688 -42.841566) (xy 293.214318 -42.883926) (xy 293.137253 -42.919121) (xy 293.057191 -42.94683)
			(xy 292.974858 -42.966804) (xy 292.890999 -42.978861) (xy 292.806374 -42.982893) (xy 292.721749 -42.978861)
			(xy 292.63789 -42.966804) (xy 292.555557 -42.94683) (xy 292.475495 -42.919121) (xy 292.39843 -42.883926)
			(xy 292.32506 -42.841566) (xy 292.256048 -42.792423) (xy 292.19202 -42.736942) (xy 292.133555 -42.675627)
			(xy 292.081184 -42.609031) (xy 292.035381 -42.537759) (xy 291.996559 -42.462456) (xy 291.965071 -42.383804)
			(xy 291.941203 -42.302514) (xy 291.925169 -42.219324) (xy 291.917116 -42.134987) (xy 291.916612 -42.092626)
			(xy 291.917078 -42.052186) (xy 291.924436 -41.971641) (xy 291.939077 -41.892097) (xy 291.960879 -41.81421)
			(xy 291.989663 -41.738625) (xy 292.025189 -41.665964) (xy 292.067166 -41.59683) (xy 292.090856 -41.564052)
			(xy 292.099492 -41.552368) (xy 292.101778 -41.52392) (xy 292.05428 -41.42994) (xy 292.049712 -41.421763)
			(xy 292.035872 -41.409169) (xy 292.018424 -41.402405) (xy 292.009068 -41.402) (xy 290.449 -41.402)
			(xy 290.424454 -41.401656) (xy 290.3756 -41.396826) (xy 290.351464 -41.392348) (xy 290.341562 -41.390793)
			(xy 290.321916 -41.394686) (xy 290.305265 -41.405817) (xy 290.299394 -41.413938) (xy 290.274682 -41.449926)
			(xy 290.219269 -41.517393) (xy 290.157512 -41.579105) (xy 290.090005 -41.634468) (xy 290.017398 -41.682951)
			(xy 289.94039 -41.724086) (xy 289.859722 -41.757477) (xy 289.776171 -41.782803) (xy 289.69054 -41.799821)
			(xy 289.603653 -41.808366) (xy 289.56 -41.808908) (xy 289.559492 -41.808908) (xy 289.520745 -41.808475)
			(xy 289.443545 -41.801707) (xy 289.367228 -41.788249) (xy 289.29237 -41.768204) (xy 289.219539 -41.741723)
			(xy 289.149289 -41.709007) (xy 289.1155 -41.690036) (xy 289.107626 -41.685877) (xy 289.0901 -41.682783)
			(xy 289.072574 -41.685877) (xy 289.0647 -41.690036) (xy 289.03092 -41.709024) (xy 288.960669 -41.74174)
			(xy 288.887836 -41.768219) (xy 288.812977 -41.788261) (xy 288.736657 -41.801713) (xy 288.659456 -41.808474)
			(xy 288.620708 -41.808908) (xy 288.6202 -41.808908) (xy 288.577852 -41.808404) (xy 288.493538 -41.800353)
			(xy 288.410372 -41.784324) (xy 288.329105 -41.760463) (xy 288.250475 -41.728984) (xy 288.175194 -41.690173)
			(xy 288.103942 -41.644383) (xy 288.037366 -41.592027) (xy 287.976068 -41.533579) (xy 287.920603 -41.469569)
			(xy 287.871474 -41.400577) (xy 287.829125 -41.327227) (xy 287.793941 -41.250184) (xy 287.766239 -41.170145)
			(xy 287.746271 -41.087836) (xy 287.734218 -41.004001) (xy 287.730188 -40.9194) (xy 287.734218 -40.834799)
			(xy 287.746271 -40.750964) (xy 287.766239 -40.668655) (xy 287.793941 -40.588616) (xy 287.829125 -40.511573)
			(xy 287.871474 -40.438223) (xy 287.920603 -40.369231) (xy 287.976068 -40.305221) (xy 288.037366 -40.246773)
			(xy 288.103942 -40.194417) (xy 288.175194 -40.148627) (xy 288.250475 -40.109816) (xy 288.329105 -40.078337)
			(xy 288.410372 -40.054476) (xy 288.493538 -40.038447) (xy 288.577852 -40.030396) (xy 288.6202 -40.029892)
			(xy 288.620708 -40.029892) (xy 288.659455 -40.030325) (xy 288.736655 -40.037093) (xy 288.812972 -40.050551)
			(xy 288.88783 -40.070596) (xy 288.960661 -40.097077) (xy 289.030911 -40.129793) (xy 289.0647 -40.148764)
			(xy 289.072574 -40.152923) (xy 289.0901 -40.156017) (xy 289.107626 -40.152923) (xy 289.1155 -40.148764)
			(xy 289.151568 -40.129206) (xy 289.15965 -40.124578) (xy 289.172043 -40.110698) (xy 289.17864 -40.093299)
			(xy 289.179 -40.083994) (xy 289.179 -34.654998) (xy 289.178825 -34.648268) (xy 289.175343 -34.635267)
			(xy 289.172142 -34.629344) (xy 289.151149 -34.592254) (xy 289.11554 -34.514817) (xy 289.087499 -34.43433)
			(xy 289.067283 -34.35153) (xy 289.055077 -34.267177) (xy 289.050993 -34.182043) (xy 289.055069 -34.096909)
			(xy 289.067267 -34.012554) (xy 289.087475 -33.929753) (xy 289.115508 -33.849263) (xy 289.151109 -33.771823)
			(xy 289.172142 -33.734756) (xy 289.17531 -33.72882) (xy 289.178784 -33.715827) (xy 289.179 -33.709102)
			(xy 289.179 -32.076898) (xy 289.178825 -32.070168) (xy 289.175343 -32.057167) (xy 289.172142 -32.051244)
			(xy 289.151147 -32.014156) (xy 289.115536 -31.936723) (xy 289.087495 -31.856238) (xy 289.067281 -31.773441)
			(xy 289.05508 -31.689089) (xy 289.051003 -31.603957) (xy 289.055088 -31.518825) (xy 289.067297 -31.434475)
			(xy 289.087519 -31.351679) (xy 289.115568 -31.271197) (xy 289.151187 -31.193767) (xy 289.172142 -31.156656)
			(xy 289.175444 -31.150814) (xy 289.179 -31.138114) (xy 289.179 -31.072836) (xy 289.175444 -31.060136)
			(xy 289.172142 -31.054294) (xy 289.152865 -31.020316) (xy 289.119656 -30.9496) (xy 289.092777 -30.876243)
			(xy 289.072434 -30.800812) (xy 289.058784 -30.723888) (xy 289.051933 -30.646063) (xy 289.051492 -30.607)
			(xy 289.051492 -30.606492) (xy 289.051978 -30.565131) (xy 289.059682 -30.482769) (xy 289.074994 -30.401476)
			(xy 289.097783 -30.321955) (xy 289.127852 -30.244892) (xy 289.14598 -30.207712) (xy 289.153346 -30.19298)
			(xy 289.148266 -30.160722) (xy 289.10153 -30.113986) (xy 289.094132 -30.107141) (xy 289.075533 -30.099419)
			(xy 289.065462 -30.099) (xy 284.584394 -30.099) (xy 284.574324 -30.099424) (xy 284.555721 -30.10714)
			(xy 284.548326 -30.113986) (xy 284.367986 -30.294326) (xy 284.361134 -30.301722) (xy 284.353396 -30.320321)
			(xy 284.353 -30.330394) (xy 284.353 -34.18967) (xy 284.353535 -34.200691) (xy 284.362746 -34.220716)
			(xy 284.37078 -34.228278) (xy 284.429962 -34.27857) (xy 284.438663 -34.285208) (xy 284.459714 -34.291116)
			(xy 284.470602 -34.29) (xy 284.470856 -34.29) (xy 284.506167 -34.28458) (xy 284.577374 -34.278732)
			(xy 284.613096 -34.278316) (xy 284.65514 -34.278818) (xy 284.73885 -34.286772) (xy 284.821437 -34.302583)
			(xy 284.902167 -34.326109) (xy 284.980319 -34.35714) (xy 285.017972 -34.375852) (xy 285.018226 -34.375852)
			(xy 285.028629 -34.380646) (xy 285.051503 -34.381302) (xy 285.062168 -34.377122) (xy 285.144718 -34.339784)
			(xy 285.159704 -34.322512) (xy 285.162498 -34.311336) (xy 285.173563 -34.271061) (xy 285.202252 -34.192612)
			(xy 285.238166 -34.117196) (xy 285.280989 -34.045478) (xy 285.330344 -33.978089) (xy 285.385798 -33.915621)
			(xy 285.446861 -33.858625) (xy 285.512997 -33.807602) (xy 285.583623 -33.763002) (xy 285.658118 -33.725216)
			(xy 285.735826 -33.694577) (xy 285.816063 -33.671355) (xy 285.898124 -33.655755) (xy 285.981285 -33.647913)
			(xy 286.02305 -33.64738) (xy 286.065365 -33.64788) (xy 286.149612 -33.655914) (xy 286.232715 -33.671914)
			(xy 286.313923 -33.695736) (xy 286.3925 -33.727165) (xy 286.467737 -33.765915) (xy 286.503618 -33.78835)
			(xy 286.512125 -33.793327) (xy 286.531465 -33.797019) (xy 286.550767 -33.793127) (xy 286.559244 -33.788096)
			(xy 286.595761 -33.764442) (xy 286.672571 -33.723562) (xy 286.753006 -33.690379) (xy 286.836298 -33.665212)
			(xy 286.921649 -33.6483) (xy 287.008245 -33.639806) (xy 287.05175 -33.639252) (xy 287.094103 -33.639738)
			(xy 287.178425 -33.647785) (xy 287.2616 -33.663812) (xy 287.342875 -33.687672) (xy 287.421515 -33.719151)
			(xy 287.496805 -33.757962) (xy 287.568065 -33.803754) (xy 287.63465 -33.856114) (xy 287.695956 -33.914565)
			(xy 287.751428 -33.97858) (xy 287.800563 -34.047578) (xy 287.842917 -34.120934) (xy 287.878106 -34.197984)
			(xy 287.905811 -34.27803) (xy 287.925782 -34.360348) (xy 287.937837 -34.444191) (xy 287.941868 -34.5288)
			(xy 287.937837 -34.613409) (xy 287.925782 -34.697252) (xy 287.905811 -34.77957) (xy 287.878106 -34.859616)
			(xy 287.842917 -34.936666) (xy 287.800563 -35.010022) (xy 287.751428 -35.07902) (xy 287.695956 -35.143035)
			(xy 287.63465 -35.201486) (xy 287.568065 -35.253846) (xy 287.496805 -35.299638) (xy 287.421515 -35.338449)
			(xy 287.342875 -35.369928) (xy 287.2616 -35.393788) (xy 287.178425 -35.409815) (xy 287.094103 -35.417862)
			(xy 287.05175 -35.418268) (xy 287.051242 -35.418268) (xy 287.008976 -35.417769) (xy 286.924824 -35.409749)
			(xy 286.841814 -35.393776) (xy 286.760695 -35.369995) (xy 286.6822 -35.33862) (xy 286.607038 -35.299936)
			(xy 286.571182 -35.277552) (xy 286.562676 -35.272574) (xy 286.543335 -35.268883) (xy 286.524033 -35.272775)
			(xy 286.515556 -35.277806) (xy 286.479046 -35.301484) (xy 286.402247 -35.342412) (xy 286.321816 -35.375642)
			(xy 286.238524 -35.400855) (xy 286.153167 -35.417811) (xy 286.066562 -35.426347) (xy 286.02305 -35.426904)
			(xy 285.981007 -35.4264) (xy 285.897298 -35.418441) (xy 285.814713 -35.402626) (xy 285.733986 -35.379096)
			(xy 285.655836 -35.348061) (xy 285.618174 -35.329368) (xy 285.61792 -35.329368) (xy 285.607516 -35.324569)
			(xy 285.584635 -35.323895) (xy 285.573978 -35.328098) (xy 285.491428 -35.365436) (xy 285.476442 -35.382708)
			(xy 285.473648 -35.393884) (xy 285.461341 -35.438467) (xy 285.428708 -35.525013) (xy 285.387264 -35.607701)
			(xy 285.337455 -35.685638) (xy 285.279821 -35.75798) (xy 285.247842 -35.791394) (xy 285.240205 -35.800029)
			(xy 285.232704 -35.821793) (xy 285.233364 -35.833304) (xy 285.243016 -35.91179) (xy 285.244828 -35.923068)
			(xy 285.256987 -35.942381) (xy 285.266384 -35.948874) (xy 285.300812 -35.97098) (xy 285.365882 -36.020586)
			(xy 285.426123 -36.075957) (xy 285.481025 -36.136625) (xy 285.530125 -36.202078) (xy 285.573009 -36.271762)
			(xy 285.609313 -36.345089) (xy 285.638731 -36.42144) (xy 285.661015 -36.500169) (xy 285.675977 -36.580612)
			(xy 285.683489 -36.662089) (xy 285.68396 -36.703) (xy 285.6835 -36.744102) (xy 285.675915 -36.825956)
			(xy 285.660809 -36.906761) (xy 285.638312 -36.985828) (xy 285.608615 -37.062481) (xy 285.571972 -37.136067)
			(xy 285.528696 -37.205958) (xy 285.479155 -37.271558) (xy 285.423772 -37.332306) (xy 285.363021 -37.387686)
			(xy 285.297418 -37.437223) (xy 285.227525 -37.480496) (xy 285.153937 -37.517135) (xy 285.077282 -37.546827)
			(xy 284.998215 -37.56932) (xy 284.917409 -37.584421) (xy 284.835554 -37.592002) (xy 284.794452 -37.592508)
			(xy 284.793944 -37.592508) (xy 284.755081 -37.592084) (xy 284.677654 -37.585281) (xy 284.601115 -37.571748)
			(xy 284.526049 -37.551589) (xy 284.489398 -37.53866) (xy 284.477714 -37.534342) (xy 284.453076 -37.537644)
			(xy 284.37459 -37.592508) (xy 284.364959 -37.600129) (xy 284.353681 -37.621901) (xy 284.353 -37.634164)
			(xy 284.353 -38.889686) (xy 284.353572 -38.900129) (xy 284.361975 -38.919259) (xy 284.369256 -38.92677)
			(xy 284.431994 -38.984936) (xy 284.451806 -38.991794) (xy 284.462474 -38.991032) (xy 284.479529 -38.989818)
			(xy 284.513702 -38.988547) (xy 284.5308 -38.988492) (xy 284.573148 -38.988996) (xy 284.657462 -38.997047)
			(xy 284.740628 -39.013076) (xy 284.821895 -39.036937) (xy 284.900525 -39.068416) (xy 284.975806 -39.107227)
			(xy 285.047058 -39.153017) (xy 285.113634 -39.205373) (xy 285.174932 -39.263821) (xy 285.230397 -39.327831)
			(xy 285.279526 -39.396823) (xy 285.321875 -39.470173) (xy 285.357059 -39.547216) (xy 285.384761 -39.627255)
			(xy 285.404729 -39.709564) (xy 285.416782 -39.793399) (xy 285.420813 -39.878) (xy 285.418795 -39.920361)
			(xy 285.876742 -39.920361) (xy 285.876742 -39.835639) (xy 285.884795 -39.751302) (xy 285.900829 -39.668112)
			(xy 285.924697 -39.586822) (xy 285.956185 -39.50817) (xy 285.995007 -39.432867) (xy 286.04081 -39.361595)
			(xy 286.093181 -39.294999) (xy 286.151646 -39.233684) (xy 286.215674 -39.178203) (xy 286.284686 -39.12906)
			(xy 286.358056 -39.0867) (xy 286.435121 -39.051505) (xy 286.515183 -39.023796) (xy 286.597516 -39.003822)
			(xy 286.681375 -38.991765) (xy 286.766 -38.987734) (xy 286.850625 -38.991765) (xy 286.934484 -39.003822)
			(xy 287.016817 -39.023796) (xy 287.096879 -39.051505) (xy 287.173944 -39.0867) (xy 287.247314 -39.12906)
			(xy 287.316326 -39.178203) (xy 287.380354 -39.233684) (xy 287.438819 -39.294999) (xy 287.49119 -39.361595)
			(xy 287.536993 -39.432867) (xy 287.575815 -39.50817) (xy 287.607303 -39.586822) (xy 287.631171 -39.668112)
			(xy 287.647205 -39.751302) (xy 287.655258 -39.835639) (xy 287.655762 -39.878) (xy 287.655258 -39.920361)
			(xy 287.647205 -40.004698) (xy 287.631171 -40.087888) (xy 287.607303 -40.169178) (xy 287.575815 -40.24783)
			(xy 287.536993 -40.323133) (xy 287.49119 -40.394405) (xy 287.438819 -40.461001) (xy 287.380354 -40.522316)
			(xy 287.316326 -40.577797) (xy 287.247314 -40.62694) (xy 287.173944 -40.6693) (xy 287.096879 -40.704495)
			(xy 287.016817 -40.732204) (xy 286.934484 -40.752178) (xy 286.850625 -40.764235) (xy 286.766 -40.768267)
			(xy 286.681375 -40.764235) (xy 286.597516 -40.752178) (xy 286.515183 -40.732204) (xy 286.435121 -40.704495)
			(xy 286.358056 -40.6693) (xy 286.284686 -40.62694) (xy 286.215674 -40.577797) (xy 286.151646 -40.522316)
			(xy 286.093181 -40.461001) (xy 286.04081 -40.394405) (xy 285.995007 -40.323133) (xy 285.956185 -40.24783)
			(xy 285.924697 -40.169178) (xy 285.900829 -40.087888) (xy 285.884795 -40.004698) (xy 285.876742 -39.920361)
			(xy 285.418795 -39.920361) (xy 285.416782 -39.962601) (xy 285.404729 -40.046436) (xy 285.384761 -40.128745)
			(xy 285.357059 -40.208784) (xy 285.321875 -40.285827) (xy 285.279526 -40.359177) (xy 285.230397 -40.428169)
			(xy 285.174932 -40.492179) (xy 285.113634 -40.550627) (xy 285.047058 -40.602983) (xy 284.975806 -40.648773)
			(xy 284.900525 -40.687584) (xy 284.821895 -40.719063) (xy 284.740628 -40.742924) (xy 284.657462 -40.758953)
			(xy 284.573148 -40.767004) (xy 284.5308 -40.767508) (xy 284.489377 -40.767033) (xy 284.406888 -40.75933)
			(xy 284.325474 -40.743992) (xy 284.245838 -40.72115) (xy 284.168671 -40.691003) (xy 284.094641 -40.653812)
			(xy 284.02439 -40.609899) (xy 283.958525 -40.559644) (xy 283.897619 -40.503484) (xy 283.842198 -40.441904)
			(xy 283.792742 -40.375438) (xy 283.770832 -40.34028) (xy 283.770832 -40.340026) (xy 283.764335 -40.330473)
			(xy 283.744891 -40.31804) (xy 283.733494 -40.31615) (xy 283.654246 -40.306752) (xy 283.642654 -40.305866)
			(xy 283.620696 -40.313421) (xy 283.612082 -40.32123) (xy 282.93822 -40.995092) (xy 282.932077 -41.001786)
			(xy 282.924549 -41.018307) (xy 282.923242 -41.036416) (xy 282.928319 -41.053847) (xy 282.933394 -41.061386)
			(xy 282.963493 -41.103054) (xy 283.014931 -41.192051) (xy 283.03601 -41.238932) (xy 283.040362 -41.247999)
			(xy 283.054765 -41.262014) (xy 283.06395 -41.26611) (xy 283.104068 -41.282646) (xy 283.181181 -41.322447)
			(xy 283.25405 -41.36957) (xy 283.321982 -41.423567) (xy 283.384331 -41.483925) (xy 283.440505 -41.550069)
			(xy 283.489968 -41.62137) (xy 283.53225 -41.69715) (xy 283.56695 -41.776689) (xy 283.58084 -41.817798)
			(xy 283.584278 -41.826907) (xy 283.596767 -41.841824) (xy 283.613899 -41.851044) (xy 283.623512 -41.852596)
			(xy 283.71546 -41.86301) (xy 283.72525 -41.863635) (xy 283.744116 -41.858321) (xy 283.759622 -41.846332)
			(xy 283.76499 -41.838118) (xy 283.786751 -41.802287) (xy 283.836041 -41.73447) (xy 283.891492 -41.671592)
			(xy 283.952614 -41.614209) (xy 284.018863 -41.562832) (xy 284.089652 -41.517916) (xy 284.164353 -41.479859)
			(xy 284.242304 -41.448999) (xy 284.322812 -41.42561) (xy 284.405163 -41.409899) (xy 284.488628 -41.402006)
			(xy 284.530546 -41.401492) (xy 284.5308 -41.401492) (xy 284.573148 -41.401996) (xy 284.657462 -41.410047)
			(xy 284.740628 -41.426076) (xy 284.821895 -41.449937) (xy 284.900525 -41.481416) (xy 284.975806 -41.520227)
			(xy 285.047058 -41.566017) (xy 285.113634 -41.618373) (xy 285.174932 -41.676821) (xy 285.230397 -41.740831)
			(xy 285.279526 -41.809823) (xy 285.321875 -41.883173) (xy 285.357059 -41.960216) (xy 285.384761 -42.040255)
			(xy 285.404729 -42.122564) (xy 285.416782 -42.206399) (xy 285.420813 -42.291) (xy 285.418795 -42.333361)
			(xy 285.876742 -42.333361) (xy 285.876742 -42.248639) (xy 285.884795 -42.164302) (xy 285.900829 -42.081112)
			(xy 285.924697 -41.999822) (xy 285.956185 -41.92117) (xy 285.995007 -41.845867) (xy 286.04081 -41.774595)
			(xy 286.093181 -41.707999) (xy 286.151646 -41.646684) (xy 286.215674 -41.591203) (xy 286.284686 -41.54206)
			(xy 286.358056 -41.4997) (xy 286.435121 -41.464505) (xy 286.515183 -41.436796) (xy 286.597516 -41.416822)
			(xy 286.681375 -41.404765) (xy 286.766 -41.400734) (xy 286.850625 -41.404765) (xy 286.934484 -41.416822)
			(xy 287.016817 -41.436796) (xy 287.096879 -41.464505) (xy 287.173944 -41.4997) (xy 287.247314 -41.54206)
			(xy 287.316326 -41.591203) (xy 287.380354 -41.646684) (xy 287.438819 -41.707999) (xy 287.49119 -41.774595)
			(xy 287.536993 -41.845867) (xy 287.575815 -41.92117) (xy 287.607303 -41.999822) (xy 287.631171 -42.081112)
			(xy 287.647205 -42.164302) (xy 287.655258 -42.248639) (xy 287.655762 -42.291) (xy 287.655258 -42.333361)
			(xy 287.647205 -42.417698) (xy 287.631171 -42.500888) (xy 287.607303 -42.582178) (xy 287.575815 -42.66083)
			(xy 287.536993 -42.736133) (xy 287.49119 -42.807405) (xy 287.438819 -42.874001) (xy 287.380354 -42.935316)
			(xy 287.316326 -42.990797) (xy 287.247314 -43.03994) (xy 287.173944 -43.0823) (xy 287.096879 -43.117495)
			(xy 287.016817 -43.145204) (xy 286.934484 -43.165178) (xy 286.850625 -43.177235) (xy 286.766 -43.181267)
			(xy 286.681375 -43.177235) (xy 286.597516 -43.165178) (xy 286.515183 -43.145204) (xy 286.435121 -43.117495)
			(xy 286.358056 -43.0823) (xy 286.284686 -43.03994) (xy 286.215674 -42.990797) (xy 286.151646 -42.935316)
			(xy 286.093181 -42.874001) (xy 286.04081 -42.807405) (xy 285.995007 -42.736133) (xy 285.956185 -42.66083)
			(xy 285.924697 -42.582178) (xy 285.900829 -42.500888) (xy 285.884795 -42.417698) (xy 285.876742 -42.333361)
			(xy 285.418795 -42.333361) (xy 285.416782 -42.375601) (xy 285.404729 -42.459436) (xy 285.384761 -42.541745)
			(xy 285.357059 -42.621784) (xy 285.321875 -42.698827) (xy 285.279526 -42.772177) (xy 285.230397 -42.841169)
			(xy 285.174932 -42.905179) (xy 285.113634 -42.963627) (xy 285.047058 -43.015983) (xy 284.975806 -43.061773)
			(xy 284.900525 -43.100584) (xy 284.821895 -43.132063) (xy 284.740628 -43.155924) (xy 284.657462 -43.171953)
			(xy 284.573148 -43.180004) (xy 284.5308 -43.180508) (xy 284.487797 -43.179984) (xy 284.402194 -43.171675)
			(xy 284.317792 -43.155144) (xy 284.235379 -43.130546) (xy 284.155724 -43.09811) (xy 284.079571 -43.058139)
			(xy 284.007631 -43.011005) (xy 283.940575 -42.95715) (xy 283.879028 -42.897075) (xy 283.823566 -42.831341)
			(xy 283.774706 -42.760562) (xy 283.732904 -42.685399) (xy 283.69855 -42.606552) (xy 283.684726 -42.565828)
			(xy 283.681294 -42.556709) (xy 283.668812 -42.541769) (xy 283.65168 -42.532523) (xy 283.642054 -42.53103)
			(xy 283.550106 -42.520616) (xy 283.540308 -42.519978) (xy 283.521417 -42.525271) (xy 283.505877 -42.537245)
			(xy 283.500576 -42.545508) (xy 283.478757 -42.581444) (xy 283.429319 -42.64945) (xy 283.373681 -42.712484)
			(xy 283.34335 -42.741596) (xy 283.335729 -42.749475) (xy 283.327452 -42.769749) (xy 283.327348 -42.780712)
			(xy 283.330396 -42.857674) (xy 283.331355 -42.868564) (xy 283.341244 -42.888036) (xy 283.349446 -42.895266)
			(xy 283.38386 -42.923345) (xy 283.447497 -42.985314) (xy 283.50464 -43.053317) (xy 283.554721 -43.126677)
			(xy 283.59724 -43.204664) (xy 283.631775 -43.2865) (xy 283.65798 -43.371371) (xy 283.675596 -43.458431)
			(xy 283.684447 -43.546814) (xy 283.68498 -43.591226) (xy 283.684504 -43.632332) (xy 283.676918 -43.714194)
			(xy 283.667571 -43.7642) (xy 287.730188 -43.7642) (xy 287.734218 -43.679599) (xy 287.746271 -43.595764)
			(xy 287.766239 -43.513455) (xy 287.793941 -43.433416) (xy 287.829125 -43.356373) (xy 287.871474 -43.283023)
			(xy 287.920603 -43.214031) (xy 287.976068 -43.150021) (xy 288.037366 -43.091573) (xy 288.103942 -43.039217)
			(xy 288.175194 -42.993427) (xy 288.250475 -42.954616) (xy 288.329105 -42.923137) (xy 288.410372 -42.899276)
			(xy 288.493538 -42.883247) (xy 288.577852 -42.875196) (xy 288.6202 -42.874692) (xy 288.620708 -42.874692)
			(xy 288.659456 -42.875126) (xy 288.736657 -42.881887) (xy 288.812977 -42.895339) (xy 288.887836 -42.915381)
			(xy 288.960669 -42.94186) (xy 289.03092 -42.974576) (xy 289.0647 -42.993564) (xy 289.072574 -42.997723)
			(xy 289.0901 -43.000817) (xy 289.107626 -42.997723) (xy 289.1155 -42.993564) (xy 289.149289 -42.974593)
			(xy 289.219539 -42.941877) (xy 289.29237 -42.915396) (xy 289.367228 -42.895351) (xy 289.443545 -42.881893)
			(xy 289.520745 -42.875125) (xy 289.559492 -42.874692) (xy 289.56 -42.874692) (xy 289.602348 -42.875196)
			(xy 289.686662 -42.883247) (xy 289.769828 -42.899276) (xy 289.851095 -42.923137) (xy 289.929725 -42.954616)
			(xy 290.005006 -42.993427) (xy 290.076258 -43.039217) (xy 290.142834 -43.091573) (xy 290.204132 -43.150021)
			(xy 290.259597 -43.214031) (xy 290.308726 -43.283023) (xy 290.351075 -43.356373) (xy 290.386259 -43.433416)
			(xy 290.413961 -43.513455) (xy 290.433929 -43.595764) (xy 290.445982 -43.679599) (xy 290.450013 -43.7642)
			(xy 290.445982 -43.848801) (xy 290.433929 -43.932636) (xy 290.413961 -44.014945) (xy 290.386259 -44.094984)
			(xy 290.351075 -44.172027) (xy 290.308726 -44.245377) (xy 290.259597 -44.314369) (xy 290.204132 -44.378379)
			(xy 290.142834 -44.436827) (xy 290.076258 -44.489183) (xy 290.005006 -44.534973) (xy 289.929725 -44.573784)
			(xy 289.851095 -44.605263) (xy 289.769828 -44.629124) (xy 289.686662 -44.645153) (xy 289.602348 -44.653204)
			(xy 289.56 -44.653708) (xy 289.559492 -44.653708) (xy 289.520744 -44.653274) (xy 289.443543 -44.646513)
			(xy 289.367223 -44.633061) (xy 289.292364 -44.613019) (xy 289.219531 -44.58654) (xy 289.14928 -44.553824)
			(xy 289.1155 -44.534836) (xy 289.107626 -44.530677) (xy 289.0901 -44.527583) (xy 289.072574 -44.530677)
			(xy 289.0647 -44.534836) (xy 289.030911 -44.553807) (xy 288.960661 -44.586523) (xy 288.88783 -44.613004)
			(xy 288.812972 -44.633049) (xy 288.736655 -44.646507) (xy 288.659455 -44.653275) (xy 288.620708 -44.653708)
			(xy 288.6202 -44.653708) (xy 288.577852 -44.653204) (xy 288.493538 -44.645153) (xy 288.410372 -44.629124)
			(xy 288.329105 -44.605263) (xy 288.250475 -44.573784) (xy 288.175194 -44.534973) (xy 288.103942 -44.489183)
			(xy 288.037366 -44.436827) (xy 287.976068 -44.378379) (xy 287.920603 -44.314369) (xy 287.871474 -44.245377)
			(xy 287.829125 -44.172027) (xy 287.793941 -44.094984) (xy 287.766239 -44.014945) (xy 287.746271 -43.932636)
			(xy 287.734218 -43.848801) (xy 287.730188 -43.7642) (xy 283.667571 -43.7642) (xy 283.661812 -43.795007)
			(xy 283.639316 -43.874082) (xy 283.609621 -43.950744) (xy 283.572981 -44.024341) (xy 283.529708 -44.094243)
			(xy 283.480171 -44.159855) (xy 283.424792 -44.220618) (xy 283.364045 -44.276014) (xy 283.298446 -44.325569)
			(xy 283.228556 -44.368861) (xy 283.154969 -44.405522) (xy 283.078315 -44.435238) (xy 282.999247 -44.457756)
			(xy 282.918438 -44.472884) (xy 282.836578 -44.480493) (xy 282.795472 -44.480988) (xy 282.751643 -44.480455)
			(xy 282.664412 -44.471817) (xy 282.578454 -44.454637) (xy 282.494603 -44.429082) (xy 282.413675 -44.3954)
			(xy 282.336453 -44.353918) (xy 282.263688 -44.305039) (xy 282.22956 -44.277534) (xy 282.229052 -44.277026)
			(xy 282.221408 -44.271344) (xy 282.203266 -44.265589) (xy 282.193746 -44.26585) (xy 282.113736 -44.271438)
			(xy 282.095956 -44.280074) (xy 282.089606 -44.287186) (xy 282.061564 -44.317242) (xy 282.000814 -44.372627)
			(xy 281.935214 -44.42217) (xy 281.865323 -44.465451) (xy 281.791737 -44.5021) (xy 281.715084 -44.531804)
			(xy 281.636018 -44.554311) (xy 281.555213 -44.569427) (xy 281.473357 -44.577025) (xy 281.432254 -44.577508)
			(xy 281.432 -44.577508) (xy 281.390898 -44.577033) (xy 281.309043 -44.569448) (xy 281.228238 -44.554343)
			(xy 281.149171 -44.531847) (xy 281.072517 -44.502151) (xy 280.99893 -44.465509) (xy 280.929038 -44.422234)
			(xy 280.863437 -44.372694) (xy 280.802687 -44.317313) (xy 280.747306 -44.256563) (xy 280.697766 -44.190962)
			(xy 280.654491 -44.12107) (xy 280.617849 -44.047483) (xy 280.588153 -43.970829) (xy 280.565657 -43.891762)
			(xy 280.550552 -43.810957) (xy 280.542967 -43.729102) (xy 280.542492 -43.688) (xy 280.542492 -43.687492)
			(xy 280.542981 -43.646377) (xy 280.550597 -43.5645) (xy 280.565734 -43.483674) (xy 280.588264 -43.40459)
			(xy 280.617995 -43.327922) (xy 280.654673 -43.254325) (xy 280.697986 -43.184425) (xy 280.747562 -43.11882)
			(xy 280.802981 -43.058069) (xy 280.863768 -43.00269) (xy 280.896314 -42.977562) (xy 280.903869 -42.97136)
			(xy 280.913942 -42.954631) (xy 280.915872 -42.94505) (xy 280.920698 -42.914824) (xy 280.921785 -42.905078)
			(xy 280.917356 -42.885993) (xy 280.912062 -42.87774) (xy 280.886504 -42.840299) (xy 280.84228 -42.761159)
			(xy 280.806328 -42.677935) (xy 280.77902 -42.591487) (xy 280.760639 -42.502712) (xy 280.751375 -42.412529)
			(xy 280.750772 -42.3672) (xy 280.751297 -42.323383) (xy 280.759913 -42.236174) (xy 280.777061 -42.150234)
			(xy 280.802575 -42.066396) (xy 280.836208 -41.985473) (xy 280.877634 -41.908249) (xy 280.926451 -41.835472)
			(xy 280.982187 -41.767846) (xy 281.044301 -41.706028) (xy 281.112193 -41.650616) (xy 281.185203 -41.602147)
			(xy 281.262624 -41.561091) (xy 281.302968 -41.543986) (xy 281.311316 -41.540141) (xy 281.324759 -41.527627)
			(xy 281.332923 -41.511176) (xy 281.33421 -41.502076) (xy 281.339544 -41.46042) (xy 281.340052 -41.45661)
			(xy 281.340052 -41.4528) (xy 281.339632 -41.442782) (xy 281.33196 -41.424274) (xy 281.317786 -41.410113)
			(xy 281.29927 -41.402459) (xy 281.289252 -41.402) (xy 277.397972 -41.402) (xy 277.396448 -41.402)
			(xy 277.368 -41.402508) (xy 277.339552 -41.402) (xy 276.702774 -41.402) (xy 276.691758 -41.402546)
			(xy 276.671751 -41.411771) (xy 276.664166 -41.41978) (xy 276.606762 -41.48709) (xy 276.600666 -41.508172)
			(xy 276.602444 -41.519094) (xy 276.607429 -41.553101) (xy 276.612772 -41.621631) (xy 276.613112 -41.656)
			(xy 276.612574 -41.699794) (xy 276.603944 -41.786957) (xy 276.586795 -41.872851) (xy 276.561295 -41.956645)
			(xy 276.52769 -42.037531) (xy 276.507448 -42.07637) (xy 276.502027 -42.087836) (xy 276.502027 -42.113164)
			(xy 276.507448 -42.12463) (xy 276.527694 -42.163469) (xy 276.561322 -42.244348) (xy 276.586835 -42.328142)
			(xy 276.603985 -42.414038) (xy 276.612607 -42.501204) (xy 276.613112 -42.545) (xy 276.612574 -42.588794)
			(xy 276.603944 -42.675957) (xy 276.586795 -42.761851) (xy 276.561295 -42.845645) (xy 276.52769 -42.926531)
			(xy 276.507448 -42.96537) (xy 276.502027 -42.976836) (xy 276.502027 -43.002164) (xy 276.507448 -43.01363)
			(xy 276.527694 -43.052469) (xy 276.561322 -43.133348) (xy 276.586835 -43.217142) (xy 276.603985 -43.303038)
			(xy 276.612607 -43.390204) (xy 276.613112 -43.434) (xy 276.612574 -43.477794) (xy 276.603944 -43.564957)
			(xy 276.586795 -43.650851) (xy 276.561295 -43.734645) (xy 276.52769 -43.815531) (xy 276.507448 -43.85437)
			(xy 276.502027 -43.865836) (xy 276.502027 -43.891164) (xy 276.507448 -43.90263) (xy 276.527694 -43.941469)
			(xy 276.561322 -44.022348) (xy 276.586835 -44.106142) (xy 276.603985 -44.192038) (xy 276.612607 -44.279204)
			(xy 276.613112 -44.323) (xy 276.612608 -44.365361) (xy 276.604555 -44.449698) (xy 276.588521 -44.532888)
			(xy 276.564653 -44.614178) (xy 276.533165 -44.69283) (xy 276.494343 -44.768133) (xy 276.44854 -44.839405)
			(xy 276.396169 -44.906001) (xy 276.337704 -44.967316) (xy 276.273676 -45.022797) (xy 276.204664 -45.07194)
			(xy 276.131294 -45.1143) (xy 276.054229 -45.149495) (xy 275.974167 -45.177204) (xy 275.891834 -45.197178)
			(xy 275.807975 -45.209235) (xy 275.72335 -45.213267) (xy 275.638725 -45.209235) (xy 275.554866 -45.197178)
			(xy 275.472533 -45.177204) (xy 275.392471 -45.149495) (xy 275.315406 -45.1143) (xy 275.242036 -45.07194)
			(xy 275.173024 -45.022797) (xy 275.108996 -44.967316) (xy 275.050531 -44.906001) (xy 274.99816 -44.839405)
			(xy 274.952357 -44.768133) (xy 274.913535 -44.69283) (xy 274.882047 -44.614178) (xy 274.858179 -44.532888)
			(xy 274.842145 -44.449698) (xy 274.834092 -44.365361) (xy 274.833588 -44.323) (xy 274.834126 -44.279206)
			(xy 274.842756 -44.192043) (xy 274.859905 -44.106149) (xy 274.885405 -44.022355) (xy 274.91901 -43.941469)
			(xy 274.939252 -43.90263) (xy 274.944673 -43.891164) (xy 274.944673 -43.865836) (xy 274.939252 -43.85437)
			(xy 274.919006 -43.815531) (xy 274.885378 -43.734652) (xy 274.859865 -43.650858) (xy 274.842715 -43.564962)
			(xy 274.834093 -43.477796) (xy 274.833588 -43.434) (xy 274.834126 -43.390206) (xy 274.842756 -43.303043)
			(xy 274.859905 -43.217149) (xy 274.885405 -43.133355) (xy 274.91901 -43.052469) (xy 274.939252 -43.01363)
			(xy 274.944673 -43.002164) (xy 274.944673 -42.976836) (xy 274.939252 -42.96537) (xy 274.919006 -42.926531)
			(xy 274.885378 -42.845652) (xy 274.859865 -42.761858) (xy 274.842715 -42.675962) (xy 274.834093 -42.588796)
			(xy 274.833588 -42.545) (xy 274.834126 -42.501206) (xy 274.842756 -42.414043) (xy 274.859905 -42.328149)
			(xy 274.885405 -42.244355) (xy 274.91901 -42.163469) (xy 274.939252 -42.12463) (xy 274.944673 -42.113164)
			(xy 274.944673 -42.087836) (xy 274.939252 -42.07637) (xy 274.919006 -42.037531) (xy 274.885378 -41.956652)
			(xy 274.859865 -41.872858) (xy 274.842715 -41.786962) (xy 274.834093 -41.699796) (xy 274.833588 -41.656)
			(xy 274.833935 -41.621631) (xy 274.839272 -41.553101) (xy 274.844256 -41.519094) (xy 274.846034 -41.508172)
			(xy 274.839938 -41.48709) (xy 274.782534 -41.41978) (xy 274.774963 -41.411753) (xy 274.754947 -41.402523)
			(xy 274.743926 -41.402) (xy 274.297394 -41.402) (xy 274.287324 -41.402424) (xy 274.268721 -41.41014)
			(xy 274.261326 -41.416986) (xy 272.302986 -43.375326) (xy 272.296134 -43.382722) (xy 272.288396 -43.401321)
			(xy 272.288 -43.411394) (xy 272.288 -44.499276) (xy 272.288456 -44.509115) (xy 272.295883 -44.527336)
			(xy 272.309646 -44.5414) (xy 272.31848 -44.545758) (xy 272.357607 -44.563444) (xy 272.43259 -44.60529)
			(xy 272.503192 -44.654169) (xy 272.568754 -44.709624) (xy 272.628667 -44.771139) (xy 272.682372 -44.838143)
			(xy 272.72937 -44.91001) (xy 272.769223 -44.986072) (xy 272.80156 -45.065621) (xy 272.82608 -45.147915)
			(xy 272.842555 -45.23219) (xy 272.850831 -45.317661) (xy 272.850831 -45.403531) (xy 272.842556 -45.489002)
			(xy 272.826082 -45.573277) (xy 272.807585 -45.635361) (xy 276.992838 -45.635361) (xy 276.992838 -45.550639)
			(xy 277.000891 -45.466302) (xy 277.016925 -45.383112) (xy 277.040793 -45.301822) (xy 277.072281 -45.22317)
			(xy 277.111103 -45.147867) (xy 277.156906 -45.076595) (xy 277.209277 -45.009999) (xy 277.267742 -44.948684)
			(xy 277.33177 -44.893203) (xy 277.400782 -44.84406) (xy 277.474152 -44.8017) (xy 277.551217 -44.766505)
			(xy 277.631279 -44.738796) (xy 277.713612 -44.718822) (xy 277.797471 -44.706765) (xy 277.882096 -44.702734)
			(xy 277.966721 -44.706765) (xy 278.05058 -44.718822) (xy 278.132913 -44.738796) (xy 278.212975 -44.766505)
			(xy 278.29004 -44.8017) (xy 278.36341 -44.84406) (xy 278.404558 -44.873361) (xy 283.641542 -44.873361)
			(xy 283.641542 -44.788639) (xy 283.649595 -44.704302) (xy 283.665629 -44.621112) (xy 283.689497 -44.539822)
			(xy 283.720985 -44.46117) (xy 283.759807 -44.385867) (xy 283.80561 -44.314595) (xy 283.857981 -44.247999)
			(xy 283.916446 -44.186684) (xy 283.980474 -44.131203) (xy 284.049486 -44.08206) (xy 284.122856 -44.0397)
			(xy 284.199921 -44.004505) (xy 284.279983 -43.976796) (xy 284.362316 -43.956822) (xy 284.446175 -43.944765)
			(xy 284.5308 -43.940734) (xy 284.615425 -43.944765) (xy 284.699284 -43.956822) (xy 284.781617 -43.976796)
			(xy 284.861679 -44.004505) (xy 284.938744 -44.0397) (xy 285.012114 -44.08206) (xy 285.081126 -44.131203)
			(xy 285.145154 -44.186684) (xy 285.203619 -44.247999) (xy 285.25599 -44.314595) (xy 285.301793 -44.385867)
			(xy 285.340615 -44.46117) (xy 285.372103 -44.539822) (xy 285.395971 -44.621112) (xy 285.412005 -44.704302)
			(xy 285.420058 -44.788639) (xy 285.420562 -44.831) (xy 285.420058 -44.873361) (xy 285.876742 -44.873361)
			(xy 285.876742 -44.788639) (xy 285.884795 -44.704302) (xy 285.900829 -44.621112) (xy 285.924697 -44.539822)
			(xy 285.956185 -44.46117) (xy 285.995007 -44.385867) (xy 286.04081 -44.314595) (xy 286.093181 -44.247999)
			(xy 286.151646 -44.186684) (xy 286.215674 -44.131203) (xy 286.284686 -44.08206) (xy 286.358056 -44.0397)
			(xy 286.435121 -44.004505) (xy 286.515183 -43.976796) (xy 286.597516 -43.956822) (xy 286.681375 -43.944765)
			(xy 286.766 -43.940734) (xy 286.850625 -43.944765) (xy 286.934484 -43.956822) (xy 287.016817 -43.976796)
			(xy 287.096879 -44.004505) (xy 287.173944 -44.0397) (xy 287.247314 -44.08206) (xy 287.316326 -44.131203)
			(xy 287.380354 -44.186684) (xy 287.438819 -44.247999) (xy 287.49119 -44.314595) (xy 287.536993 -44.385867)
			(xy 287.575815 -44.46117) (xy 287.607303 -44.539822) (xy 287.631171 -44.621112) (xy 287.647205 -44.704302)
			(xy 287.655258 -44.788639) (xy 287.655762 -44.831) (xy 287.655258 -44.873361) (xy 287.647205 -44.957698)
			(xy 287.631171 -45.040888) (xy 287.607303 -45.122178) (xy 287.575815 -45.20083) (xy 287.536993 -45.276133)
			(xy 287.49119 -45.347405) (xy 287.438819 -45.414001) (xy 287.380354 -45.475316) (xy 287.316326 -45.530797)
			(xy 287.247314 -45.57994) (xy 287.173944 -45.6223) (xy 287.096879 -45.657495) (xy 287.016817 -45.685204)
			(xy 286.934484 -45.705178) (xy 286.850625 -45.717235) (xy 286.766 -45.721267) (xy 286.681375 -45.717235)
			(xy 286.597516 -45.705178) (xy 286.515183 -45.685204) (xy 286.435121 -45.657495) (xy 286.358056 -45.6223)
			(xy 286.284686 -45.57994) (xy 286.215674 -45.530797) (xy 286.151646 -45.475316) (xy 286.093181 -45.414001)
			(xy 286.04081 -45.347405) (xy 285.995007 -45.276133) (xy 285.956185 -45.20083) (xy 285.924697 -45.122178)
			(xy 285.900829 -45.040888) (xy 285.884795 -44.957698) (xy 285.876742 -44.873361) (xy 285.420058 -44.873361)
			(xy 285.412005 -44.957698) (xy 285.395971 -45.040888) (xy 285.372103 -45.122178) (xy 285.340615 -45.20083)
			(xy 285.301793 -45.276133) (xy 285.25599 -45.347405) (xy 285.203619 -45.414001) (xy 285.145154 -45.475316)
			(xy 285.081126 -45.530797) (xy 285.012114 -45.57994) (xy 284.938744 -45.6223) (xy 284.861679 -45.657495)
			(xy 284.781617 -45.685204) (xy 284.699284 -45.705178) (xy 284.615425 -45.717235) (xy 284.5308 -45.721267)
			(xy 284.446175 -45.717235) (xy 284.362316 -45.705178) (xy 284.279983 -45.685204) (xy 284.199921 -45.657495)
			(xy 284.122856 -45.6223) (xy 284.049486 -45.57994) (xy 283.980474 -45.530797) (xy 283.916446 -45.475316)
			(xy 283.857981 -45.414001) (xy 283.80561 -45.347405) (xy 283.759807 -45.276133) (xy 283.720985 -45.20083)
			(xy 283.689497 -45.122178) (xy 283.665629 -45.040888) (xy 283.649595 -44.957698) (xy 283.641542 -44.873361)
			(xy 278.404558 -44.873361) (xy 278.432422 -44.893203) (xy 278.49645 -44.948684) (xy 278.554915 -45.009999)
			(xy 278.607286 -45.076595) (xy 278.653089 -45.147867) (xy 278.691911 -45.22317) (xy 278.723399 -45.301822)
			(xy 278.747267 -45.383112) (xy 278.763301 -45.466302) (xy 278.771354 -45.550639) (xy 278.771858 -45.593)
			(xy 278.771354 -45.635361) (xy 278.763301 -45.719698) (xy 278.747267 -45.802888) (xy 278.723399 -45.884178)
			(xy 278.691911 -45.96283) (xy 278.653089 -46.038133) (xy 278.607286 -46.109405) (xy 278.554915 -46.176001)
			(xy 278.49645 -46.237316) (xy 278.432422 -46.292797) (xy 278.36341 -46.34194) (xy 278.29004 -46.3843)
			(xy 278.212975 -46.419495) (xy 278.132913 -46.447204) (xy 278.05058 -46.467178) (xy 277.966721 -46.479235)
			(xy 277.882096 -46.483267) (xy 277.797471 -46.479235) (xy 277.713612 -46.467178) (xy 277.631279 -46.447204)
			(xy 277.551217 -46.419495) (xy 277.474152 -46.3843) (xy 277.400782 -46.34194) (xy 277.33177 -46.292797)
			(xy 277.267742 -46.237316) (xy 277.209277 -46.176001) (xy 277.156906 -46.109405) (xy 277.111103 -46.038133)
			(xy 277.072281 -45.96283) (xy 277.040793 -45.884178) (xy 277.016925 -45.802888) (xy 277.000891 -45.719698)
			(xy 276.992838 -45.635361) (xy 272.807585 -45.635361) (xy 272.801563 -45.655572) (xy 272.769227 -45.735121)
			(xy 272.729374 -45.811183) (xy 272.682377 -45.883051) (xy 272.628672 -45.950055) (xy 272.56876 -46.011571)
			(xy 272.503198 -46.067026) (xy 272.432597 -46.115905) (xy 272.357614 -46.157753) (xy 272.31848 -46.175422)
			(xy 272.309646 -46.179778) (xy 272.295898 -46.193856) (xy 272.28844 -46.212067) (xy 272.288 -46.221904)
			(xy 272.288 -46.882) (xy 273.302784 -46.882) (xy 273.306814 -46.79738) (xy 273.318871 -46.713525)
			(xy 273.338844 -46.631197) (xy 273.366552 -46.55114) (xy 273.401744 -46.474079) (xy 273.444102 -46.400713)
			(xy 273.493243 -46.331705) (xy 273.54872 -46.26768) (xy 273.610032 -46.209219) (xy 273.676624 -46.156851)
			(xy 273.747892 -46.11105) (xy 273.823191 -46.072231) (xy 273.901839 -46.040745) (xy 273.983124 -46.016877)
			(xy 274.066309 -46.000845) (xy 274.150642 -45.992792) (xy 274.193 -45.992288) (xy 274.236489 -45.992841)
			(xy 274.323051 -46.001349) (xy 274.408369 -46.018263) (xy 274.49163 -46.043422) (xy 274.572038 -46.076587)
			(xy 274.648826 -46.11744) (xy 274.72126 -46.165591) (xy 274.78865 -46.220581) (xy 274.819872 -46.25086)
			(xy 274.820126 -46.251114) (xy 274.82751 -46.257689) (xy 274.845809 -46.265133) (xy 274.855686 -46.265592)
			(xy 274.927314 -46.265592) (xy 274.937197 -46.265171) (xy 274.955496 -46.257705) (xy 274.962874 -46.251114)
			(xy 274.963128 -46.25086) (xy 274.994367 -46.220599) (xy 275.061755 -46.165608) (xy 275.134187 -46.117455)
			(xy 275.210972 -46.0766) (xy 275.291377 -46.043431) (xy 275.374635 -46.018266) (xy 275.459951 -46.001345)
			(xy 275.546511 -45.992829) (xy 275.59 -45.992288) (xy 275.632363 -45.992692) (xy 275.716705 -46.000746)
			(xy 275.7999 -46.01678) (xy 275.881194 -46.04065) (xy 275.959851 -46.07214) (xy 276.035158 -46.110963)
			(xy 276.106434 -46.15677) (xy 276.173033 -46.209144) (xy 276.234352 -46.267611) (xy 276.289836 -46.331643)
			(xy 276.338982 -46.400659) (xy 276.381345 -46.474033) (xy 276.416541 -46.551103) (xy 276.444252 -46.631169)
			(xy 276.464227 -46.713506) (xy 276.476285 -46.79737) (xy 276.480317 -46.882) (xy 276.476285 -46.96663)
			(xy 276.464227 -47.050494) (xy 276.444252 -47.132831) (xy 276.416541 -47.212897) (xy 276.381345 -47.289967)
			(xy 276.338982 -47.363341) (xy 276.289836 -47.432357) (xy 276.234352 -47.496389) (xy 276.173033 -47.554856)
			(xy 276.106434 -47.60723) (xy 276.035158 -47.653037) (xy 275.959851 -47.69186) (xy 275.881194 -47.72335)
			(xy 275.7999 -47.74722) (xy 275.716705 -47.763254) (xy 275.632363 -47.771308) (xy 275.59 -47.771812)
			(xy 275.546511 -47.771259) (xy 275.459949 -47.762751) (xy 275.374631 -47.745837) (xy 275.29137 -47.720678)
			(xy 275.210962 -47.687513) (xy 275.134174 -47.64666) (xy 275.06174 -47.598509) (xy 274.99435 -47.543519)
			(xy 274.963128 -47.51324) (xy 274.962874 -47.512986) (xy 274.95549 -47.506411) (xy 274.937191 -47.498967)
			(xy 274.927314 -47.498508) (xy 274.855686 -47.498508) (xy 274.845803 -47.498929) (xy 274.827504 -47.506395)
			(xy 274.820126 -47.512986) (xy 274.819872 -47.51324) (xy 274.788633 -47.543501) (xy 274.721245 -47.598492)
			(xy 274.648813 -47.646645) (xy 274.572028 -47.6875) (xy 274.491623 -47.720669) (xy 274.408365 -47.745834)
			(xy 274.323049 -47.762755) (xy 274.236489 -47.771271) (xy 274.193 -47.771812) (xy 274.150642 -47.771208)
			(xy 274.066309 -47.763155) (xy 273.983124 -47.747123) (xy 273.901839 -47.723255) (xy 273.823191 -47.691769)
			(xy 273.747892 -47.65295) (xy 273.676624 -47.607149) (xy 273.610032 -47.554781) (xy 273.54872 -47.49632)
			(xy 273.493243 -47.432295) (xy 273.444102 -47.363287) (xy 273.401744 -47.289921) (xy 273.366552 -47.21286)
			(xy 273.338844 -47.132803) (xy 273.318871 -47.050475) (xy 273.306814 -46.96662) (xy 273.302784 -46.882)
			(xy 272.288 -46.882) (xy 272.288 -47.690024) (xy 272.288624 -47.701867) (xy 272.299226 -47.72305)
			(xy 272.30832 -47.730664) (xy 272.373598 -47.779432) (xy 272.383445 -47.78605) (xy 272.406759 -47.790299)
			(xy 272.418302 -47.78756) (xy 272.459087 -47.776085) (xy 272.542286 -47.760038) (xy 272.626634 -47.751978)
			(xy 272.669 -47.751492) (xy 272.711348 -47.751996) (xy 272.795662 -47.760047) (xy 272.878828 -47.776076)
			(xy 272.960095 -47.799937) (xy 273.038725 -47.831416) (xy 273.114006 -47.870227) (xy 273.185258 -47.916017)
			(xy 273.251834 -47.968373) (xy 273.313132 -48.026821) (xy 273.368597 -48.090831) (xy 273.417726 -48.159823)
			(xy 273.460075 -48.233173) (xy 273.495259 -48.310216) (xy 273.522961 -48.390255) (xy 273.542929 -48.472564)
			(xy 273.554982 -48.556399) (xy 273.559013 -48.641) (xy 273.554982 -48.725601) (xy 273.542929 -48.809436)
			(xy 273.522961 -48.891745) (xy 273.495259 -48.971784) (xy 273.460075 -49.048827) (xy 273.417726 -49.122177)
			(xy 273.368597 -49.191169) (xy 273.313132 -49.255179) (xy 273.251834 -49.313627) (xy 273.185258 -49.365983)
			(xy 273.114006 -49.411773) (xy 273.038725 -49.450584) (xy 272.960095 -49.482063) (xy 272.878828 -49.505924)
			(xy 272.795662 -49.521953) (xy 272.711348 -49.530004) (xy 272.669 -49.530508) (xy 272.626634 -49.530019)
			(xy 272.542286 -49.521961) (xy 272.459087 -49.505917) (xy 272.418302 -49.49444) (xy 272.406618 -49.491138)
			(xy 272.38325 -49.495202) (xy 272.30832 -49.551336) (xy 272.299211 -49.558937) (xy 272.288605 -49.580128)
			(xy 272.288 -49.591976) (xy 272.288 -50.419) (xy 272.287479 -50.45226) (xy 272.278791 -50.51821)
			(xy 272.261566 -50.582461) (xy 272.236097 -50.643912) (xy 272.202821 -50.701511) (xy 272.162308 -50.754271)
			(xy 272.139156 -50.778156) (xy 270.996156 -51.921156) (xy 270.972276 -51.944312) (xy 270.919512 -51.984818)
			(xy 270.861911 -52.018089) (xy 270.80046 -52.043553) (xy 270.736209 -52.060775) (xy 270.670259 -52.069461)
			(xy 270.637 -52.07) (xy 258.784344 -52.07) (xy 258.774278 -52.070434) (xy 258.755689 -52.078162)
			(xy 258.748276 -52.084986) (xy 255.429004 -55.404258) (xy 255.424432 -55.437786) (xy 255.433068 -55.452772)
			(xy 255.481287 -55.539122) (xy 255.571682 -55.715057) (xy 255.655051 -55.894429) (xy 255.731262 -56.076957)
			(xy 255.800198 -56.262355) (xy 255.86175 -56.450334) (xy 255.915822 -56.640599) (xy 255.96233 -56.832853)
			(xy 256.0012 -57.026795) (xy 256.032372 -57.222123) (xy 256.055797 -57.41853) (xy 256.071439 -57.61571)
			(xy 256.079273 -57.813354) (xy 256.079752 -57.912254) (xy 256.079246 -58.012957) (xy 256.071138 -58.214198)
			(xy 256.054934 -58.41495) (xy 256.03066 -58.614887) (xy 255.998354 -58.813684) (xy 255.958071 -59.01102)
			(xy 255.909874 -59.206573) (xy 255.853843 -59.400027) (xy 255.790067 -59.591068) (xy 255.718651 -59.779386)
			(xy 255.639711 -59.964676) (xy 255.553373 -60.146637) (xy 255.459779 -60.324974) (xy 255.35908 -60.499398)
			(xy 255.251439 -60.669626) (xy 255.137032 -60.835381) (xy 255.016043 -60.996396) (xy 254.888669 -61.152408)
			(xy 254.755116 -61.303165) (xy 254.615602 -61.448422) (xy 254.470352 -61.587944) (xy 254.319601 -61.721504)
			(xy 254.163596 -61.848886) (xy 254.002587 -61.969883) (xy 253.836838 -62.084299) (xy 253.666615 -62.191948)
			(xy 253.492196 -62.292656) (xy 253.313864 -62.38626) (xy 253.131908 -62.472606) (xy 252.946622 -62.551556)
			(xy 252.758307 -62.622982) (xy 252.567269 -62.686767) (xy 252.373818 -62.742809) (xy 252.178268 -62.791015)
			(xy 251.980934 -62.831309) (xy 251.782139 -62.863624) (xy 251.582203 -62.887908) (xy 251.381452 -62.904123)
			(xy 251.18021 -62.912241) (xy 251.079508 -62.912752) (xy 230.521002 -62.912752) (xy 230.510933 -62.913176)
			(xy 230.492333 -62.920896) (xy 230.484934 -62.927738) (xy 221.410072 -72.0026) (xy 221.994784 -72.0026)
			(xy 221.998814 -71.91798) (xy 222.010871 -71.834125) (xy 222.030844 -71.751797) (xy 222.058552 -71.67174)
			(xy 222.093744 -71.594679) (xy 222.136102 -71.521313) (xy 222.185243 -71.452305) (xy 222.24072 -71.38828)
			(xy 222.302032 -71.329819) (xy 222.368624 -71.277451) (xy 222.439892 -71.23165) (xy 222.515191 -71.192831)
			(xy 222.593839 -71.161345) (xy 222.675124 -71.137477) (xy 222.758309 -71.121445) (xy 222.842642 -71.113392)
			(xy 222.885 -71.112888) (xy 222.928791 -71.113422) (xy 223.01595 -71.12202) (xy 223.101841 -71.139145)
			(xy 223.185634 -71.164629) (xy 223.266515 -71.198225) (xy 223.343703 -71.239609) (xy 223.416449 -71.28838)
			(xy 223.48405 -71.344065) (xy 223.545849 -71.406125) (xy 223.601249 -71.473959) (xy 223.625918 -71.510144)
			(xy 223.63303 -71.520558) (xy 223.655382 -71.53275) (xy 223.765618 -71.53275) (xy 223.78797 -71.520558)
			(xy 223.795082 -71.510144) (xy 223.819739 -71.473951) (xy 223.875146 -71.406123) (xy 223.93695 -71.344068)
			(xy 224.004553 -71.288386) (xy 224.0773 -71.239618) (xy 224.154488 -71.198234) (xy 224.235369 -71.164636)
			(xy 224.319161 -71.139149) (xy 224.405051 -71.122019) (xy 224.492209 -71.113412) (xy 224.536 -71.112888)
			(xy 224.578321 -71.113409) (xy 224.662577 -71.12148) (xy 224.745686 -71.13752) (xy 224.826894 -71.161384)
			(xy 224.905468 -71.192856) (xy 224.980695 -71.231651) (xy 225.016568 -71.254112) (xy 225.024962 -71.258975)
			(xy 225.044 -71.262628) (xy 225.063038 -71.258975) (xy 225.071432 -71.254112) (xy 225.107317 -71.231673)
			(xy 225.182548 -71.192891) (xy 225.261121 -71.161425) (xy 225.342326 -71.137559) (xy 225.425429 -71.121508)
			(xy 225.509681 -71.113418) (xy 225.552 -71.112888) (xy 225.595791 -71.113422) (xy 225.68295 -71.12202)
			(xy 225.768841 -71.139145) (xy 225.852634 -71.164629) (xy 225.933515 -71.198225) (xy 226.010703 -71.239609)
			(xy 226.083449 -71.28838) (xy 226.15105 -71.344065) (xy 226.212849 -71.406125) (xy 226.268249 -71.473959)
			(xy 226.292918 -71.510144) (xy 226.30003 -71.520558) (xy 226.322382 -71.53275) (xy 226.432618 -71.53275)
			(xy 226.45497 -71.520558) (xy 226.462082 -71.510144) (xy 226.486739 -71.473951) (xy 226.542146 -71.406123)
			(xy 226.60395 -71.344068) (xy 226.671553 -71.288386) (xy 226.7443 -71.239618) (xy 226.821488 -71.198234)
			(xy 226.902369 -71.164636) (xy 226.986161 -71.139149) (xy 227.072051 -71.122019) (xy 227.159209 -71.113412)
			(xy 227.203 -71.112888) (xy 227.245363 -71.113292) (xy 227.329705 -71.121346) (xy 227.4129 -71.13738)
			(xy 227.494194 -71.16125) (xy 227.572851 -71.19274) (xy 227.648158 -71.231563) (xy 227.719434 -71.27737)
			(xy 227.786033 -71.329744) (xy 227.847352 -71.388211) (xy 227.902836 -71.452243) (xy 227.951982 -71.521259)
			(xy 227.994345 -71.594633) (xy 228.029541 -71.671703) (xy 228.057252 -71.751769) (xy 228.077227 -71.834106)
			(xy 228.089285 -71.91797) (xy 228.093317 -72.0026) (xy 228.979784 -72.0026) (xy 228.983814 -71.91798)
			(xy 228.995871 -71.834125) (xy 229.015844 -71.751797) (xy 229.043552 -71.67174) (xy 229.078744 -71.594679)
			(xy 229.121102 -71.521313) (xy 229.170243 -71.452305) (xy 229.22572 -71.38828) (xy 229.287032 -71.329819)
			(xy 229.353624 -71.277451) (xy 229.424892 -71.23165) (xy 229.500191 -71.192831) (xy 229.578839 -71.161345)
			(xy 229.660124 -71.137477) (xy 229.743309 -71.121445) (xy 229.827642 -71.113392) (xy 229.87 -71.112888)
			(xy 229.912321 -71.113409) (xy 229.996577 -71.12148) (xy 230.079686 -71.13752) (xy 230.160894 -71.161384)
			(xy 230.239468 -71.192856) (xy 230.314695 -71.231651) (xy 230.350568 -71.254112) (xy 230.358962 -71.258975)
			(xy 230.378 -71.262628) (xy 230.397038 -71.258975) (xy 230.405432 -71.254112) (xy 230.441317 -71.231673)
			(xy 230.516548 -71.192891) (xy 230.595121 -71.161425) (xy 230.676326 -71.137559) (xy 230.759429 -71.121508)
			(xy 230.843681 -71.113418) (xy 230.886 -71.112888) (xy 230.929791 -71.113422) (xy 231.01695 -71.12202)
			(xy 231.102841 -71.139145) (xy 231.186634 -71.164629) (xy 231.267515 -71.198225) (xy 231.344703 -71.239609)
			(xy 231.417449 -71.28838) (xy 231.48505 -71.344065) (xy 231.546849 -71.406125) (xy 231.602249 -71.473959)
			(xy 231.626918 -71.510144) (xy 231.63403 -71.520558) (xy 231.656382 -71.53275) (xy 231.766618 -71.53275)
			(xy 231.78897 -71.520558) (xy 231.796082 -71.510144) (xy 231.820739 -71.473951) (xy 231.876146 -71.406123)
			(xy 231.93795 -71.344068) (xy 232.005553 -71.288386) (xy 232.0783 -71.239618) (xy 232.155488 -71.198234)
			(xy 232.236369 -71.164636) (xy 232.320161 -71.139149) (xy 232.406051 -71.122019) (xy 232.493209 -71.113412)
			(xy 232.537 -71.112888) (xy 232.579363 -71.113292) (xy 232.663705 -71.121346) (xy 232.7469 -71.13738)
			(xy 232.828194 -71.16125) (xy 232.906851 -71.19274) (xy 232.982158 -71.231563) (xy 233.053434 -71.27737)
			(xy 233.120033 -71.329744) (xy 233.181352 -71.388211) (xy 233.236836 -71.452243) (xy 233.285982 -71.521259)
			(xy 233.328345 -71.594633) (xy 233.363541 -71.671703) (xy 233.391252 -71.751769) (xy 233.411227 -71.834106)
			(xy 233.423285 -71.91797) (xy 233.427317 -72.0026) (xy 233.425296 -72.045011) (xy 234.314742 -72.045011)
			(xy 234.314742 -71.960289) (xy 234.322795 -71.875952) (xy 234.338829 -71.792762) (xy 234.362697 -71.711472)
			(xy 234.394185 -71.63282) (xy 234.433007 -71.557517) (xy 234.47881 -71.486245) (xy 234.531181 -71.419649)
			(xy 234.589646 -71.358334) (xy 234.653674 -71.302853) (xy 234.722686 -71.25371) (xy 234.796056 -71.21135)
			(xy 234.873121 -71.176155) (xy 234.953183 -71.148446) (xy 235.035516 -71.128472) (xy 235.119375 -71.116415)
			(xy 235.204 -71.112384) (xy 235.288625 -71.116415) (xy 235.372484 -71.128472) (xy 235.454817 -71.148446)
			(xy 235.534879 -71.176155) (xy 235.611944 -71.21135) (xy 235.685314 -71.25371) (xy 235.754326 -71.302853)
			(xy 235.818354 -71.358334) (xy 235.876819 -71.419649) (xy 235.92919 -71.486245) (xy 235.974993 -71.557517)
			(xy 236.013815 -71.63282) (xy 236.045303 -71.711472) (xy 236.069171 -71.792762) (xy 236.085205 -71.875952)
			(xy 236.093258 -71.960289) (xy 236.093762 -72.00265) (xy 236.093258 -72.045011) (xy 236.085376 -72.127561)
			(xy 237.870742 -72.127561) (xy 237.870742 -72.042839) (xy 237.878795 -71.958502) (xy 237.894829 -71.875312)
			(xy 237.918697 -71.794022) (xy 237.950185 -71.71537) (xy 237.989007 -71.640067) (xy 238.03481 -71.568795)
			(xy 238.087181 -71.502199) (xy 238.145646 -71.440884) (xy 238.209674 -71.385403) (xy 238.278686 -71.33626)
			(xy 238.352056 -71.2939) (xy 238.429121 -71.258705) (xy 238.509183 -71.230996) (xy 238.591516 -71.211022)
			(xy 238.675375 -71.198965) (xy 238.76 -71.194934) (xy 238.844625 -71.198965) (xy 238.928484 -71.211022)
			(xy 239.010817 -71.230996) (xy 239.090879 -71.258705) (xy 239.167944 -71.2939) (xy 239.241314 -71.33626)
			(xy 239.310326 -71.385403) (xy 239.374354 -71.440884) (xy 239.432819 -71.502199) (xy 239.48519 -71.568795)
			(xy 239.530993 -71.640067) (xy 239.569815 -71.71537) (xy 239.601303 -71.794022) (xy 239.625171 -71.875312)
			(xy 239.641205 -71.958502) (xy 239.649258 -72.042839) (xy 239.649762 -72.0852) (xy 239.649258 -72.127561)
			(xy 239.641205 -72.211898) (xy 239.625171 -72.295088) (xy 239.601303 -72.376378) (xy 239.569815 -72.45503)
			(xy 239.530993 -72.530333) (xy 239.48519 -72.601605) (xy 239.432819 -72.668201) (xy 239.374354 -72.729516)
			(xy 239.310326 -72.784997) (xy 239.241314 -72.83414) (xy 239.167944 -72.8765) (xy 239.090879 -72.911695)
			(xy 239.010817 -72.939404) (xy 238.928484 -72.959378) (xy 238.844625 -72.971435) (xy 238.76 -72.975467)
			(xy 238.675375 -72.971435) (xy 238.591516 -72.959378) (xy 238.509183 -72.939404) (xy 238.429121 -72.911695)
			(xy 238.352056 -72.8765) (xy 238.278686 -72.83414) (xy 238.209674 -72.784997) (xy 238.145646 -72.729516)
			(xy 238.087181 -72.668201) (xy 238.03481 -72.601605) (xy 237.989007 -72.530333) (xy 237.950185 -72.45503)
			(xy 237.918697 -72.376378) (xy 237.894829 -72.295088) (xy 237.878795 -72.211898) (xy 237.870742 -72.127561)
			(xy 236.085376 -72.127561) (xy 236.085205 -72.129348) (xy 236.069171 -72.212538) (xy 236.045303 -72.293828)
			(xy 236.013815 -72.37248) (xy 235.974993 -72.447783) (xy 235.92919 -72.519055) (xy 235.876819 -72.585651)
			(xy 235.818354 -72.646966) (xy 235.754326 -72.702447) (xy 235.685314 -72.75159) (xy 235.611944 -72.79395)
			(xy 235.534879 -72.829145) (xy 235.454817 -72.856854) (xy 235.372484 -72.876828) (xy 235.288625 -72.888885)
			(xy 235.204 -72.892917) (xy 235.119375 -72.888885) (xy 235.035516 -72.876828) (xy 234.953183 -72.856854)
			(xy 234.873121 -72.829145) (xy 234.796056 -72.79395) (xy 234.722686 -72.75159) (xy 234.653674 -72.702447)
			(xy 234.589646 -72.646966) (xy 234.531181 -72.585651) (xy 234.47881 -72.519055) (xy 234.433007 -72.447783)
			(xy 234.394185 -72.37248) (xy 234.362697 -72.293828) (xy 234.338829 -72.212538) (xy 234.322795 -72.129348)
			(xy 234.314742 -72.045011) (xy 233.425296 -72.045011) (xy 233.423285 -72.08723) (xy 233.411227 -72.171094)
			(xy 233.391252 -72.253431) (xy 233.363541 -72.333497) (xy 233.328345 -72.410567) (xy 233.285982 -72.483941)
			(xy 233.236836 -72.552957) (xy 233.181352 -72.616989) (xy 233.120033 -72.675456) (xy 233.053434 -72.72783)
			(xy 232.982158 -72.773637) (xy 232.906851 -72.81246) (xy 232.828194 -72.84395) (xy 232.7469 -72.86782)
			(xy 232.663705 -72.883854) (xy 232.579363 -72.891908) (xy 232.537 -72.892412) (xy 232.493209 -72.891878)
			(xy 232.40605 -72.88328) (xy 232.320159 -72.866155) (xy 232.236366 -72.840671) (xy 232.155485 -72.807075)
			(xy 232.078297 -72.765691) (xy 232.005551 -72.71692) (xy 231.93795 -72.661235) (xy 231.876151 -72.599175)
			(xy 231.820751 -72.531341) (xy 231.796082 -72.495156) (xy 231.78897 -72.484742) (xy 231.766618 -72.47255)
			(xy 231.656382 -72.47255) (xy 231.63403 -72.484742) (xy 231.626918 -72.495156) (xy 231.602261 -72.531349)
			(xy 231.546854 -72.599177) (xy 231.48505 -72.661232) (xy 231.417447 -72.716914) (xy 231.3447 -72.765682)
			(xy 231.267512 -72.807066) (xy 231.186631 -72.840664) (xy 231.102839 -72.866151) (xy 231.016949 -72.883281)
			(xy 230.929791 -72.891888) (xy 230.886 -72.892412) (xy 230.843679 -72.891891) (xy 230.759423 -72.88382)
			(xy 230.676314 -72.86778) (xy 230.595106 -72.843916) (xy 230.516532 -72.812444) (xy 230.441305 -72.773649)
			(xy 230.405432 -72.751188) (xy 230.397038 -72.746325) (xy 230.378 -72.742672) (xy 230.358962 -72.746325)
			(xy 230.350568 -72.751188) (xy 230.314683 -72.773627) (xy 230.239452 -72.812409) (xy 230.160879 -72.843875)
			(xy 230.079674 -72.867741) (xy 229.996571 -72.883792) (xy 229.912319 -72.891882) (xy 229.87 -72.892412)
			(xy 229.827642 -72.891808) (xy 229.743309 -72.883755) (xy 229.660124 -72.867723) (xy 229.578839 -72.843855)
			(xy 229.500191 -72.812369) (xy 229.424892 -72.77355) (xy 229.353624 -72.727749) (xy 229.287032 -72.675381)
			(xy 229.22572 -72.61692) (xy 229.170243 -72.552895) (xy 229.121102 -72.483887) (xy 229.078744 -72.410521)
			(xy 229.043552 -72.33346) (xy 229.015844 -72.253403) (xy 228.995871 -72.171075) (xy 228.983814 -72.08722)
			(xy 228.979784 -72.0026) (xy 228.093317 -72.0026) (xy 228.089285 -72.08723) (xy 228.077227 -72.171094)
			(xy 228.057252 -72.253431) (xy 228.029541 -72.333497) (xy 227.994345 -72.410567) (xy 227.951982 -72.483941)
			(xy 227.902836 -72.552957) (xy 227.847352 -72.616989) (xy 227.786033 -72.675456) (xy 227.719434 -72.72783)
			(xy 227.648158 -72.773637) (xy 227.572851 -72.81246) (xy 227.494194 -72.84395) (xy 227.4129 -72.86782)
			(xy 227.329705 -72.883854) (xy 227.245363 -72.891908) (xy 227.203 -72.892412) (xy 227.159209 -72.891878)
			(xy 227.07205 -72.88328) (xy 226.986159 -72.866155) (xy 226.902366 -72.840671) (xy 226.821485 -72.807075)
			(xy 226.744297 -72.765691) (xy 226.671551 -72.71692) (xy 226.60395 -72.661235) (xy 226.542151 -72.599175)
			(xy 226.486751 -72.531341) (xy 226.462082 -72.495156) (xy 226.45497 -72.484742) (xy 226.432618 -72.47255)
			(xy 226.322382 -72.47255) (xy 226.30003 -72.484742) (xy 226.292918 -72.495156) (xy 226.268261 -72.531349)
			(xy 226.212854 -72.599177) (xy 226.15105 -72.661232) (xy 226.083447 -72.716914) (xy 226.0107 -72.765682)
			(xy 225.933512 -72.807066) (xy 225.852631 -72.840664) (xy 225.768839 -72.866151) (xy 225.682949 -72.883281)
			(xy 225.595791 -72.891888) (xy 225.552 -72.892412) (xy 225.509679 -72.891891) (xy 225.425423 -72.88382)
			(xy 225.342314 -72.86778) (xy 225.261106 -72.843916) (xy 225.182532 -72.812444) (xy 225.107305 -72.773649)
			(xy 225.071432 -72.751188) (xy 225.063038 -72.746325) (xy 225.044 -72.742672) (xy 225.024962 -72.746325)
			(xy 225.016568 -72.751188) (xy 224.980683 -72.773627) (xy 224.905452 -72.812409) (xy 224.826879 -72.843875)
			(xy 224.745674 -72.867741) (xy 224.662571 -72.883792) (xy 224.578319 -72.891882) (xy 224.536 -72.892412)
			(xy 224.492209 -72.891878) (xy 224.40505 -72.88328) (xy 224.319159 -72.866155) (xy 224.235366 -72.840671)
			(xy 224.154485 -72.807075) (xy 224.077297 -72.765691) (xy 224.004551 -72.71692) (xy 223.93695 -72.661235)
			(xy 223.875151 -72.599175) (xy 223.819751 -72.531341) (xy 223.795082 -72.495156) (xy 223.78797 -72.484742)
			(xy 223.765618 -72.47255) (xy 223.655382 -72.47255) (xy 223.63303 -72.484742) (xy 223.625918 -72.495156)
			(xy 223.601261 -72.531349) (xy 223.545854 -72.599177) (xy 223.48405 -72.661232) (xy 223.416447 -72.716914)
			(xy 223.3437 -72.765682) (xy 223.266512 -72.807066) (xy 223.185631 -72.840664) (xy 223.101839 -72.866151)
			(xy 223.015949 -72.883281) (xy 222.928791 -72.891888) (xy 222.885 -72.892412) (xy 222.842642 -72.891808)
			(xy 222.758309 -72.883755) (xy 222.675124 -72.867723) (xy 222.593839 -72.843855) (xy 222.515191 -72.812369)
			(xy 222.439892 -72.77355) (xy 222.368624 -72.727749) (xy 222.302032 -72.675381) (xy 222.24072 -72.61692)
			(xy 222.185243 -72.552895) (xy 222.136102 -72.483887) (xy 222.093744 -72.410521) (xy 222.058552 -72.33346)
			(xy 222.030844 -72.253403) (xy 222.010871 -72.171075) (xy 221.998814 -72.08722) (xy 221.994784 -72.0026)
			(xy 221.410072 -72.0026) (xy 220.486986 -72.925686) (xy 220.480144 -72.933085) (xy 220.472427 -72.951684)
			(xy 220.472 -72.961754) (xy 220.472 -73.107042) (xy 220.490796 -73.133204) (xy 220.50629 -73.138538)
			(xy 220.546294 -73.152765) (xy 220.623632 -73.187815) (xy 220.697279 -73.230075) (xy 220.766563 -73.279162)
			(xy 220.830853 -73.334628) (xy 220.889566 -73.395968) (xy 220.942166 -73.462624) (xy 220.988175 -73.533989)
			(xy 221.027173 -73.609414) (xy 221.058806 -73.688212) (xy 221.082786 -73.769665) (xy 221.098894 -73.853034)
			(xy 221.106984 -73.937558) (xy 221.106983 -74.022468) (xy 221.09889 -74.106992) (xy 221.082779 -74.19036)
			(xy 221.058797 -74.271813) (xy 221.027162 -74.35061) (xy 220.988162 -74.426034) (xy 220.942151 -74.497397)
			(xy 220.889549 -74.564052) (xy 220.830835 -74.62539) (xy 220.766542 -74.680854) (xy 220.740489 -74.699311)
			(xy 223.392742 -74.699311) (xy 223.392742 -74.614589) (xy 223.400795 -74.530252) (xy 223.416829 -74.447062)
			(xy 223.440697 -74.365772) (xy 223.472185 -74.28712) (xy 223.511007 -74.211817) (xy 223.55681 -74.140545)
			(xy 223.609181 -74.073949) (xy 223.667646 -74.012634) (xy 223.731674 -73.957153) (xy 223.800686 -73.90801)
			(xy 223.874056 -73.86565) (xy 223.951121 -73.830455) (xy 224.031183 -73.802746) (xy 224.113516 -73.782772)
			(xy 224.197375 -73.770715) (xy 224.282 -73.766684) (xy 224.366625 -73.770715) (xy 224.450484 -73.782772)
			(xy 224.532817 -73.802746) (xy 224.612879 -73.830455) (xy 224.689944 -73.86565) (xy 224.763314 -73.90801)
			(xy 224.832326 -73.957153) (xy 224.896354 -74.012634) (xy 224.954819 -74.073949) (xy 225.00719 -74.140545)
			(xy 225.052057 -74.210361) (xy 228.853742 -74.210361) (xy 228.853742 -74.125639) (xy 228.861795 -74.041302)
			(xy 228.877829 -73.958112) (xy 228.901697 -73.876822) (xy 228.933185 -73.79817) (xy 228.972007 -73.722867)
			(xy 229.01781 -73.651595) (xy 229.070181 -73.584999) (xy 229.128646 -73.523684) (xy 229.192674 -73.468203)
			(xy 229.261686 -73.41906) (xy 229.335056 -73.3767) (xy 229.412121 -73.341505) (xy 229.492183 -73.313796)
			(xy 229.574516 -73.293822) (xy 229.658375 -73.281765) (xy 229.743 -73.277734) (xy 229.827625 -73.281765)
			(xy 229.911484 -73.293822) (xy 229.993817 -73.313796) (xy 230.073879 -73.341505) (xy 230.150944 -73.3767)
			(xy 230.224314 -73.41906) (xy 230.293326 -73.468203) (xy 230.357354 -73.523684) (xy 230.415819 -73.584999)
			(xy 230.46819 -73.651595) (xy 230.513993 -73.722867) (xy 230.552815 -73.79817) (xy 230.584303 -73.876822)
			(xy 230.608171 -73.958112) (xy 230.624205 -74.041302) (xy 230.632258 -74.125639) (xy 230.632762 -74.168)
			(xy 230.632258 -74.210361) (xy 231.393742 -74.210361) (xy 231.393742 -74.125639) (xy 231.401795 -74.041302)
			(xy 231.417829 -73.958112) (xy 231.441697 -73.876822) (xy 231.473185 -73.79817) (xy 231.512007 -73.722867)
			(xy 231.55781 -73.651595) (xy 231.610181 -73.584999) (xy 231.668646 -73.523684) (xy 231.732674 -73.468203)
			(xy 231.801686 -73.41906) (xy 231.875056 -73.3767) (xy 231.952121 -73.341505) (xy 232.032183 -73.313796)
			(xy 232.114516 -73.293822) (xy 232.198375 -73.281765) (xy 232.283 -73.277734) (xy 232.367625 -73.281765)
			(xy 232.451484 -73.293822) (xy 232.533817 -73.313796) (xy 232.613879 -73.341505) (xy 232.690944 -73.3767)
			(xy 232.764314 -73.41906) (xy 232.833326 -73.468203) (xy 232.897354 -73.523684) (xy 232.955819 -73.584999)
			(xy 233.00819 -73.651595) (xy 233.053993 -73.722867) (xy 233.092815 -73.79817) (xy 233.124303 -73.876822)
			(xy 233.148171 -73.958112) (xy 233.164205 -74.041302) (xy 233.172258 -74.125639) (xy 233.172762 -74.168)
			(xy 233.172258 -74.210361) (xy 233.164205 -74.294698) (xy 233.148171 -74.377888) (xy 233.124303 -74.459178)
			(xy 233.092815 -74.53783) (xy 233.090201 -74.5429) (xy 236.091992 -74.5429) (xy 236.096022 -74.458299)
			(xy 236.108075 -74.374465) (xy 236.128043 -74.292156) (xy 236.155745 -74.212117) (xy 236.190929 -74.135075)
			(xy 236.233277 -74.061725) (xy 236.282406 -73.992733) (xy 236.337871 -73.928724) (xy 236.399168 -73.870276)
			(xy 236.465744 -73.81792) (xy 236.536996 -73.77213) (xy 236.612277 -73.73332) (xy 236.690907 -73.701841)
			(xy 236.772173 -73.677979) (xy 236.855339 -73.661951) (xy 236.939652 -73.6539) (xy 236.982 -73.653396)
			(xy 237.023248 -73.653844) (xy 237.105389 -73.661474) (xy 237.186471 -73.676677) (xy 237.265797 -73.699324)
			(xy 237.342685 -73.729218) (xy 237.416474 -73.766105) (xy 237.486531 -73.809665) (xy 237.552252 -73.859526)
			(xy 237.613074 -73.915259) (xy 237.668474 -73.976384) (xy 237.717976 -74.042377) (xy 237.761154 -74.11267)
			(xy 237.779814 -74.149458) (xy 237.784384 -74.157761) (xy 237.798386 -74.170514) (xy 237.816063 -74.17731)
			(xy 237.825534 -74.177652) (xy 237.916466 -74.177652) (xy 237.925934 -74.177277) (xy 237.94361 -74.170493)
			(xy 237.957623 -74.157761) (xy 237.962186 -74.149458) (xy 237.981683 -74.111087) (xy 238.02705 -74.037938)
			(xy 238.07927 -73.969513) (xy 238.137854 -73.906451) (xy 238.202254 -73.849341) (xy 238.271869 -73.798718)
			(xy 238.346047 -73.755055) (xy 238.424096 -73.718761) (xy 238.505285 -73.690173) (xy 238.588855 -73.669561)
			(xy 238.674026 -73.657116) (xy 238.76 -73.652954) (xy 238.845974 -73.657116) (xy 238.931145 -73.669561)
			(xy 239.014715 -73.690173) (xy 239.095904 -73.718761) (xy 239.173953 -73.755055) (xy 239.248131 -73.798718)
			(xy 239.317746 -73.849341) (xy 239.382146 -73.906451) (xy 239.44073 -73.969513) (xy 239.49295 -74.037938)
			(xy 239.538317 -74.111087) (xy 239.557814 -74.149458) (xy 239.562384 -74.157761) (xy 239.576386 -74.170514)
			(xy 239.594063 -74.17731) (xy 239.603534 -74.177652) (xy 239.694466 -74.177652) (xy 239.703934 -74.177277)
			(xy 239.72161 -74.170493) (xy 239.735623 -74.157761) (xy 239.740186 -74.149458) (xy 239.758799 -74.112647)
			(xy 239.801992 -74.042364) (xy 239.851506 -73.976381) (xy 239.906915 -73.915265) (xy 239.967744 -73.859541)
			(xy 240.03347 -73.809687) (xy 240.103529 -73.766132) (xy 240.177319 -73.729249) (xy 240.254207 -73.699355)
			(xy 240.333532 -73.676707) (xy 240.414612 -73.661499) (xy 240.496753 -73.653863) (xy 240.538 -73.653396)
			(xy 240.580349 -73.653892) (xy 240.664663 -73.661943) (xy 240.747829 -73.677972) (xy 240.829096 -73.701834)
			(xy 240.907726 -73.733313) (xy 240.983008 -73.772123) (xy 241.05426 -73.817914) (xy 241.120837 -73.87027)
			(xy 241.182135 -73.928718) (xy 241.2376 -73.992728) (xy 241.28673 -74.061721) (xy 241.329078 -74.135071)
			(xy 241.364263 -74.212114) (xy 241.391965 -74.292153) (xy 241.411933 -74.374463) (xy 241.423986 -74.458299)
			(xy 241.428017 -74.5429) (xy 241.423986 -74.627501) (xy 241.411933 -74.711337) (xy 241.391965 -74.793647)
			(xy 241.364263 -74.873686) (xy 241.329078 -74.950729) (xy 241.28673 -75.024079) (xy 241.2376 -75.093072)
			(xy 241.182135 -75.157082) (xy 241.120837 -75.21553) (xy 241.05426 -75.267886) (xy 240.983008 -75.313677)
			(xy 240.907726 -75.352487) (xy 240.829096 -75.383966) (xy 240.747829 -75.407828) (xy 240.664663 -75.423857)
			(xy 240.580349 -75.431908) (xy 240.538 -75.432412) (xy 240.496753 -75.43196) (xy 240.414611 -75.42433)
			(xy 240.333529 -75.409127) (xy 240.254204 -75.38648) (xy 240.177316 -75.356586) (xy 240.103527 -75.3197)
			(xy 240.033471 -75.27614) (xy 239.967749 -75.226279) (xy 239.906927 -75.170547) (xy 239.851527 -75.109423)
			(xy 239.802025 -75.04343) (xy 239.758847 -74.973138) (xy 239.740186 -74.93635) (xy 239.735613 -74.928048)
			(xy 239.721613 -74.915295) (xy 239.703937 -74.908498) (xy 239.694466 -74.908156) (xy 239.603534 -74.908156)
			(xy 239.594065 -74.908527) (xy 239.576389 -74.915312) (xy 239.562377 -74.928046) (xy 239.557814 -74.93635)
			(xy 239.538997 -74.97349) (xy 239.495344 -75.044397) (xy 239.445257 -75.110913) (xy 239.389174 -75.172459)
			(xy 239.327585 -75.228495) (xy 239.261029 -75.278531) (xy 239.190089 -75.322129) (xy 239.115386 -75.358907)
			(xy 239.037573 -75.388544) (xy 238.957331 -75.410781) (xy 238.875363 -75.425422) (xy 238.833914 -75.429364)
			(xy 238.83366 -75.429364) (xy 238.824216 -75.430661) (xy 238.807191 -75.439197) (xy 238.794452 -75.453354)
			(xy 238.790734 -75.46213) (xy 238.752888 -75.561952) (xy 238.75873 -75.590654) (xy 238.769144 -75.601322)
			(xy 238.798414 -75.632395) (xy 238.851538 -75.699222) (xy 238.898016 -75.770832) (xy 238.937418 -75.846565)
			(xy 238.969383 -75.925725) (xy 238.993617 -76.007583) (xy 239.009895 -76.091387) (xy 239.01807 -76.176365)
			(xy 239.018572 -76.21905) (xy 239.018545 -76.235701) (xy 239.017401 -76.268984) (xy 239.016286 -76.285598)
			(xy 239.015924 -76.294998) (xy 239.021319 -76.313006) (xy 239.032863 -76.327841) (xy 239.048994 -76.337494)
			(xy 239.058196 -76.339446) (xy 239.102205 -76.347638) (xy 239.188423 -76.371745) (xy 239.271785 -76.404386)
			(xy 239.351448 -76.445232) (xy 239.426608 -76.493869) (xy 239.496506 -76.549805) (xy 239.528858 -76.580746)
			(xy 239.535185 -76.586522) (xy 239.550667 -76.593832) (xy 239.567696 -76.595609) (xy 239.576102 -76.593954)
			(xy 239.672876 -76.57084) (xy 239.691926 -76.553568) (xy 239.696244 -76.541122) (xy 239.710414 -76.501058)
			(xy 239.74542 -76.423614) (xy 239.787652 -76.349862) (xy 239.836724 -76.280472) (xy 239.892189 -76.216079)
			(xy 239.953541 -76.157268) (xy 240.020223 -76.104575) (xy 240.091625 -76.058481) (xy 240.167097 -76.019406)
			(xy 240.245951 -75.987705) (xy 240.327469 -75.963669) (xy 240.410908 -75.947516) (xy 240.495506 -75.939392)
			(xy 240.538 -75.938888) (xy 240.580363 -75.939292) (xy 240.664705 -75.947346) (xy 240.7479 -75.96338)
			(xy 240.829194 -75.98725) (xy 240.907851 -76.01874) (xy 240.983158 -76.057563) (xy 241.054434 -76.10337)
			(xy 241.121033 -76.155744) (xy 241.182352 -76.214211) (xy 241.237836 -76.278243) (xy 241.286982 -76.347259)
			(xy 241.329345 -76.420633) (xy 241.364541 -76.497703) (xy 241.392252 -76.577769) (xy 241.412227 -76.660106)
			(xy 241.424285 -76.74397) (xy 241.428317 -76.8286) (xy 241.424285 -76.91323) (xy 241.412227 -76.997094)
			(xy 241.392252 -77.079431) (xy 241.364541 -77.159497) (xy 241.329345 -77.236567) (xy 241.286982 -77.309941)
			(xy 241.237836 -77.378957) (xy 241.182352 -77.442989) (xy 241.121033 -77.501456) (xy 241.054434 -77.55383)
			(xy 240.983158 -77.599637) (xy 240.907851 -77.63846) (xy 240.829194 -77.66995) (xy 240.7479 -77.69382)
			(xy 240.664705 -77.709854) (xy 240.580363 -77.717908) (xy 240.538 -77.718412) (xy 240.494868 -77.717905)
			(xy 240.409009 -77.709544) (xy 240.324363 -77.692911) (xy 240.241724 -77.668162) (xy 240.16187 -77.635529)
			(xy 240.08555 -77.595319) (xy 240.013481 -77.547909) (xy 239.94634 -77.493745) (xy 239.915192 -77.463904)
			(xy 239.908845 -77.458153) (xy 239.893372 -77.45084) (xy 239.876352 -77.44905) (xy 239.867948 -77.450696)
			(xy 239.771174 -77.47381) (xy 239.752124 -77.491082) (xy 239.747806 -77.503528) (xy 239.734444 -77.541365)
			(xy 239.701809 -77.614678) (xy 239.6627 -77.684752) (xy 239.617437 -77.751017) (xy 239.566386 -77.812934)
			(xy 239.509963 -77.869998) (xy 239.479582 -77.896212) (xy 239.467136 -77.906626) (xy 239.459008 -77.937614)
			(xy 239.504474 -78.057756) (xy 239.53089 -78.075536) (xy 239.547146 -78.075282) (xy 239.565688 -78.075028)
			(xy 239.606799 -78.075464) (xy 239.688672 -78.083051) (xy 239.769494 -78.098162) (xy 239.848577 -78.120667)
			(xy 239.925246 -78.150374) (xy 239.998846 -78.18703) (xy 240.068749 -78.230323) (xy 240.134358 -78.279881)
			(xy 240.195113 -78.335284) (xy 240.250496 -78.396056) (xy 240.300035 -78.461681) (xy 240.343305 -78.531597)
			(xy 240.379938 -78.605208) (xy 240.409622 -78.681886) (xy 240.432102 -78.760977) (xy 240.447187 -78.841804)
			(xy 240.454749 -78.923678) (xy 240.455196 -78.96479) (xy 240.454705 -79.006312) (xy 240.44697 -79.088996)
			(xy 240.431565 -79.170599) (xy 240.408626 -79.250413) (xy 240.378352 -79.327742) (xy 240.341005 -79.401915)
			(xy 240.296911 -79.472286) (xy 240.272062 -79.505556) (xy 240.265675 -79.51473) (xy 240.260852 -79.536535)
			(xy 240.265705 -79.558334) (xy 240.272062 -79.567532) (xy 240.296877 -79.600781) (xy 240.340937 -79.671087)
			(xy 240.378264 -79.745188) (xy 240.408533 -79.822441) (xy 240.431483 -79.902175) (xy 240.446913 -79.983699)
			(xy 240.45469 -80.066305) (xy 240.455196 -80.10779) (xy 240.454692 -80.150151) (xy 240.446639 -80.234488)
			(xy 240.430605 -80.317678) (xy 240.406737 -80.398968) (xy 240.375249 -80.47762) (xy 240.336427 -80.552923)
			(xy 240.290624 -80.624195) (xy 240.238253 -80.690791) (xy 240.179788 -80.752106) (xy 240.11576 -80.807587)
			(xy 240.046748 -80.85673) (xy 239.973378 -80.89909) (xy 239.896313 -80.934285) (xy 239.816251 -80.961994)
			(xy 239.733918 -80.981968) (xy 239.650059 -80.994025) (xy 239.565434 -80.998057) (xy 239.480809 -80.994025)
			(xy 239.39695 -80.981968) (xy 239.314617 -80.961994) (xy 239.234555 -80.934285) (xy 239.15749 -80.89909)
			(xy 239.08412 -80.85673) (xy 239.015108 -80.807587) (xy 238.95108 -80.752106) (xy 238.892615 -80.690791)
			(xy 238.840244 -80.624195) (xy 238.794441 -80.552923) (xy 238.755619 -80.47762) (xy 238.724131 -80.398968)
			(xy 238.700263 -80.317678) (xy 238.684229 -80.234488) (xy 238.676176 -80.150151) (xy 238.675672 -80.10779)
			(xy 238.676166 -80.066243) (xy 238.683914 -79.983511) (xy 238.699341 -79.901862) (xy 238.722313 -79.822007)
			(xy 238.75263 -79.744642) (xy 238.790027 -79.670439) (xy 238.83418 -79.600047) (xy 238.85906 -79.56677)
			(xy 238.865384 -79.557609) (xy 238.870213 -79.535907) (xy 238.86539 -79.514204) (xy 238.85906 -79.505048)
			(xy 238.834243 -79.471806) (xy 238.790206 -79.401496) (xy 238.752909 -79.32739) (xy 238.722674 -79.250133)
			(xy 238.699766 -79.170397) (xy 238.684382 -79.088873) (xy 238.676657 -79.006271) (xy 238.67618 -78.96479)
			(xy 238.676706 -78.921769) (xy 238.684978 -78.836125) (xy 238.701482 -78.75168) (xy 238.726064 -78.669223)
			(xy 238.758494 -78.589526) (xy 238.798469 -78.513334) (xy 238.845615 -78.441358) (xy 238.899493 -78.374272)
			(xy 238.959596 -78.312702) (xy 238.992156 -78.284578) (xy 239.004602 -78.274164) (xy 239.01273 -78.243176)
			(xy 238.967264 -78.123034) (xy 238.940848 -78.105254) (xy 238.9251 -78.105508) (xy 238.924084 -78.105508)
			(xy 238.90605 -78.105508) (xy 238.864945 -78.10494) (xy 238.783086 -78.09736) (xy 238.702276 -78.082262)
			(xy 238.623202 -78.059773) (xy 238.546541 -78.030085) (xy 238.472945 -77.993451) (xy 238.403043 -77.950184)
			(xy 238.33743 -77.900654) (xy 238.276667 -77.845281) (xy 238.22127 -77.784539) (xy 238.171714 -77.718946)
			(xy 238.128419 -77.649061) (xy 238.091757 -77.575479) (xy 238.062039 -77.49883) (xy 238.039518 -77.419765)
			(xy 238.024388 -77.33896) (xy 238.016776 -77.257104) (xy 238.016288 -77.216) (xy 238.016374 -77.199346)
			(xy 238.017644 -77.166064) (xy 238.018828 -77.149452) (xy 238.019223 -77.140052) (xy 238.013814 -77.122044)
			(xy 238.002259 -77.107209) (xy 237.986122 -77.097557) (xy 237.976918 -77.095604) (xy 237.936121 -77.088041)
			(xy 237.856044 -77.066285) (xy 237.77834 -77.037168) (xy 237.703686 -77.000941) (xy 237.63273 -76.95792)
			(xy 237.566088 -76.908478) (xy 237.504339 -76.853045) (xy 237.448021 -76.792104) (xy 237.397623 -76.726182)
			(xy 237.353582 -76.655854) (xy 237.316281 -76.581731) (xy 237.286045 -76.504456) (xy 237.263137 -76.424701)
			(xy 237.247754 -76.343159) (xy 237.240032 -76.26054) (xy 237.239556 -76.21905) (xy 237.239989 -76.177689)
			(xy 237.247665 -76.095323) (xy 237.262955 -76.014026) (xy 237.285728 -75.9345) (xy 237.315787 -75.857432)
			(xy 237.352871 -75.783487) (xy 237.396661 -75.713306) (xy 237.446778 -75.647493) (xy 237.502789 -75.586618)
			(xy 237.56421 -75.531207) (xy 237.630511 -75.481737) (xy 237.701118 -75.438638) (xy 237.775423 -75.40228)
			(xy 237.852782 -75.372979) (xy 237.932528 -75.350987) (xy 238.013971 -75.336495) (xy 238.05515 -75.33259)
			(xy 238.055404 -75.33259) (xy 238.064861 -75.331363) (xy 238.081889 -75.322797) (xy 238.094621 -75.308612)
			(xy 238.09833 -75.299824) (xy 238.136176 -75.200002) (xy 238.130334 -75.1713) (xy 238.11992 -75.160632)
			(xy 238.088457 -75.127217) (xy 238.031855 -75.05496) (xy 237.982997 -74.977257) (xy 237.962186 -74.93635)
			(xy 237.957613 -74.928048) (xy 237.943613 -74.915295) (xy 237.925937 -74.908498) (xy 237.916466 -74.908156)
			(xy 237.825534 -74.908156) (xy 237.816065 -74.908527) (xy 237.798389 -74.915312) (xy 237.784377 -74.928046)
			(xy 237.779814 -74.93635) (xy 237.761159 -74.973139) (xy 237.717973 -75.043425) (xy 237.668465 -75.10941)
			(xy 237.613061 -75.170528) (xy 237.552237 -75.226255) (xy 237.486514 -75.276112) (xy 237.416459 -75.31967)
			(xy 237.342672 -75.356555) (xy 237.265786 -75.38645) (xy 237.186464 -75.4091) (xy 237.105385 -75.424308)
			(xy 237.023246 -75.431945) (xy 236.982 -75.432412) (xy 236.939652 -75.4319) (xy 236.855339 -75.423849)
			(xy 236.772173 -75.407821) (xy 236.690907 -75.383959) (xy 236.612277 -75.35248) (xy 236.536996 -75.31367)
			(xy 236.465744 -75.26788) (xy 236.399168 -75.215524) (xy 236.337871 -75.157076) (xy 236.282406 -75.093067)
			(xy 236.233277 -75.024075) (xy 236.190929 -74.950725) (xy 236.155745 -74.873683) (xy 236.128043 -74.793644)
			(xy 236.108075 -74.711335) (xy 236.096022 -74.627501) (xy 236.091992 -74.5429) (xy 233.090201 -74.5429)
			(xy 233.053993 -74.613133) (xy 233.00819 -74.684405) (xy 232.955819 -74.751001) (xy 232.897354 -74.812316)
			(xy 232.833326 -74.867797) (xy 232.764314 -74.91694) (xy 232.690944 -74.9593) (xy 232.613879 -74.994495)
			(xy 232.533817 -75.022204) (xy 232.451484 -75.042178) (xy 232.367625 -75.054235) (xy 232.283 -75.058267)
			(xy 232.198375 -75.054235) (xy 232.114516 -75.042178) (xy 232.032183 -75.022204) (xy 231.952121 -74.994495)
			(xy 231.875056 -74.9593) (xy 231.801686 -74.91694) (xy 231.732674 -74.867797) (xy 231.668646 -74.812316)
			(xy 231.610181 -74.751001) (xy 231.55781 -74.684405) (xy 231.512007 -74.613133) (xy 231.473185 -74.53783)
			(xy 231.441697 -74.459178) (xy 231.417829 -74.377888) (xy 231.401795 -74.294698) (xy 231.393742 -74.210361)
			(xy 230.632258 -74.210361) (xy 230.624205 -74.294698) (xy 230.608171 -74.377888) (xy 230.584303 -74.459178)
			(xy 230.552815 -74.53783) (xy 230.513993 -74.613133) (xy 230.46819 -74.684405) (xy 230.415819 -74.751001)
			(xy 230.357354 -74.812316) (xy 230.293326 -74.867797) (xy 230.224314 -74.91694) (xy 230.150944 -74.9593)
			(xy 230.073879 -74.994495) (xy 229.993817 -75.022204) (xy 229.911484 -75.042178) (xy 229.827625 -75.054235)
			(xy 229.743 -75.058267) (xy 229.658375 -75.054235) (xy 229.574516 -75.042178) (xy 229.492183 -75.022204)
			(xy 229.412121 -74.994495) (xy 229.335056 -74.9593) (xy 229.261686 -74.91694) (xy 229.192674 -74.867797)
			(xy 229.128646 -74.812316) (xy 229.070181 -74.751001) (xy 229.01781 -74.684405) (xy 228.972007 -74.613133)
			(xy 228.933185 -74.53783) (xy 228.901697 -74.459178) (xy 228.877829 -74.377888) (xy 228.861795 -74.294698)
			(xy 228.853742 -74.210361) (xy 225.052057 -74.210361) (xy 225.052993 -74.211817) (xy 225.091815 -74.28712)
			(xy 225.123303 -74.365772) (xy 225.147171 -74.447062) (xy 225.163205 -74.530252) (xy 225.171258 -74.614589)
			(xy 225.171762 -74.65695) (xy 225.171258 -74.699311) (xy 225.163205 -74.783648) (xy 225.147171 -74.866838)
			(xy 225.123303 -74.948128) (xy 225.091815 -75.02678) (xy 225.052993 -75.102083) (xy 225.00719 -75.173355)
			(xy 224.954819 -75.239951) (xy 224.896354 -75.301266) (xy 224.832326 -75.356747) (xy 224.763314 -75.40589)
			(xy 224.689944 -75.44825) (xy 224.612879 -75.483445) (xy 224.532817 -75.511154) (xy 224.450484 -75.531128)
			(xy 224.366625 -75.543185) (xy 224.282 -75.547217) (xy 224.197375 -75.543185) (xy 224.113516 -75.531128)
			(xy 224.031183 -75.511154) (xy 223.951121 -75.483445) (xy 223.874056 -75.44825) (xy 223.800686 -75.40589)
			(xy 223.731674 -75.356747) (xy 223.667646 -75.301266) (xy 223.609181 -75.239951) (xy 223.55681 -75.173355)
			(xy 223.511007 -75.102083) (xy 223.472185 -75.02678) (xy 223.440697 -74.948128) (xy 223.416829 -74.866838)
			(xy 223.400795 -74.783648) (xy 223.392742 -74.699311) (xy 220.740489 -74.699311) (xy 220.697257 -74.729938)
			(xy 220.623609 -74.772197) (xy 220.546269 -74.807245) (xy 220.50629 -74.821542) (xy 220.490796 -74.826876)
			(xy 220.472 -74.853038) (xy 220.472 -75.922321) (xy 226.024944 -75.922321) (xy 226.024944 -75.837599)
			(xy 226.032997 -75.753262) (xy 226.049031 -75.670072) (xy 226.072899 -75.588782) (xy 226.104387 -75.51013)
			(xy 226.143209 -75.434827) (xy 226.189012 -75.363555) (xy 226.241383 -75.296959) (xy 226.299848 -75.235644)
			(xy 226.363876 -75.180163) (xy 226.432888 -75.13102) (xy 226.506258 -75.08866) (xy 226.583323 -75.053465)
			(xy 226.663385 -75.025756) (xy 226.745718 -75.005782) (xy 226.829577 -74.993725) (xy 226.914202 -74.989694)
			(xy 226.998827 -74.993725) (xy 227.082686 -75.005782) (xy 227.165019 -75.025756) (xy 227.245081 -75.053465)
			(xy 227.322146 -75.08866) (xy 227.395516 -75.13102) (xy 227.464528 -75.180163) (xy 227.528556 -75.235644)
			(xy 227.587021 -75.296959) (xy 227.639392 -75.363555) (xy 227.685195 -75.434827) (xy 227.724017 -75.51013)
			(xy 227.755505 -75.588782) (xy 227.779373 -75.670072) (xy 227.795407 -75.753262) (xy 227.80346 -75.837599)
			(xy 227.803964 -75.87996) (xy 227.80346 -75.922321) (xy 227.795407 -76.006658) (xy 227.779373 -76.089848)
			(xy 227.755505 -76.171138) (xy 227.724017 -76.24979) (xy 227.685195 -76.325093) (xy 227.639392 -76.396365)
			(xy 227.587021 -76.462961) (xy 227.528556 -76.524276) (xy 227.464528 -76.579757) (xy 227.395516 -76.6289)
			(xy 227.322146 -76.67126) (xy 227.245081 -76.706455) (xy 227.165019 -76.734164) (xy 227.082686 -76.754138)
			(xy 226.998827 -76.766195) (xy 226.914202 -76.770227) (xy 226.829577 -76.766195) (xy 226.745718 -76.754138)
			(xy 226.663385 -76.734164) (xy 226.583323 -76.706455) (xy 226.506258 -76.67126) (xy 226.432888 -76.6289)
			(xy 226.363876 -76.579757) (xy 226.299848 -76.524276) (xy 226.241383 -76.462961) (xy 226.189012 -76.396365)
			(xy 226.143209 -76.325093) (xy 226.104387 -76.24979) (xy 226.072899 -76.171138) (xy 226.049031 -76.089848)
			(xy 226.032997 -76.006658) (xy 226.024944 -75.922321) (xy 220.472 -75.922321) (xy 220.472 -76.44511)
			(xy 220.472708 -76.45784) (xy 220.484845 -76.480224) (xy 220.495114 -76.487782) (xy 220.577664 -76.541122)
			(xy 220.603572 -76.543154) (xy 220.615256 -76.53782) (xy 220.658367 -76.519117) (xy 220.747669 -76.489845)
			(xy 220.839558 -76.47014) (xy 220.933011 -76.460222) (xy 220.98 -76.459588) (xy 221.020054 -76.460025)
			(xy 221.099837 -76.467222) (xy 221.17865 -76.481568) (xy 221.255852 -76.502945) (xy 221.330818 -76.531181)
			(xy 221.40294 -76.566047) (xy 221.471634 -76.607259) (xy 221.536341 -76.654484) (xy 221.56674 -76.680568)
			(xy 221.573897 -76.686343) (xy 221.591081 -76.692858) (xy 221.600268 -76.693268) (xy 221.629732 -76.693268)
			(xy 221.638925 -76.69288) (xy 221.656121 -76.686372) (xy 221.66326 -76.680568) (xy 221.69366 -76.654489)
			(xy 221.758384 -76.607295) (xy 221.827085 -76.566106) (xy 221.899209 -76.531255) (xy 221.974172 -76.503025)
			(xy 222.051368 -76.481643) (xy 222.130173 -76.467283) (xy 222.209949 -76.46006) (xy 222.25 -76.459588)
			(xy 222.290054 -76.460025) (xy 222.369837 -76.467222) (xy 222.44865 -76.481568) (xy 222.525852 -76.502945)
			(xy 222.600818 -76.531181) (xy 222.67294 -76.566047) (xy 222.741634 -76.607259) (xy 222.806341 -76.654484)
			(xy 222.83674 -76.680568) (xy 222.843897 -76.686343) (xy 222.861081 -76.692858) (xy 222.870268 -76.693268)
			(xy 222.899732 -76.693268) (xy 222.908925 -76.69288) (xy 222.926121 -76.686372) (xy 222.93326 -76.680568)
			(xy 222.96366 -76.654489) (xy 223.028384 -76.607295) (xy 223.097085 -76.566106) (xy 223.169209 -76.531255)
			(xy 223.244172 -76.503025) (xy 223.321368 -76.481643) (xy 223.400173 -76.467283) (xy 223.479949 -76.46006)
			(xy 223.52 -76.459588) (xy 223.562358 -76.460092) (xy 223.646691 -76.468145) (xy 223.729876 -76.484177)
			(xy 223.811161 -76.508045) (xy 223.889809 -76.539531) (xy 223.965108 -76.57835) (xy 224.036376 -76.624151)
			(xy 224.102968 -76.676519) (xy 224.16428 -76.73498) (xy 224.219757 -76.799005) (xy 224.268898 -76.868013)
			(xy 224.311256 -76.941379) (xy 224.346448 -77.01844) (xy 224.374156 -77.098497) (xy 224.394129 -77.180825)
			(xy 224.406186 -77.26468) (xy 224.410217 -77.3493) (xy 224.406186 -77.43392) (xy 224.394129 -77.517775)
			(xy 224.374156 -77.600103) (xy 224.346448 -77.68016) (xy 224.311256 -77.757221) (xy 224.268898 -77.830587)
			(xy 224.224196 -77.893361) (xy 229.219756 -77.893361) (xy 229.219756 -77.808639) (xy 229.227809 -77.724302)
			(xy 229.243843 -77.641112) (xy 229.267711 -77.559822) (xy 229.299199 -77.48117) (xy 229.338021 -77.405867)
			(xy 229.383824 -77.334595) (xy 229.436195 -77.267999) (xy 229.49466 -77.206684) (xy 229.558688 -77.151203)
			(xy 229.6277 -77.10206) (xy 229.70107 -77.0597) (xy 229.778135 -77.024505) (xy 229.858197 -76.996796)
			(xy 229.94053 -76.976822) (xy 230.024389 -76.964765) (xy 230.109014 -76.960734) (xy 230.193639 -76.964765)
			(xy 230.277498 -76.976822) (xy 230.359831 -76.996796) (xy 230.439893 -77.024505) (xy 230.516958 -77.0597)
			(xy 230.590328 -77.10206) (xy 230.65934 -77.151203) (xy 230.723368 -77.206684) (xy 230.781833 -77.267999)
			(xy 230.834204 -77.334595) (xy 230.880007 -77.405867) (xy 230.918829 -77.48117) (xy 230.950317 -77.559822)
			(xy 230.974185 -77.641112) (xy 230.990219 -77.724302) (xy 230.998272 -77.808639) (xy 230.998776 -77.851)
			(xy 230.998272 -77.893361) (xy 230.990219 -77.977698) (xy 230.974185 -78.060888) (xy 230.950317 -78.142178)
			(xy 230.918829 -78.22083) (xy 230.880007 -78.296133) (xy 230.834204 -78.367405) (xy 230.781833 -78.434001)
			(xy 230.723368 -78.495316) (xy 230.65934 -78.550797) (xy 230.590328 -78.59994) (xy 230.516958 -78.6423)
			(xy 230.439893 -78.677495) (xy 230.359831 -78.705204) (xy 230.277498 -78.725178) (xy 230.193639 -78.737235)
			(xy 230.109014 -78.741267) (xy 230.024389 -78.737235) (xy 229.94053 -78.725178) (xy 229.858197 -78.705204)
			(xy 229.778135 -78.677495) (xy 229.70107 -78.6423) (xy 229.6277 -78.59994) (xy 229.558688 -78.550797)
			(xy 229.49466 -78.495316) (xy 229.436195 -78.434001) (xy 229.383824 -78.367405) (xy 229.338021 -78.296133)
			(xy 229.299199 -78.22083) (xy 229.267711 -78.142178) (xy 229.243843 -78.060888) (xy 229.227809 -77.977698)
			(xy 229.219756 -77.893361) (xy 224.224196 -77.893361) (xy 224.219757 -77.899595) (xy 224.16428 -77.96362)
			(xy 224.102968 -78.022081) (xy 224.036376 -78.074449) (xy 223.965108 -78.12025) (xy 223.889809 -78.159069)
			(xy 223.811161 -78.190555) (xy 223.729876 -78.214423) (xy 223.646691 -78.230455) (xy 223.562358 -78.238508)
			(xy 223.52 -78.239112) (xy 223.479946 -78.238675) (xy 223.400163 -78.231478) (xy 223.32135 -78.217132)
			(xy 223.244148 -78.195755) (xy 223.169182 -78.167519) (xy 223.09706 -78.132653) (xy 223.028366 -78.091441)
			(xy 222.963659 -78.044216) (xy 222.93326 -78.018132) (xy 222.926103 -78.012357) (xy 222.908919 -78.005842)
			(xy 222.899732 -78.005432) (xy 222.870268 -78.005432) (xy 222.861075 -78.00582) (xy 222.843879 -78.012328)
			(xy 222.83674 -78.018132) (xy 222.80634 -78.044211) (xy 222.741616 -78.091405) (xy 222.672915 -78.132594)
			(xy 222.600791 -78.167445) (xy 222.525828 -78.195675) (xy 222.448632 -78.217057) (xy 222.369827 -78.231417)
			(xy 222.290051 -78.23864) (xy 222.25 -78.239112) (xy 222.209946 -78.238675) (xy 222.130163 -78.231478)
			(xy 222.05135 -78.217132) (xy 221.974148 -78.195755) (xy 221.899182 -78.167519) (xy 221.82706 -78.132653)
			(xy 221.758366 -78.091441) (xy 221.693659 -78.044216) (xy 221.66326 -78.018132) (xy 221.656103 -78.012357)
			(xy 221.638919 -78.005842) (xy 221.629732 -78.005432) (xy 221.600268 -78.005432) (xy 221.591075 -78.00582)
			(xy 221.573879 -78.012328) (xy 221.56674 -78.018132) (xy 221.53634 -78.044211) (xy 221.471616 -78.091405)
			(xy 221.402915 -78.132594) (xy 221.330791 -78.167445) (xy 221.255828 -78.195675) (xy 221.178632 -78.217057)
			(xy 221.099827 -78.231417) (xy 221.020051 -78.23864) (xy 220.98 -78.239112) (xy 220.933009 -78.238506)
			(xy 220.839551 -78.228603) (xy 220.74766 -78.208895) (xy 220.658359 -78.179604) (xy 220.615256 -78.16088)
			(xy 220.603572 -78.155546) (xy 220.577664 -78.157578) (xy 220.495114 -78.210918) (xy 220.488182 -78.21578)
			(xy 220.477765 -78.229116) (xy 220.472287 -78.245128) (xy 220.472 -78.25359) (xy 220.472 -78.543912)
			(xy 220.472709 -78.556642) (xy 220.484846 -78.579025) (xy 220.495114 -78.586584) (xy 220.577664 -78.639924)
			(xy 220.603572 -78.641956) (xy 220.615256 -78.636622) (xy 220.658251 -78.617985) (xy 220.747308 -78.588814)
			(xy 220.838939 -78.56917) (xy 220.932128 -78.559271) (xy 220.978984 -78.558644) (xy 220.98 -78.558644)
			(xy 221.022351 -78.559148) (xy 221.106669 -78.567199) (xy 221.18984 -78.583229) (xy 221.27111 -78.607092)
			(xy 221.349744 -78.638572) (xy 221.42503 -78.677385) (xy 221.496286 -78.723178) (xy 221.562866 -78.775537)
			(xy 221.624167 -78.833988) (xy 221.679635 -78.898001) (xy 221.728767 -78.966997) (xy 221.771117 -79.040351)
			(xy 221.806304 -79.117398) (xy 221.834007 -79.197441) (xy 221.853976 -79.279755) (xy 221.86603 -79.363594)
			(xy 221.870061 -79.4482) (xy 221.867234 -79.507531) (xy 222.630742 -79.507531) (xy 222.630742 -79.422809)
			(xy 222.638795 -79.338472) (xy 222.654829 -79.255282) (xy 222.678697 -79.173992) (xy 222.710185 -79.09534)
			(xy 222.749007 -79.020037) (xy 222.79481 -78.948765) (xy 222.847181 -78.882169) (xy 222.905646 -78.820854)
			(xy 222.969674 -78.765373) (xy 223.038686 -78.71623) (xy 223.112056 -78.67387) (xy 223.189121 -78.638675)
			(xy 223.269183 -78.610966) (xy 223.351516 -78.590992) (xy 223.435375 -78.578935) (xy 223.52 -78.574904)
			(xy 223.604625 -78.578935) (xy 223.688484 -78.590992) (xy 223.770817 -78.610966) (xy 223.850879 -78.638675)
			(xy 223.927944 -78.67387) (xy 224.001314 -78.71623) (xy 224.070326 -78.765373) (xy 224.134354 -78.820854)
			(xy 224.192819 -78.882169) (xy 224.24519 -78.948765) (xy 224.290993 -79.020037) (xy 224.329815 -79.09534)
			(xy 224.361303 -79.173992) (xy 224.385171 -79.255282) (xy 224.401205 -79.338472) (xy 224.409258 -79.422809)
			(xy 224.409762 -79.46517) (xy 224.409258 -79.507531) (xy 224.401205 -79.591868) (xy 224.385171 -79.675058)
			(xy 224.361303 -79.756348) (xy 224.329815 -79.835) (xy 224.290993 -79.910303) (xy 224.24519 -79.981575)
			(xy 224.192819 -80.048171) (xy 224.134354 -80.109486) (xy 224.114327 -80.12684) (xy 235.457492 -80.12684)
			(xy 235.458084 -80.083505) (xy 235.466508 -79.997245) (xy 235.483279 -79.912213) (xy 235.508239 -79.829215)
			(xy 235.541152 -79.749037) (xy 235.581705 -79.67244) (xy 235.629513 -79.600148) (xy 235.684125 -79.532848)
			(xy 235.745022 -79.471178) (xy 235.811627 -79.415721) (xy 235.883309 -79.367003) (xy 235.959388 -79.325486)
			(xy 236.039144 -79.291564) (xy 236.12182 -79.265558) (xy 236.16412 -79.256128) (xy 236.175804 -79.253588)
			(xy 236.194092 -79.239364) (xy 236.234478 -79.156306) (xy 236.239114 -79.145607) (xy 236.239095 -79.122311)
			(xy 236.234478 -79.111602) (xy 236.216775 -79.074785) (xy 236.187432 -78.998536) (xy 236.1652 -78.91992)
			(xy 236.150264 -78.839597) (xy 236.142751 -78.758244) (xy 236.142276 -78.717394) (xy 236.142276 -78.71714)
			(xy 236.14278 -78.674792) (xy 236.150831 -78.590478) (xy 236.16686 -78.507312) (xy 236.190721 -78.426045)
			(xy 236.2222 -78.347415) (xy 236.261011 -78.272134) (xy 236.306801 -78.200882) (xy 236.359157 -78.134306)
			(xy 236.417605 -78.073008) (xy 236.481615 -78.017543) (xy 236.550607 -77.968414) (xy 236.623957 -77.926065)
			(xy 236.701 -77.890881) (xy 236.781039 -77.863179) (xy 236.863348 -77.843211) (xy 236.947183 -77.831158)
			(xy 237.031784 -77.827128) (xy 237.116385 -77.831158) (xy 237.20022 -77.843211) (xy 237.282529 -77.863179)
			(xy 237.362568 -77.890881) (xy 237.439611 -77.926065) (xy 237.512961 -77.968414) (xy 237.581953 -78.017543)
			(xy 237.645963 -78.073008) (xy 237.704411 -78.134306) (xy 237.756767 -78.200882) (xy 237.802557 -78.272134)
			(xy 237.841368 -78.347415) (xy 237.872847 -78.426045) (xy 237.896708 -78.507312) (xy 237.912737 -78.590478)
			(xy 237.920788 -78.674792) (xy 237.921292 -78.71714) (xy 237.920787 -78.760477) (xy 237.912356 -78.84674)
			(xy 237.895576 -78.931774) (xy 237.870609 -79.014774) (xy 237.837689 -79.094953) (xy 237.797129 -79.171551)
			(xy 237.749313 -79.243843) (xy 237.694695 -79.311142) (xy 237.633791 -79.372812) (xy 237.56718 -79.428268)
			(xy 237.495493 -79.476984) (xy 237.419408 -79.518499) (xy 237.339647 -79.552419) (xy 237.256966 -79.578424)
			(xy 237.214664 -79.587852) (xy 237.20298 -79.590392) (xy 237.184692 -79.604616) (xy 237.144306 -79.687674)
			(xy 237.139684 -79.698377) (xy 237.139695 -79.721669) (xy 237.144306 -79.732378) (xy 237.162008 -79.769196)
			(xy 237.19135 -79.845444) (xy 237.213582 -79.924061) (xy 237.228518 -80.004383) (xy 237.236032 -80.085736)
			(xy 237.236508 -80.126586) (xy 237.236508 -80.12684) (xy 237.236004 -80.169188) (xy 237.227953 -80.253502)
			(xy 237.211924 -80.336668) (xy 237.188063 -80.417935) (xy 237.156584 -80.496565) (xy 237.117773 -80.571846)
			(xy 237.071983 -80.643098) (xy 237.019627 -80.709674) (xy 236.961179 -80.770972) (xy 236.897169 -80.826437)
			(xy 236.828177 -80.875566) (xy 236.754827 -80.917915) (xy 236.677784 -80.953099) (xy 236.597745 -80.980801)
			(xy 236.515436 -81.000769) (xy 236.431601 -81.012822) (xy 236.347 -81.016853) (xy 236.262399 -81.012822)
			(xy 236.178564 -81.000769) (xy 236.096255 -80.980801) (xy 236.016216 -80.953099) (xy 235.939173 -80.917915)
			(xy 235.865823 -80.875566) (xy 235.796831 -80.826437) (xy 235.732821 -80.770972) (xy 235.674373 -80.709674)
			(xy 235.622017 -80.643098) (xy 235.576227 -80.571846) (xy 235.537416 -80.496565) (xy 235.505937 -80.417935)
			(xy 235.482076 -80.336668) (xy 235.466047 -80.253502) (xy 235.457996 -80.169188) (xy 235.457492 -80.12684)
			(xy 224.114327 -80.12684) (xy 224.070326 -80.164967) (xy 224.001314 -80.21411) (xy 223.927944 -80.25647)
			(xy 223.850879 -80.291665) (xy 223.770817 -80.319374) (xy 223.688484 -80.339348) (xy 223.604625 -80.351405)
			(xy 223.52 -80.355437) (xy 223.435375 -80.351405) (xy 223.351516 -80.339348) (xy 223.269183 -80.319374)
			(xy 223.189121 -80.291665) (xy 223.112056 -80.25647) (xy 223.038686 -80.21411) (xy 222.969674 -80.164967)
			(xy 222.905646 -80.109486) (xy 222.847181 -80.048171) (xy 222.79481 -79.981575) (xy 222.749007 -79.910303)
			(xy 222.710185 -79.835) (xy 222.678697 -79.756348) (xy 222.654829 -79.675058) (xy 222.638795 -79.591868)
			(xy 222.630742 -79.507531) (xy 221.867234 -79.507531) (xy 221.86603 -79.532806) (xy 221.853976 -79.616645)
			(xy 221.834007 -79.698959) (xy 221.806304 -79.779002) (xy 221.771117 -79.856049) (xy 221.728767 -79.929403)
			(xy 221.679635 -79.998399) (xy 221.624167 -80.062412) (xy 221.562866 -80.120863) (xy 221.496286 -80.173222)
			(xy 221.42503 -80.219015) (xy 221.349744 -80.257828) (xy 221.27111 -80.289308) (xy 221.18984 -80.313171)
			(xy 221.106669 -80.329201) (xy 221.022351 -80.337252) (xy 220.98 -80.33766) (xy 220.978984 -80.33766)
			(xy 220.932128 -80.337031) (xy 220.83894 -80.327127) (xy 220.747309 -80.307484) (xy 220.65825 -80.278319)
			(xy 220.615256 -80.259682) (xy 220.603572 -80.254348) (xy 220.577664 -80.25638) (xy 220.495114 -80.30972)
			(xy 220.488182 -80.314582) (xy 220.477766 -80.327919) (xy 220.472288 -80.34393) (xy 220.472 -80.352392)
			(xy 220.472 -81.415325) (xy 229.219756 -81.415325) (xy 229.219756 -81.330603) (xy 229.227809 -81.246266)
			(xy 229.243843 -81.163076) (xy 229.267711 -81.081786) (xy 229.299199 -81.003134) (xy 229.338021 -80.927831)
			(xy 229.383824 -80.856559) (xy 229.436195 -80.789963) (xy 229.49466 -80.728648) (xy 229.558688 -80.673167)
			(xy 229.6277 -80.624024) (xy 229.70107 -80.581664) (xy 229.778135 -80.546469) (xy 229.858197 -80.51876)
			(xy 229.94053 -80.498786) (xy 230.024389 -80.486729) (xy 230.109014 -80.482698) (xy 230.193639 -80.486729)
			(xy 230.277498 -80.498786) (xy 230.359831 -80.51876) (xy 230.439893 -80.546469) (xy 230.516958 -80.581664)
			(xy 230.590328 -80.624024) (xy 230.65934 -80.673167) (xy 230.723368 -80.728648) (xy 230.781833 -80.789963)
			(xy 230.834204 -80.856559) (xy 230.880007 -80.927831) (xy 230.918829 -81.003134) (xy 230.950317 -81.081786)
			(xy 230.974185 -81.163076) (xy 230.990219 -81.246266) (xy 230.998272 -81.330603) (xy 230.998776 -81.372964)
			(xy 230.998272 -81.415325) (xy 230.990219 -81.499662) (xy 230.974185 -81.582852) (xy 230.950317 -81.664142)
			(xy 230.918829 -81.742794) (xy 230.880007 -81.818097) (xy 230.834204 -81.889369) (xy 230.781833 -81.955965)
			(xy 230.723368 -82.01728) (xy 230.65934 -82.072761) (xy 230.590328 -82.121904) (xy 230.516958 -82.164264)
			(xy 230.439893 -82.199459) (xy 230.359831 -82.227168) (xy 230.277498 -82.247142) (xy 230.193639 -82.259199)
			(xy 230.109014 -82.263231) (xy 230.024389 -82.259199) (xy 229.94053 -82.247142) (xy 229.858197 -82.227168)
			(xy 229.778135 -82.199459) (xy 229.70107 -82.164264) (xy 229.6277 -82.121904) (xy 229.558688 -82.072761)
			(xy 229.49466 -82.01728) (xy 229.436195 -81.955965) (xy 229.383824 -81.889369) (xy 229.338021 -81.818097)
			(xy 229.299199 -81.742794) (xy 229.267711 -81.664142) (xy 229.243843 -81.582852) (xy 229.227809 -81.499662)
			(xy 229.219756 -81.415325) (xy 220.472 -81.415325) (xy 220.472 -83.3056) (xy 228.598784 -83.3056)
			(xy 228.602814 -83.22098) (xy 228.614871 -83.137125) (xy 228.634844 -83.054797) (xy 228.662552 -82.97474)
			(xy 228.697744 -82.897679) (xy 228.740102 -82.824313) (xy 228.789243 -82.755305) (xy 228.84472 -82.69128)
			(xy 228.906032 -82.632819) (xy 228.972624 -82.580451) (xy 229.043892 -82.53465) (xy 229.119191 -82.495831)
			(xy 229.197839 -82.464345) (xy 229.279124 -82.440477) (xy 229.362309 -82.424445) (xy 229.446642 -82.416392)
			(xy 229.489 -82.415888) (xy 229.530512 -82.41638) (xy 229.613172 -82.424148) (xy 229.694748 -82.439588)
			(xy 229.774529 -82.462566) (xy 229.851821 -82.492881) (xy 229.92595 -82.53027) (xy 229.99627 -82.574407)
			(xy 230.029512 -82.599276) (xy 230.038711 -82.605619) (xy 230.0605 -82.61045) (xy 230.082289 -82.605619)
			(xy 230.091488 -82.599276) (xy 230.124746 -82.574432) (xy 230.195072 -82.53031) (xy 230.269201 -82.492931)
			(xy 230.34649 -82.462618) (xy 230.426266 -82.439635) (xy 230.507836 -82.424183) (xy 230.59049 -82.416395)
			(xy 230.632 -82.415888) (xy 230.673512 -82.41638) (xy 230.756172 -82.424148) (xy 230.837748 -82.439588)
			(xy 230.917529 -82.462566) (xy 230.994821 -82.492881) (xy 231.06895 -82.53027) (xy 231.13927 -82.574407)
			(xy 231.172512 -82.599276) (xy 231.181711 -82.605619) (xy 231.2035 -82.61045) (xy 231.225289 -82.605619)
			(xy 231.234488 -82.599276) (xy 231.270142 -82.57265) (xy 231.345838 -82.525859) (xy 231.425826 -82.486856)
			(xy 231.509307 -82.45603) (xy 231.552242 -82.444336) (xy 231.563084 -82.440862) (xy 231.580486 -82.426226)
			(xy 231.58577 -82.416142) (xy 231.618282 -82.344006) (xy 231.622573 -82.333314) (xy 231.622029 -82.310302)
			(xy 231.617266 -82.29981) (xy 231.598716 -82.262296) (xy 231.56794 -82.184465) (xy 231.544602 -82.10409)
			(xy 231.528909 -82.021879) (xy 231.520999 -81.938559) (xy 231.520492 -81.896712) (xy 231.520492 -81.89595)
			(xy 231.520996 -81.853602) (xy 231.529047 -81.769288) (xy 231.545076 -81.686122) (xy 231.568937 -81.604855)
			(xy 231.600416 -81.526225) (xy 231.639227 -81.450944) (xy 231.685017 -81.379692) (xy 231.737373 -81.313116)
			(xy 231.795821 -81.251818) (xy 231.859831 -81.196353) (xy 231.928823 -81.147224) (xy 232.002173 -81.104875)
			(xy 232.079216 -81.069691) (xy 232.159255 -81.041989) (xy 232.241564 -81.022021) (xy 232.325399 -81.009968)
			(xy 232.41 -81.005938) (xy 232.494601 -81.009968) (xy 232.578436 -81.022021) (xy 232.660745 -81.041989)
			(xy 232.740784 -81.069691) (xy 232.817827 -81.104875) (xy 232.891177 -81.147224) (xy 232.960169 -81.196353)
			(xy 233.024179 -81.251818) (xy 233.082627 -81.313116) (xy 233.134983 -81.379692) (xy 233.180773 -81.450944)
			(xy 233.219584 -81.526225) (xy 233.251063 -81.604855) (xy 233.274924 -81.686122) (xy 233.290953 -81.769288)
			(xy 233.299004 -81.853602) (xy 233.299508 -81.89595) (xy 233.298994 -81.937821) (xy 233.291121 -82.021191)
			(xy 233.27545 -82.103453) (xy 233.252119 -82.183878) (xy 233.221334 -82.261756) (xy 233.183369 -82.336396)
			(xy 233.138559 -82.40714) (xy 233.087299 -82.47336) (xy 233.030045 -82.534471) (xy 232.967303 -82.589932)
			(xy 232.899626 -82.639253) (xy 232.827616 -82.681996) (xy 232.751907 -82.717785) (xy 232.673171 -82.746302)
			(xy 232.632758 -82.757264) (xy 232.621916 -82.760738) (xy 232.604514 -82.775374) (xy 232.59923 -82.785458)
			(xy 232.566718 -82.857594) (xy 232.562427 -82.868286) (xy 232.562971 -82.891298) (xy 232.567734 -82.90179)
			(xy 232.586315 -82.939374) (xy 232.617134 -83.017352) (xy 232.640486 -83.097881) (xy 232.656166 -83.180249)
			(xy 232.664033 -83.263726) (xy 232.664508 -83.30565) (xy 232.664022 -83.347993) (xy 232.655995 -83.432297)
			(xy 232.639998 -83.515458) (xy 232.616178 -83.596725) (xy 232.584748 -83.675362) (xy 232.545992 -83.750659)
			(xy 232.500262 -83.821936) (xy 232.447971 -83.888549) (xy 232.419144 -83.919568) (xy 232.411956 -83.927948)
			(xy 232.404859 -83.948828) (xy 232.407134 -83.970764) (xy 232.412286 -83.980528) (xy 232.432279 -84.014995)
			(xy 232.46675 -84.086842) (xy 232.49466 -84.161483) (xy 232.515787 -84.238319) (xy 232.529962 -84.316736)
			(xy 232.537072 -84.396106) (xy 232.537508 -84.43595) (xy 232.537014 -84.480384) (xy 232.528235 -84.568816)
			(xy 232.519982 -84.61248) (xy 232.517442 -84.624418) (xy 232.524046 -84.647532) (xy 232.587546 -84.717128)
			(xy 232.596183 -84.72564) (xy 232.618873 -84.73411) (xy 232.63098 -84.733384) (xy 232.655662 -84.730773)
			(xy 232.705221 -84.72798) (xy 232.73004 -84.727796) (xy 232.77196 -84.728317) (xy 232.855429 -84.736211)
			(xy 232.937784 -84.751923) (xy 233.018296 -84.775316) (xy 233.096248 -84.806182) (xy 233.170951 -84.844245)
			(xy 233.24174 -84.88917) (xy 233.307987 -84.940557) (xy 233.369105 -84.997949) (xy 233.424551 -85.060838)
			(xy 233.473833 -85.128666) (xy 233.516514 -85.20083) (xy 233.552214 -85.27669) (xy 233.580618 -85.355573)
			(xy 233.601472 -85.436779) (xy 233.614592 -85.519587) (xy 233.619862 -85.603263) (xy 233.617234 -85.687062)
			(xy 233.606732 -85.770243) (xy 233.58845 -85.852066) (xy 233.562549 -85.931806) (xy 233.529259 -86.008755)
			(xy 233.488876 -86.082229) (xy 233.441757 -86.151577) (xy 233.388323 -86.216184) (xy 233.329046 -86.275476)
			(xy 233.264452 -86.328927) (xy 233.195115 -86.376062) (xy 233.12165 -86.416463) (xy 233.04471 -86.449771)
			(xy 232.964977 -86.475692) (xy 232.883158 -86.493995) (xy 232.79998 -86.504517) (xy 232.716181 -86.507165)
			(xy 232.632504 -86.501916) (xy 232.549693 -86.488816) (xy 232.468482 -86.467982) (xy 232.389592 -86.439598)
			(xy 232.313723 -86.403916) (xy 232.241548 -86.361253) (xy 232.173708 -86.311988) (xy 232.110806 -86.256557)
			(xy 232.053398 -86.195453) (xy 232.001995 -86.129218) (xy 231.957053 -86.05844) (xy 231.918971 -85.983747)
			(xy 231.888087 -85.905802) (xy 231.864674 -85.825296) (xy 231.848941 -85.742945) (xy 231.841027 -85.659478)
			(xy 231.840532 -85.617558) (xy 231.841027 -85.573124) (xy 231.849805 -85.484692) (xy 231.858058 -85.441028)
			(xy 231.860598 -85.42909) (xy 231.853994 -85.405976) (xy 231.790494 -85.33638) (xy 231.781839 -85.32789)
			(xy 231.759163 -85.319407) (xy 231.74706 -85.320124) (xy 231.722378 -85.322731) (xy 231.672819 -85.325527)
			(xy 231.648 -85.325712) (xy 231.606889 -85.325248) (xy 231.525019 -85.31766) (xy 231.444199 -85.302549)
			(xy 231.365118 -85.280044) (xy 231.288451 -85.250338) (xy 231.214853 -85.213682) (xy 231.144951 -85.170392)
			(xy 231.079343 -85.120835) (xy 231.018588 -85.065435) (xy 230.963205 -85.004665) (xy 230.913667 -84.939043)
			(xy 230.870396 -84.869129) (xy 230.833761 -84.79552) (xy 230.804076 -84.718845) (xy 230.781594 -84.639758)
			(xy 230.766506 -84.558933) (xy 230.758941 -84.477061) (xy 230.758492 -84.43595) (xy 230.758696 -84.404476)
			(xy 230.763021 -84.341679) (xy 230.767128 -84.310474) (xy 230.768906 -84.299298) (xy 230.762302 -84.277962)
			(xy 230.702612 -84.211414) (xy 230.694763 -84.203557) (xy 230.674346 -84.194874) (xy 230.663242 -84.19465)
			(xy 230.662734 -84.19465) (xy 230.632254 -84.195412) (xy 230.631746 -84.195412) (xy 230.590252 -84.194909)
			(xy 230.50763 -84.187124) (xy 230.426093 -84.171674) (xy 230.34635 -84.148693) (xy 230.269096 -84.118382)
			(xy 230.195003 -84.081003) (xy 230.124715 -84.036883) (xy 230.091488 -84.012024) (xy 230.082289 -84.005681)
			(xy 230.0605 -84.00085) (xy 230.038711 -84.005681) (xy 230.029512 -84.012024) (xy 229.996254 -84.036868)
			(xy 229.925928 -84.08099) (xy 229.851799 -84.118369) (xy 229.77451 -84.148682) (xy 229.694734 -84.171665)
			(xy 229.613164 -84.187117) (xy 229.53051 -84.194905) (xy 229.489 -84.195412) (xy 229.446642 -84.194808)
			(xy 229.362309 -84.186755) (xy 229.279124 -84.170723) (xy 229.197839 -84.146855) (xy 229.119191 -84.115369)
			(xy 229.043892 -84.07655) (xy 228.972624 -84.030749) (xy 228.906032 -83.978381) (xy 228.84472 -83.91992)
			(xy 228.789243 -83.855895) (xy 228.740102 -83.786887) (xy 228.697744 -83.713521) (xy 228.662552 -83.63646)
			(xy 228.634844 -83.556403) (xy 228.614871 -83.474075) (xy 228.602814 -83.39022) (xy 228.598784 -83.3056)
			(xy 220.472 -83.3056) (xy 220.472 -88.249703) (xy 221.360742 -88.249703) (xy 221.360742 -88.164981)
			(xy 221.368795 -88.080644) (xy 221.384829 -87.997454) (xy 221.408697 -87.916164) (xy 221.440185 -87.837512)
			(xy 221.479007 -87.762209) (xy 221.52481 -87.690937) (xy 221.577181 -87.624341) (xy 221.635646 -87.563026)
			(xy 221.699674 -87.507545) (xy 221.768686 -87.458402) (xy 221.842056 -87.416042) (xy 221.919121 -87.380847)
			(xy 221.999183 -87.353138) (xy 222.081516 -87.333164) (xy 222.165375 -87.321107) (xy 222.25 -87.317076)
			(xy 222.334625 -87.321107) (xy 222.418484 -87.333164) (xy 222.500817 -87.353138) (xy 222.580879 -87.380847)
			(xy 222.657944 -87.416042) (xy 222.731314 -87.458402) (xy 222.800326 -87.507545) (xy 222.864354 -87.563026)
			(xy 222.922819 -87.624341) (xy 222.97519 -87.690937) (xy 223.020993 -87.762209) (xy 223.040146 -87.799361)
			(xy 233.740702 -87.799361) (xy 233.740702 -87.714639) (xy 233.748755 -87.630302) (xy 233.764789 -87.547112)
			(xy 233.788657 -87.465822) (xy 233.820145 -87.38717) (xy 233.858967 -87.311867) (xy 233.90477 -87.240595)
			(xy 233.957141 -87.173999) (xy 234.015606 -87.112684) (xy 234.079634 -87.057203) (xy 234.148646 -87.00806)
			(xy 234.222016 -86.9657) (xy 234.299081 -86.930505) (xy 234.379143 -86.902796) (xy 234.461476 -86.882822)
			(xy 234.545335 -86.870765) (xy 234.62996 -86.866734) (xy 234.714585 -86.870765) (xy 234.798444 -86.882822)
			(xy 234.880777 -86.902796) (xy 234.960839 -86.930505) (xy 235.037904 -86.9657) (xy 235.111274 -87.00806)
			(xy 235.180286 -87.057203) (xy 235.244314 -87.112684) (xy 235.302779 -87.173999) (xy 235.35515 -87.240595)
			(xy 235.400953 -87.311867) (xy 235.439775 -87.38717) (xy 235.471263 -87.465822) (xy 235.495131 -87.547112)
			(xy 235.511165 -87.630302) (xy 235.511373 -87.632483) (xy 236.18342 -87.632483) (xy 236.18342 -87.547761)
			(xy 236.191473 -87.463424) (xy 236.207507 -87.380234) (xy 236.231375 -87.298944) (xy 236.262863 -87.220292)
			(xy 236.301685 -87.144989) (xy 236.347488 -87.073717) (xy 236.399859 -87.007121) (xy 236.458324 -86.945806)
			(xy 236.522352 -86.890325) (xy 236.591364 -86.841182) (xy 236.664734 -86.798822) (xy 236.741799 -86.763627)
			(xy 236.821861 -86.735918) (xy 236.904194 -86.715944) (xy 236.988053 -86.703887) (xy 237.072678 -86.699856)
			(xy 237.157303 -86.703887) (xy 237.241162 -86.715944) (xy 237.323495 -86.735918) (xy 237.403557 -86.763627)
			(xy 237.480622 -86.798822) (xy 237.553992 -86.841182) (xy 237.623004 -86.890325) (xy 237.687032 -86.945806)
			(xy 237.745497 -87.007121) (xy 237.797868 -87.073717) (xy 237.843671 -87.144989) (xy 237.882493 -87.220292)
			(xy 237.913981 -87.298944) (xy 237.937849 -87.380234) (xy 237.953883 -87.463424) (xy 237.961076 -87.538757)
			(xy 238.133632 -87.538757) (xy 238.133632 -87.454035) (xy 238.141685 -87.369698) (xy 238.157719 -87.286508)
			(xy 238.181587 -87.205218) (xy 238.213075 -87.126566) (xy 238.251897 -87.051263) (xy 238.2977 -86.979991)
			(xy 238.350071 -86.913395) (xy 238.408536 -86.85208) (xy 238.472564 -86.796599) (xy 238.541576 -86.747456)
			(xy 238.614946 -86.705096) (xy 238.692011 -86.669901) (xy 238.772073 -86.642192) (xy 238.854406 -86.622218)
			(xy 238.938265 -86.610161) (xy 239.02289 -86.60613) (xy 239.107515 -86.610161) (xy 239.191374 -86.622218)
			(xy 239.273707 -86.642192) (xy 239.353769 -86.669901) (xy 239.430834 -86.705096) (xy 239.504204 -86.747456)
			(xy 239.573216 -86.796599) (xy 239.637244 -86.85208) (xy 239.695709 -86.913395) (xy 239.74808 -86.979991)
			(xy 239.793883 -87.051263) (xy 239.832705 -87.126566) (xy 239.864193 -87.205218) (xy 239.888061 -87.286508)
			(xy 239.904095 -87.369698) (xy 239.912148 -87.454035) (xy 239.912652 -87.496396) (xy 239.912148 -87.538757)
			(xy 239.904095 -87.623094) (xy 239.888061 -87.706284) (xy 239.864193 -87.787574) (xy 239.832705 -87.866226)
			(xy 239.793883 -87.941529) (xy 239.74808 -88.012801) (xy 239.695709 -88.079397) (xy 239.637244 -88.140712)
			(xy 239.573216 -88.196193) (xy 239.504204 -88.245336) (xy 239.430834 -88.287696) (xy 239.353769 -88.322891)
			(xy 239.273707 -88.3506) (xy 239.191374 -88.370574) (xy 239.107515 -88.382631) (xy 239.02289 -88.386663)
			(xy 238.938265 -88.382631) (xy 238.854406 -88.370574) (xy 238.772073 -88.3506) (xy 238.692011 -88.322891)
			(xy 238.614946 -88.287696) (xy 238.541576 -88.245336) (xy 238.472564 -88.196193) (xy 238.408536 -88.140712)
			(xy 238.350071 -88.079397) (xy 238.2977 -88.012801) (xy 238.251897 -87.941529) (xy 238.213075 -87.866226)
			(xy 238.181587 -87.787574) (xy 238.157719 -87.706284) (xy 238.141685 -87.623094) (xy 238.133632 -87.538757)
			(xy 237.961076 -87.538757) (xy 237.961936 -87.547761) (xy 237.96244 -87.590122) (xy 237.961936 -87.632483)
			(xy 237.953883 -87.71682) (xy 237.937849 -87.80001) (xy 237.913981 -87.8813) (xy 237.882493 -87.959952)
			(xy 237.843671 -88.035255) (xy 237.797868 -88.106527) (xy 237.745497 -88.173123) (xy 237.687032 -88.234438)
			(xy 237.623004 -88.289919) (xy 237.553992 -88.339062) (xy 237.480622 -88.381422) (xy 237.403557 -88.416617)
			(xy 237.323495 -88.444326) (xy 237.241162 -88.4643) (xy 237.157303 -88.476357) (xy 237.072678 -88.480389)
			(xy 236.988053 -88.476357) (xy 236.904194 -88.4643) (xy 236.821861 -88.444326) (xy 236.741799 -88.416617)
			(xy 236.664734 -88.381422) (xy 236.591364 -88.339062) (xy 236.522352 -88.289919) (xy 236.458324 -88.234438)
			(xy 236.399859 -88.173123) (xy 236.347488 -88.106527) (xy 236.301685 -88.035255) (xy 236.262863 -87.959952)
			(xy 236.231375 -87.8813) (xy 236.207507 -87.80001) (xy 236.191473 -87.71682) (xy 236.18342 -87.632483)
			(xy 235.511373 -87.632483) (xy 235.519218 -87.714639) (xy 235.519722 -87.757) (xy 235.519218 -87.799361)
			(xy 235.511165 -87.883698) (xy 235.495131 -87.966888) (xy 235.471263 -88.048178) (xy 235.439775 -88.12683)
			(xy 235.400953 -88.202133) (xy 235.35515 -88.273405) (xy 235.302779 -88.340001) (xy 235.244314 -88.401316)
			(xy 235.180286 -88.456797) (xy 235.111274 -88.50594) (xy 235.037904 -88.5483) (xy 234.960839 -88.583495)
			(xy 234.880777 -88.611204) (xy 234.798444 -88.631178) (xy 234.714585 -88.643235) (xy 234.62996 -88.647267)
			(xy 234.545335 -88.643235) (xy 234.461476 -88.631178) (xy 234.379143 -88.611204) (xy 234.299081 -88.583495)
			(xy 234.222016 -88.5483) (xy 234.148646 -88.50594) (xy 234.079634 -88.456797) (xy 234.015606 -88.401316)
			(xy 233.957141 -88.340001) (xy 233.90477 -88.273405) (xy 233.858967 -88.202133) (xy 233.820145 -88.12683)
			(xy 233.788657 -88.048178) (xy 233.764789 -87.966888) (xy 233.748755 -87.883698) (xy 233.740702 -87.799361)
			(xy 223.040146 -87.799361) (xy 223.059815 -87.837512) (xy 223.091303 -87.916164) (xy 223.115171 -87.997454)
			(xy 223.131205 -88.080644) (xy 223.139258 -88.164981) (xy 223.139762 -88.207342) (xy 223.139258 -88.249703)
			(xy 223.131205 -88.33404) (xy 223.115171 -88.41723) (xy 223.091303 -88.49852) (xy 223.059815 -88.577172)
			(xy 223.020993 -88.652475) (xy 222.97519 -88.723747) (xy 222.922819 -88.790343) (xy 222.864354 -88.851658)
			(xy 222.800326 -88.907139) (xy 222.731314 -88.956282) (xy 222.657944 -88.998642) (xy 222.580879 -89.033837)
			(xy 222.500817 -89.061546) (xy 222.418484 -89.08152) (xy 222.334625 -89.093577) (xy 222.25 -89.097609)
			(xy 222.165375 -89.093577) (xy 222.081516 -89.08152) (xy 221.999183 -89.061546) (xy 221.919121 -89.033837)
			(xy 221.842056 -88.998642) (xy 221.768686 -88.956282) (xy 221.699674 -88.907139) (xy 221.635646 -88.851658)
			(xy 221.577181 -88.790343) (xy 221.52481 -88.723747) (xy 221.479007 -88.652475) (xy 221.440185 -88.577172)
			(xy 221.408697 -88.49852) (xy 221.384829 -88.41723) (xy 221.368795 -88.33404) (xy 221.360742 -88.249703)
			(xy 220.472 -88.249703) (xy 220.472 -90.587576) (xy 220.472536 -90.598597) (xy 220.481749 -90.618619)
			(xy 220.48978 -90.626184) (xy 220.55709 -90.683588) (xy 220.578172 -90.689684) (xy 220.589094 -90.687906)
			(xy 220.623106 -90.682991) (xy 220.691636 -90.677777) (xy 220.726 -90.677492) (xy 220.768085 -90.677959)
			(xy 220.851884 -90.685861) (xy 220.934562 -90.70164) (xy 221.01538 -90.725157) (xy 221.054676 -90.74023)
			(xy 221.063566 -90.743786) (xy 221.083378 -90.743786) (xy 221.157546 -90.713814) (xy 221.166375 -90.709773)
			(xy 221.180358 -90.696324) (xy 221.184724 -90.687652) (xy 221.202634 -90.649033) (xy 221.244802 -90.575077)
			(xy 221.293844 -90.505489) (xy 221.34931 -90.440904) (xy 221.410693 -90.381914) (xy 221.477432 -90.329059)
			(xy 221.548915 -90.282822) (xy 221.624488 -90.243627) (xy 221.703461 -90.211831) (xy 221.785111 -90.187726)
			(xy 221.86869 -90.171533) (xy 221.953433 -90.163399) (xy 221.996 -90.162888) (xy 222.038319 -90.163418)
			(xy 222.122571 -90.171508) (xy 222.205674 -90.187559) (xy 222.286879 -90.211425) (xy 222.365452 -90.242891)
			(xy 222.440683 -90.281673) (xy 222.476568 -90.304112) (xy 222.484962 -90.308975) (xy 222.504 -90.312628)
			(xy 222.523038 -90.308975) (xy 222.531432 -90.304112) (xy 222.567305 -90.281651) (xy 222.642532 -90.242856)
			(xy 222.721106 -90.211384) (xy 222.802314 -90.18752) (xy 222.885423 -90.17148) (xy 222.969679 -90.163409)
			(xy 223.012 -90.162888) (xy 223.052325 -90.16334) (xy 223.132644 -90.170639) (xy 223.211973 -90.185176)
			(xy 223.289661 -90.206833) (xy 223.36507 -90.235431) (xy 223.437582 -90.270737) (xy 223.506601 -90.312459)
			(xy 223.571561 -90.360257) (xy 223.602042 -90.386662) (xy 223.609127 -90.392457) (xy 223.626177 -90.399083)
			(xy 223.635316 -90.399616) (xy 223.665034 -90.399616) (xy 223.67427 -90.399316) (xy 223.6916 -90.392942)
			(xy 223.698816 -90.38717) (xy 223.730347 -90.360399) (xy 223.797558 -90.31218) (xy 223.86896 -90.270414)
			(xy 223.943932 -90.235462) (xy 224.021829 -90.207629) (xy 224.061782 -90.196924) (xy 224.072958 -90.19413)
			(xy 224.090992 -90.179144) (xy 224.128076 -90.09634) (xy 224.132321 -90.085555) (xy 224.131672 -90.062408)
			(xy 224.126806 -90.05189) (xy 224.107774 -90.014006) (xy 224.076182 -89.935326) (xy 224.052219 -89.853996)
			(xy 224.036105 -89.770755) (xy 224.027983 -89.686359) (xy 224.027492 -89.643966) (xy 224.027492 -89.64295)
			(xy 224.027996 -89.600602) (xy 224.036047 -89.516288) (xy 224.052076 -89.433122) (xy 224.075937 -89.351855)
			(xy 224.107416 -89.273225) (xy 224.146227 -89.197944) (xy 224.192017 -89.126692) (xy 224.244373 -89.060116)
			(xy 224.302821 -88.998818) (xy 224.366831 -88.943353) (xy 224.435823 -88.894224) (xy 224.509173 -88.851875)
			(xy 224.586216 -88.816691) (xy 224.666255 -88.788989) (xy 224.748564 -88.769021) (xy 224.832399 -88.756968)
			(xy 224.917 -88.752938) (xy 225.001601 -88.756968) (xy 225.085436 -88.769021) (xy 225.167745 -88.788989)
			(xy 225.247784 -88.816691) (xy 225.324827 -88.851875) (xy 225.398177 -88.894224) (xy 225.467169 -88.943353)
			(xy 225.531179 -88.998818) (xy 225.589627 -89.060116) (xy 225.641983 -89.126692) (xy 225.687773 -89.197944)
			(xy 225.726584 -89.273225) (xy 225.758063 -89.351855) (xy 225.781924 -89.433122) (xy 225.797953 -89.516288)
			(xy 225.799904 -89.536721) (xy 227.980744 -89.536721) (xy 227.980744 -89.451999) (xy 227.988797 -89.367662)
			(xy 228.004831 -89.284472) (xy 228.028699 -89.203182) (xy 228.060187 -89.12453) (xy 228.099009 -89.049227)
			(xy 228.144812 -88.977955) (xy 228.197183 -88.911359) (xy 228.255648 -88.850044) (xy 228.319676 -88.794563)
			(xy 228.388688 -88.74542) (xy 228.462058 -88.70306) (xy 228.539123 -88.667865) (xy 228.619185 -88.640156)
			(xy 228.701518 -88.620182) (xy 228.785377 -88.608125) (xy 228.870002 -88.604094) (xy 228.954627 -88.608125)
			(xy 229.038486 -88.620182) (xy 229.120819 -88.640156) (xy 229.200881 -88.667865) (xy 229.277946 -88.70306)
			(xy 229.351316 -88.74542) (xy 229.420328 -88.794563) (xy 229.484356 -88.850044) (xy 229.542821 -88.911359)
			(xy 229.595192 -88.977955) (xy 229.640995 -89.049227) (xy 229.679817 -89.12453) (xy 229.711305 -89.203182)
			(xy 229.735173 -89.284472) (xy 229.751207 -89.367662) (xy 229.75926 -89.451999) (xy 229.759764 -89.49436)
			(xy 229.75926 -89.536721) (xy 229.751207 -89.621058) (xy 229.735173 -89.704248) (xy 229.711305 -89.785538)
			(xy 229.679817 -89.86419) (xy 229.640995 -89.939493) (xy 229.595192 -90.010765) (xy 229.542821 -90.077361)
			(xy 229.484356 -90.138676) (xy 229.420328 -90.194157) (xy 229.351316 -90.2433) (xy 229.277946 -90.28566)
			(xy 229.200881 -90.320855) (xy 229.120819 -90.348564) (xy 229.038486 -90.368538) (xy 228.954627 -90.380595)
			(xy 228.870002 -90.384627) (xy 228.785377 -90.380595) (xy 228.701518 -90.368538) (xy 228.619185 -90.348564)
			(xy 228.539123 -90.320855) (xy 228.462058 -90.28566) (xy 228.388688 -90.2433) (xy 228.319676 -90.194157)
			(xy 228.255648 -90.138676) (xy 228.197183 -90.077361) (xy 228.144812 -90.010765) (xy 228.099009 -89.939493)
			(xy 228.060187 -89.86419) (xy 228.028699 -89.785538) (xy 228.004831 -89.704248) (xy 227.988797 -89.621058)
			(xy 227.980744 -89.536721) (xy 225.799904 -89.536721) (xy 225.806004 -89.600602) (xy 225.806508 -89.64295)
			(xy 225.806021 -89.684918) (xy 225.798112 -89.76848) (xy 225.782371 -89.850927) (xy 225.758936 -89.931525)
			(xy 225.728016 -90.009558) (xy 225.689886 -90.084333) (xy 225.644884 -90.155186) (xy 225.593411 -90.221486)
			(xy 225.535923 -90.282645) (xy 225.472932 -90.338119) (xy 225.404998 -90.387415) (xy 225.332723 -90.430095)
			(xy 225.256751 -90.46578) (xy 225.177756 -90.494153) (xy 225.137218 -90.505026) (xy 225.126042 -90.50782)
			(xy 225.108008 -90.522806) (xy 225.070924 -90.60561) (xy 225.066691 -90.616394) (xy 225.06736 -90.63953)
			(xy 225.072194 -90.65006) (xy 225.091224 -90.687944) (xy 225.122812 -90.766626) (xy 225.146769 -90.847955)
			(xy 225.16288 -90.931196) (xy 225.170996 -91.015592) (xy 225.171508 -91.057984) (xy 225.171508 -91.059)
			(xy 225.171033 -91.100102) (xy 225.163448 -91.181957) (xy 225.148343 -91.262762) (xy 225.125847 -91.341829)
			(xy 225.096151 -91.418483) (xy 225.059509 -91.49207) (xy 225.016234 -91.561962) (xy 224.966694 -91.627563)
			(xy 224.911313 -91.688313) (xy 224.850563 -91.743694) (xy 224.784962 -91.793234) (xy 224.71507 -91.836509)
			(xy 224.641483 -91.873151) (xy 224.564829 -91.902847) (xy 224.485762 -91.925343) (xy 224.404957 -91.940448)
			(xy 224.323102 -91.948033) (xy 224.282 -91.948508) (xy 224.281492 -91.948508) (xy 224.241206 -91.94804)
			(xy 224.160968 -91.940722) (xy 224.081718 -91.926183) (xy 224.004108 -91.904541) (xy 223.92877 -91.875975)
			(xy 223.856322 -91.840717) (xy 223.787357 -91.799056) (xy 223.722439 -91.751334) (xy 223.691958 -91.724988)
			(xy 223.684875 -91.719188) (xy 223.667824 -91.712556) (xy 223.658684 -91.712034) (xy 223.628966 -91.712034)
			(xy 223.61973 -91.712335) (xy 223.602404 -91.718714) (xy 223.595184 -91.72448) (xy 223.564879 -91.750222)
			(xy 223.50043 -91.796802) (xy 223.43208 -91.837444) (xy 223.360375 -91.871821) (xy 223.285888 -91.899661)
			(xy 223.209212 -91.920739) (xy 223.130962 -91.934889) (xy 223.05176 -91.941997) (xy 223.012 -91.942412)
			(xy 222.969681 -91.941882) (xy 222.885429 -91.933792) (xy 222.802326 -91.917741) (xy 222.721121 -91.893875)
			(xy 222.642548 -91.862409) (xy 222.567317 -91.823627) (xy 222.531432 -91.801188) (xy 222.523038 -91.796325)
			(xy 222.504 -91.792672) (xy 222.484962 -91.796325) (xy 222.476568 -91.801188) (xy 222.440695 -91.823649)
			(xy 222.365468 -91.862444) (xy 222.286894 -91.893916) (xy 222.205686 -91.91778) (xy 222.122577 -91.93382)
			(xy 222.038321 -91.941891) (xy 221.996 -91.942412) (xy 221.95391 -91.941904) (xy 221.870109 -91.933925)
			(xy 221.787435 -91.918075) (xy 221.706624 -91.894497) (xy 221.667324 -91.87942) (xy 221.658434 -91.875864)
			(xy 221.638622 -91.875864) (xy 221.564454 -91.905836) (xy 221.555629 -91.90988) (xy 221.541658 -91.923335)
			(xy 221.537276 -91.931998) (xy 221.520276 -91.968643) (xy 221.480566 -92.038998) (xy 221.434642 -92.105463)
			(xy 221.382883 -92.167493) (xy 221.325715 -92.224576) (xy 221.29496 -92.250768) (xy 221.287086 -92.257372)
			(xy 221.277942 -92.274898) (xy 221.270576 -92.35694) (xy 221.270039 -92.366939) (xy 221.275941 -92.386056)
			(xy 221.282006 -92.394024) (xy 221.283022 -92.39504) (xy 221.290134 -92.403676) (xy 221.310454 -92.413328)
			(xy 221.411546 -92.413328) (xy 221.431866 -92.403676) (xy 221.438978 -92.39504) (xy 221.467105 -92.362046)
			(xy 221.528783 -92.301107) (xy 221.596098 -92.246458) (xy 221.668412 -92.198619) (xy 221.745038 -92.158044)
			(xy 221.825248 -92.125118) (xy 221.908282 -92.100154) (xy 221.993351 -92.083388) (xy 222.079647 -92.07498)
			(xy 222.123 -92.074492) (xy 222.169396 -92.075077) (xy 222.261686 -92.08471) (xy 222.352471 -92.103903)
			(xy 222.440764 -92.132447) (xy 222.483426 -92.150692) (xy 222.493368 -92.154498) (xy 222.514632 -92.154498)
			(xy 222.524574 -92.150692) (xy 222.567239 -92.132454) (xy 222.655532 -92.103916) (xy 222.746316 -92.08472)
			(xy 222.838604 -92.075075) (xy 222.885 -92.074492) (xy 222.928785 -92.075002) (xy 223.015933 -92.083579)
			(xy 223.101817 -92.100681) (xy 223.185603 -92.126142) (xy 223.266482 -92.159714) (xy 223.343669 -92.201073)
			(xy 223.416417 -92.249819) (xy 223.484021 -92.305479) (xy 223.545828 -92.367514) (xy 223.601238 -92.435324)
			(xy 223.625918 -92.471494) (xy 223.63303 -92.481908) (xy 223.655382 -92.4941) (xy 223.765618 -92.4941)
			(xy 223.78797 -92.481908) (xy 223.795082 -92.471494) (xy 223.819762 -92.435324) (xy 223.87518 -92.367522)
			(xy 223.936991 -92.305492) (xy 224.004597 -92.249835) (xy 224.077345 -92.20109) (xy 224.15453 -92.159728)
			(xy 224.235406 -92.12615) (xy 224.319189 -92.10068) (xy 224.405069 -92.083566) (xy 224.492215 -92.074972)
			(xy 224.536 -92.074492) (xy 224.582396 -92.075077) (xy 224.674686 -92.08471) (xy 224.765471 -92.103903)
			(xy 224.853764 -92.132447) (xy 224.896426 -92.150692) (xy 224.906368 -92.154498) (xy 224.927632 -92.154498)
			(xy 224.937574 -92.150692) (xy 224.980239 -92.132454) (xy 225.068532 -92.103916) (xy 225.159316 -92.08472)
			(xy 225.251604 -92.075075) (xy 225.298 -92.074492) (xy 225.341785 -92.075002) (xy 225.428933 -92.083579)
			(xy 225.514817 -92.100681) (xy 225.598603 -92.126142) (xy 225.679482 -92.159714) (xy 225.756669 -92.201073)
			(xy 225.829417 -92.249819) (xy 225.897021 -92.305479) (xy 225.958828 -92.367514) (xy 226.014238 -92.435324)
			(xy 226.038918 -92.471494) (xy 226.04603 -92.481908) (xy 226.068382 -92.4941) (xy 226.178618 -92.4941)
			(xy 226.20097 -92.481908) (xy 226.208082 -92.471494) (xy 226.232762 -92.435324) (xy 226.28818 -92.367522)
			(xy 226.349991 -92.305492) (xy 226.417597 -92.249835) (xy 226.490345 -92.20109) (xy 226.56753 -92.159728)
			(xy 226.648406 -92.12615) (xy 226.732189 -92.10068) (xy 226.818069 -92.083566) (xy 226.905215 -92.074972)
			(xy 226.949 -92.074492) (xy 226.995396 -92.075077) (xy 227.087686 -92.08471) (xy 227.178471 -92.103903)
			(xy 227.266764 -92.132447) (xy 227.309426 -92.150692) (xy 227.319368 -92.154498) (xy 227.340632 -92.154498)
			(xy 227.350574 -92.150692) (xy 227.393239 -92.132454) (xy 227.481532 -92.103916) (xy 227.572316 -92.08472)
			(xy 227.664604 -92.075075) (xy 227.711 -92.074492) (xy 227.754785 -92.075002) (xy 227.841933 -92.083579)
			(xy 227.927817 -92.100681) (xy 228.011603 -92.126142) (xy 228.092482 -92.159714) (xy 228.169669 -92.201073)
			(xy 228.242417 -92.249819) (xy 228.310021 -92.305479) (xy 228.371828 -92.367514) (xy 228.427238 -92.435324)
			(xy 228.451918 -92.471494) (xy 228.45903 -92.481908) (xy 228.481382 -92.4941) (xy 228.591618 -92.4941)
			(xy 228.61397 -92.481908) (xy 228.621082 -92.471494) (xy 228.645762 -92.435324) (xy 228.70118 -92.367522)
			(xy 228.762991 -92.305492) (xy 228.830597 -92.249835) (xy 228.903345 -92.20109) (xy 228.98053 -92.159728)
			(xy 229.061406 -92.12615) (xy 229.145189 -92.10068) (xy 229.231069 -92.083566) (xy 229.318215 -92.074972)
			(xy 229.362 -92.074492) (xy 229.408396 -92.075077) (xy 229.500686 -92.08471) (xy 229.591471 -92.103903)
			(xy 229.679764 -92.132447) (xy 229.722426 -92.150692) (xy 229.732368 -92.154498) (xy 229.753632 -92.154498)
			(xy 229.763574 -92.150692) (xy 229.806239 -92.132454) (xy 229.894532 -92.103916) (xy 229.985316 -92.08472)
			(xy 230.077604 -92.075075) (xy 230.124 -92.074492) (xy 230.161541 -92.074862) (xy 230.23636 -92.081149)
			(xy 230.310382 -92.093721) (xy 230.383081 -92.112487) (xy 230.41864 -92.12453) (xy 230.43261 -92.12961)
			(xy 230.460804 -92.12326) (xy 230.536242 -92.048838) (xy 230.542639 -92.041848) (xy 230.550323 -92.024545)
			(xy 230.551252 -92.005636) (xy 230.548688 -91.996514) (xy 230.548688 -91.99626) (xy 230.534027 -91.950543)
			(xy 230.513464 -91.85676) (xy 230.503112 -91.761309) (xy 230.50246 -91.713304) (xy 230.50246 -91.71305)
			(xy 230.502964 -91.670702) (xy 230.511015 -91.586388) (xy 230.527044 -91.503222) (xy 230.550905 -91.421955)
			(xy 230.582384 -91.343325) (xy 230.621195 -91.268044) (xy 230.666985 -91.196792) (xy 230.719341 -91.130216)
			(xy 230.777789 -91.068918) (xy 230.841799 -91.013453) (xy 230.910791 -90.964324) (xy 230.984141 -90.921975)
			(xy 231.061184 -90.886791) (xy 231.141223 -90.859089) (xy 231.223532 -90.839121) (xy 231.307367 -90.827068)
			(xy 231.391968 -90.823038) (xy 231.476569 -90.827068) (xy 231.560404 -90.839121) (xy 231.642713 -90.859089)
			(xy 231.722752 -90.886791) (xy 231.799795 -90.921975) (xy 231.873145 -90.964324) (xy 231.942137 -91.013453)
			(xy 232.006147 -91.068918) (xy 232.064595 -91.130216) (xy 232.116951 -91.196792) (xy 232.162741 -91.268044)
			(xy 232.201552 -91.343325) (xy 232.233031 -91.421955) (xy 232.256892 -91.503222) (xy 232.272921 -91.586388)
			(xy 232.280972 -91.670702) (xy 232.281476 -91.71305) (xy 232.281476 -91.713812) (xy 232.280955 -91.755959)
			(xy 232.272932 -91.83987) (xy 232.257016 -91.922648) (xy 232.245662 -91.96324) (xy 232.245662 -91.963494)
			(xy 232.243578 -91.971937) (xy 232.244574 -91.989287) (xy 232.25128 -92.005319) (xy 232.256838 -92.012008)
			(xy 232.324656 -92.085922) (xy 232.350056 -92.09405) (xy 232.36301 -92.09151) (xy 232.406059 -92.083494)
			(xy 232.493214 -92.074964) (xy 232.537 -92.074492) (xy 232.580785 -92.075002) (xy 232.667933 -92.083579)
			(xy 232.753817 -92.100681) (xy 232.837603 -92.126142) (xy 232.918482 -92.159714) (xy 232.995669 -92.201073)
			(xy 233.068417 -92.249819) (xy 233.136021 -92.305479) (xy 233.197828 -92.367514) (xy 233.253238 -92.435324)
			(xy 233.277918 -92.471494) (xy 233.28503 -92.481908) (xy 233.307382 -92.4941) (xy 233.417618 -92.4941)
			(xy 233.43997 -92.481908) (xy 233.447082 -92.471494) (xy 233.471762 -92.435324) (xy 233.52718 -92.367522)
			(xy 233.588991 -92.305492) (xy 233.656597 -92.249835) (xy 233.729345 -92.20109) (xy 233.80653 -92.159728)
			(xy 233.887406 -92.12615) (xy 233.971189 -92.10068) (xy 234.057069 -92.083566) (xy 234.144215 -92.074972)
			(xy 234.188 -92.074492) (xy 234.234396 -92.075077) (xy 234.326686 -92.08471) (xy 234.417471 -92.103903)
			(xy 234.505764 -92.132447) (xy 234.548426 -92.150692) (xy 234.558368 -92.154498) (xy 234.579632 -92.154498)
			(xy 234.589574 -92.150692) (xy 234.597448 -92.147136) (xy 234.606358 -92.142812) (xy 234.620222 -92.128696)
			(xy 234.624372 -92.119704) (xy 234.636056 -92.091256) (xy 234.639274 -92.081921) (xy 234.639141 -92.062194)
			(xy 234.635802 -92.052902) (xy 234.619674 -92.012432) (xy 234.594468 -91.929034) (xy 234.577528 -91.843573)
			(xy 234.569017 -91.756866) (xy 234.568492 -91.713304) (xy 234.568492 -91.71305) (xy 234.56893 -91.673951)
			(xy 234.575817 -91.596056) (xy 234.589508 -91.519066) (xy 234.609898 -91.443572) (xy 234.636829 -91.370157)
			(xy 234.653074 -91.33459) (xy 234.65731 -91.324203) (xy 234.65731 -91.301797) (xy 234.653074 -91.29141)
			(xy 234.636811 -91.255849) (xy 234.609859 -91.182439) (xy 234.589461 -91.106944) (xy 234.575772 -91.02995)
			(xy 234.568898 -90.952051) (xy 234.568492 -90.91295) (xy 234.568492 -90.906854) (xy 234.568062 -90.896228)
			(xy 234.559664 -90.876717) (xy 234.544077 -90.862286) (xy 234.534202 -90.85834) (xy 234.443016 -90.827098)
			(xy 234.432811 -90.824173) (xy 234.411681 -90.825955) (xy 234.393042 -90.836068) (xy 234.38612 -90.844116)
			(xy 234.38612 -90.84437) (xy 234.360946 -90.87648) (xy 234.305607 -90.936444) (xy 234.245011 -90.99109)
			(xy 234.179665 -91.039959) (xy 234.11012 -91.082639) (xy 234.03696 -91.118773) (xy 233.960798 -91.148058)
			(xy 233.882275 -91.170246) (xy 233.802051 -91.185151) (xy 233.720799 -91.192649) (xy 233.68 -91.193112)
			(xy 233.637111 -91.192597) (xy 233.551732 -91.184336) (xy 233.467546 -91.167891) (xy 233.385334 -91.143414)
			(xy 233.305862 -91.111134) (xy 233.229868 -91.07135) (xy 233.158059 -91.024432) (xy 233.124248 -90.99804)
			(xy 233.116909 -90.992662) (xy 233.09963 -90.987006) (xy 233.081464 -90.987747) (xy 233.07294 -90.990928)
			(xy 233.032237 -91.007327) (xy 232.948306 -91.032965) (xy 232.862261 -91.050222) (xy 232.774935 -91.05893)
			(xy 232.731056 -91.059508) (xy 232.73004 -91.059508) (xy 232.68769 -91.059022) (xy 232.603372 -91.050974)
			(xy 232.520201 -91.034948) (xy 232.43893 -91.011088) (xy 232.360295 -90.97961) (xy 232.285009 -90.9408)
			(xy 232.213753 -90.895009) (xy 232.147172 -90.842653) (xy 232.08587 -90.784204) (xy 232.030401 -90.720192)
			(xy 231.981269 -90.651198) (xy 231.938917 -90.577845) (xy 231.90373 -90.500799) (xy 231.876026 -90.420757)
			(xy 231.856057 -90.338444) (xy 231.844002 -90.254605) (xy 231.839972 -90.17) (xy 231.844002 -90.085395)
			(xy 231.856057 -90.001556) (xy 231.876026 -89.919243) (xy 231.90373 -89.839201) (xy 231.938917 -89.762155)
			(xy 231.981269 -89.688802) (xy 232.030401 -89.619808) (xy 232.08587 -89.555796) (xy 232.147172 -89.497347)
			(xy 232.213753 -89.444991) (xy 232.285009 -89.3992) (xy 232.360295 -89.36039) (xy 232.43893 -89.328912)
			(xy 232.520201 -89.305052) (xy 232.603372 -89.289026) (xy 232.68769 -89.280978) (xy 232.73004 -89.280492)
			(xy 232.730548 -89.280492) (xy 232.773394 -89.281016) (xy 232.858685 -89.289284) (xy 232.942786 -89.305718)
			(xy 233.024916 -89.330166) (xy 233.104313 -89.362402) (xy 233.18024 -89.402126) (xy 233.251994 -89.44897)
			(xy 233.285792 -89.47531) (xy 233.29313 -89.480685) (xy 233.310407 -89.486334) (xy 233.328568 -89.48558)
			(xy 233.3371 -89.482422) (xy 233.377914 -89.465939) (xy 233.462087 -89.440173) (xy 233.548392 -89.422845)
			(xy 233.635986 -89.414123) (xy 233.68 -89.413588) (xy 233.721111 -89.414048) (xy 233.802981 -89.421636)
			(xy 233.883802 -89.436747) (xy 233.962884 -89.459252) (xy 234.039551 -89.488959) (xy 234.113149 -89.525614)
			(xy 234.183051 -89.568905) (xy 234.24866 -89.618462) (xy 234.309415 -89.673862) (xy 234.364798 -89.734633)
			(xy 234.410974 -89.795801) (xy 236.142526 -89.795801) (xy 236.142526 -89.711079) (xy 236.150579 -89.626742)
			(xy 236.166613 -89.543552) (xy 236.190481 -89.462262) (xy 236.221969 -89.38361) (xy 236.260791 -89.308307)
			(xy 236.306594 -89.237035) (xy 236.358965 -89.170439) (xy 236.41743 -89.109124) (xy 236.481458 -89.053643)
			(xy 236.55047 -89.0045) (xy 236.62384 -88.96214) (xy 236.700905 -88.926945) (xy 236.780967 -88.899236)
			(xy 236.8633 -88.879262) (xy 236.947159 -88.867205) (xy 237.031784 -88.863174) (xy 237.116409 -88.867205)
			(xy 237.200268 -88.879262) (xy 237.282601 -88.899236) (xy 237.362663 -88.926945) (xy 237.439728 -88.96214)
			(xy 237.513098 -89.0045) (xy 237.58211 -89.053643) (xy 237.646138 -89.109124) (xy 237.704603 -89.170439)
			(xy 237.756974 -89.237035) (xy 237.802777 -89.308307) (xy 237.841599 -89.38361) (xy 237.873087 -89.462262)
			(xy 237.896955 -89.543552) (xy 237.897841 -89.548151) (xy 238.857532 -89.548151) (xy 238.857532 -89.463429)
			(xy 238.865585 -89.379092) (xy 238.881619 -89.295902) (xy 238.905487 -89.214612) (xy 238.936975 -89.13596)
			(xy 238.975797 -89.060657) (xy 239.0216 -88.989385) (xy 239.073971 -88.922789) (xy 239.132436 -88.861474)
			(xy 239.196464 -88.805993) (xy 239.265476 -88.75685) (xy 239.338846 -88.71449) (xy 239.415911 -88.679295)
			(xy 239.495973 -88.651586) (xy 239.578306 -88.631612) (xy 239.662165 -88.619555) (xy 239.74679 -88.615524)
			(xy 239.831415 -88.619555) (xy 239.915274 -88.631612) (xy 239.997607 -88.651586) (xy 240.077669 -88.679295)
			(xy 240.154734 -88.71449) (xy 240.228104 -88.75685) (xy 240.297116 -88.805993) (xy 240.361144 -88.861474)
			(xy 240.419609 -88.922789) (xy 240.47198 -88.989385) (xy 240.517783 -89.060657) (xy 240.556605 -89.13596)
			(xy 240.588093 -89.214612) (xy 240.611961 -89.295902) (xy 240.627995 -89.379092) (xy 240.636048 -89.463429)
			(xy 240.636552 -89.50579) (xy 240.636048 -89.548151) (xy 240.627995 -89.632488) (xy 240.611961 -89.715678)
			(xy 240.588093 -89.796968) (xy 240.556605 -89.87562) (xy 240.517783 -89.950923) (xy 240.47198 -90.022195)
			(xy 240.419609 -90.088791) (xy 240.361144 -90.150106) (xy 240.297116 -90.205587) (xy 240.228104 -90.25473)
			(xy 240.154734 -90.29709) (xy 240.077669 -90.332285) (xy 239.997607 -90.359994) (xy 239.915274 -90.379968)
			(xy 239.831415 -90.392025) (xy 239.74679 -90.396057) (xy 239.662165 -90.392025) (xy 239.578306 -90.379968)
			(xy 239.495973 -90.359994) (xy 239.415911 -90.332285) (xy 239.338846 -90.29709) (xy 239.265476 -90.25473)
			(xy 239.196464 -90.205587) (xy 239.132436 -90.150106) (xy 239.073971 -90.088791) (xy 239.0216 -90.022195)
			(xy 238.975797 -89.950923) (xy 238.936975 -89.87562) (xy 238.905487 -89.796968) (xy 238.881619 -89.715678)
			(xy 238.865585 -89.632488) (xy 238.857532 -89.548151) (xy 237.897841 -89.548151) (xy 237.912989 -89.626742)
			(xy 237.921042 -89.711079) (xy 237.921546 -89.75344) (xy 237.921042 -89.795801) (xy 237.912989 -89.880138)
			(xy 237.896955 -89.963328) (xy 237.873087 -90.044618) (xy 237.841599 -90.12327) (xy 237.802777 -90.198573)
			(xy 237.756974 -90.269845) (xy 237.704603 -90.336441) (xy 237.646138 -90.397756) (xy 237.58211 -90.453237)
			(xy 237.513098 -90.50238) (xy 237.439728 -90.54474) (xy 237.362663 -90.579935) (xy 237.282601 -90.607644)
			(xy 237.200268 -90.627618) (xy 237.116409 -90.639675) (xy 237.031784 -90.643707) (xy 236.947159 -90.639675)
			(xy 236.8633 -90.627618) (xy 236.780967 -90.607644) (xy 236.700905 -90.579935) (xy 236.62384 -90.54474)
			(xy 236.55047 -90.50238) (xy 236.481458 -90.453237) (xy 236.41743 -90.397756) (xy 236.358965 -90.336441)
			(xy 236.306594 -90.269845) (xy 236.260791 -90.198573) (xy 236.221969 -90.12327) (xy 236.190481 -90.044618)
			(xy 236.166613 -89.963328) (xy 236.150579 -89.880138) (xy 236.142526 -89.795801) (xy 234.410974 -89.795801)
			(xy 234.414336 -89.800255) (xy 234.457608 -89.870169) (xy 234.494242 -89.943778) (xy 234.523928 -90.020454)
			(xy 234.54641 -90.099541) (xy 234.561498 -90.180367) (xy 234.569063 -90.262239) (xy 234.569508 -90.30335)
			(xy 234.569508 -90.309446) (xy 234.569938 -90.320072) (xy 234.578336 -90.339583) (xy 234.593923 -90.354014)
			(xy 234.603798 -90.35796) (xy 234.694984 -90.389202) (xy 234.705189 -90.392127) (xy 234.726319 -90.390345)
			(xy 234.744958 -90.380232) (xy 234.75188 -90.372184) (xy 234.75188 -90.37193) (xy 234.777054 -90.33982)
			(xy 234.832393 -90.279856) (xy 234.892989 -90.22521) (xy 234.958335 -90.176341) (xy 235.02788 -90.133661)
			(xy 235.10104 -90.097527) (xy 235.177202 -90.068242) (xy 235.255725 -90.046054) (xy 235.335949 -90.031149)
			(xy 235.417201 -90.023651) (xy 235.458 -90.023188) (xy 235.499095 -90.023662) (xy 235.580935 -90.031244)
			(xy 235.661726 -90.046344) (xy 235.74078 -90.068832) (xy 235.817422 -90.098518) (xy 235.890999 -90.135147)
			(xy 235.960883 -90.178407) (xy 236.026478 -90.22793) (xy 236.087225 -90.283293) (xy 236.142605 -90.344024)
			(xy 236.192147 -90.409604) (xy 236.235428 -90.479476) (xy 236.272078 -90.553042) (xy 236.301785 -90.629675)
			(xy 236.324297 -90.708723) (xy 236.33942 -90.78951) (xy 236.347026 -90.871347) (xy 236.347508 -90.912442)
			(xy 236.347508 -90.91295) (xy 236.34707 -90.952049) (xy 236.340183 -91.029944) (xy 236.326492 -91.106934)
			(xy 236.306102 -91.182428) (xy 236.279171 -91.255843) (xy 236.262926 -91.29141) (xy 236.25869 -91.301797)
			(xy 236.25869 -91.324203) (xy 236.262926 -91.33459) (xy 236.279189 -91.370151) (xy 236.306141 -91.443561)
			(xy 236.326539 -91.519056) (xy 236.340228 -91.59605) (xy 236.347102 -91.673949) (xy 236.347508 -91.71305)
			(xy 236.347508 -91.713304) (xy 236.346999 -91.755493) (xy 236.338989 -91.839492) (xy 236.323068 -91.922356)
			(xy 236.311694 -91.962986) (xy 236.307884 -91.97594) (xy 236.31398 -92.001594) (xy 236.381798 -92.075762)
			(xy 236.387896 -92.081893) (xy 236.403155 -92.090002) (xy 236.420243 -92.092572) (xy 236.428788 -92.091256)
			(xy 236.429042 -92.091256) (xy 236.471596 -92.083394) (xy 236.557729 -92.074993) (xy 236.601 -92.074492)
			(xy 236.658404 -92.07627) (xy 236.658658 -92.07627) (xy 236.670759 -92.076324) (xy 236.692903 -92.066651)
			(xy 236.701076 -92.057728) (xy 236.761274 -91.983814) (xy 236.766354 -91.959938) (xy 236.763052 -91.948)
			(xy 236.753041 -91.90978) (xy 236.73904 -91.832018) (xy 236.732003 -91.753318) (xy 236.731556 -91.713812)
			(xy 236.731556 -91.71305) (xy 236.73206 -91.670702) (xy 236.740111 -91.586388) (xy 236.75614 -91.503222)
			(xy 236.780001 -91.421955) (xy 236.81148 -91.343325) (xy 236.850291 -91.268044) (xy 236.896081 -91.196792)
			(xy 236.948437 -91.130216) (xy 237.006885 -91.068918) (xy 237.070895 -91.013453) (xy 237.139887 -90.964324)
			(xy 237.213237 -90.921975) (xy 237.29028 -90.886791) (xy 237.370319 -90.859089) (xy 237.452628 -90.839121)
			(xy 237.536463 -90.827068) (xy 237.621064 -90.823038) (xy 237.705665 -90.827068) (xy 237.7895 -90.839121)
			(xy 237.871809 -90.859089) (xy 237.951848 -90.886791) (xy 238.028891 -90.921975) (xy 238.102241 -90.964324)
			(xy 238.171233 -91.013453) (xy 238.235243 -91.068918) (xy 238.293691 -91.130216) (xy 238.346047 -91.196792)
			(xy 238.391837 -91.268044) (xy 238.430648 -91.343325) (xy 238.462127 -91.421955) (xy 238.485988 -91.503222)
			(xy 238.502017 -91.586388) (xy 238.510068 -91.670702) (xy 238.510572 -91.71305) (xy 238.510572 -91.714066)
			(xy 238.510011 -91.758047) (xy 238.501279 -91.845576) (xy 238.483954 -91.931816) (xy 238.458207 -92.015927)
			(xy 238.441738 -92.056712) (xy 238.43817 -92.066604) (xy 238.438506 -92.087609) (xy 238.44721 -92.106728)
			(xy 238.454692 -92.114116) (xy 238.525812 -92.178378) (xy 238.534 -92.185051) (xy 238.55403 -92.191684)
			(xy 238.575035 -92.189696) (xy 238.584486 -92.184982) (xy 238.624023 -92.163841) (xy 238.70651 -92.128698)
			(xy 238.792112 -92.102024) (xy 238.879962 -92.08409) (xy 238.969169 -92.075077) (xy 239.014 -92.074492)
			(xy 239.060396 -92.075077) (xy 239.152686 -92.08471) (xy 239.243471 -92.103903) (xy 239.331764 -92.132447)
			(xy 239.374426 -92.150692) (xy 239.384368 -92.154498) (xy 239.405632 -92.154498) (xy 239.415574 -92.150692)
			(xy 239.458239 -92.132454) (xy 239.546532 -92.103916) (xy 239.637316 -92.08472) (xy 239.729604 -92.075075)
			(xy 239.776 -92.074492) (xy 239.819785 -92.075002) (xy 239.906933 -92.083579) (xy 239.992817 -92.100681)
			(xy 240.076603 -92.126142) (xy 240.157482 -92.159714) (xy 240.234669 -92.201073) (xy 240.307417 -92.249819)
			(xy 240.375021 -92.305479) (xy 240.436828 -92.367514) (xy 240.492238 -92.435324) (xy 240.516918 -92.471494)
			(xy 240.52403 -92.481908) (xy 240.546382 -92.4941) (xy 240.656618 -92.4941) (xy 240.67897 -92.481908)
			(xy 240.686082 -92.471494) (xy 240.710762 -92.435324) (xy 240.76618 -92.367522) (xy 240.827991 -92.305492)
			(xy 240.895597 -92.249835) (xy 240.968345 -92.20109) (xy 241.04553 -92.159728) (xy 241.126406 -92.12615)
			(xy 241.210189 -92.10068) (xy 241.296069 -92.083566) (xy 241.383215 -92.074972) (xy 241.427 -92.074492)
			(xy 241.473396 -92.075077) (xy 241.565686 -92.08471) (xy 241.656471 -92.103903) (xy 241.744764 -92.132447)
			(xy 241.787426 -92.150692) (xy 241.797368 -92.154498) (xy 241.818632 -92.154498) (xy 241.828574 -92.150692)
			(xy 241.871179 -92.132477) (xy 241.959348 -92.103965) (xy 242.050002 -92.084769) (xy 242.14216 -92.075098)
			(xy 242.188492 -92.074492) (xy 242.189 -92.074492) (xy 242.231348 -92.074996) (xy 242.315662 -92.083047)
			(xy 242.398828 -92.099076) (xy 242.480095 -92.122937) (xy 242.558725 -92.154416) (xy 242.634006 -92.193227)
			(xy 242.705258 -92.239017) (xy 242.771834 -92.291373) (xy 242.833132 -92.349821) (xy 242.888597 -92.413831)
			(xy 242.937726 -92.482823) (xy 242.980075 -92.556173) (xy 243.015259 -92.633216) (xy 243.042961 -92.713255)
			(xy 243.062929 -92.795564) (xy 243.074982 -92.879399) (xy 243.079013 -92.964) (xy 243.074982 -93.048601)
			(xy 243.062929 -93.132436) (xy 243.042961 -93.214745) (xy 243.015259 -93.294784) (xy 242.980075 -93.371827)
			(xy 242.937726 -93.445177) (xy 242.888597 -93.514169) (xy 242.833132 -93.578179) (xy 242.771834 -93.636627)
			(xy 242.705258 -93.688983) (xy 242.634006 -93.734773) (xy 242.558725 -93.773584) (xy 242.480095 -93.805063)
			(xy 242.398828 -93.828924) (xy 242.315662 -93.844953) (xy 242.231348 -93.853004) (xy 242.189 -93.853508)
			(xy 242.188492 -93.853508) (xy 242.14216 -93.8529) (xy 242.05 -93.84324) (xy 241.959344 -93.824048)
			(xy 241.871177 -93.79553) (xy 241.828574 -93.777308) (xy 241.818632 -93.773502) (xy 241.797368 -93.773502)
			(xy 241.787426 -93.777308) (xy 241.744761 -93.795546) (xy 241.656468 -93.824084) (xy 241.565684 -93.84328)
			(xy 241.473396 -93.852925) (xy 241.427 -93.853508) (xy 241.383215 -93.852998) (xy 241.296067 -93.844421)
			(xy 241.210183 -93.827319) (xy 241.126397 -93.801858) (xy 241.045518 -93.768286) (xy 240.968331 -93.726927)
			(xy 240.895583 -93.678181) (xy 240.827979 -93.622521) (xy 240.766172 -93.560486) (xy 240.710762 -93.492676)
			(xy 240.686082 -93.456506) (xy 240.67897 -93.446092) (xy 240.656618 -93.4339) (xy 240.546382 -93.4339)
			(xy 240.52403 -93.446092) (xy 240.516918 -93.456506) (xy 240.492238 -93.492676) (xy 240.43682 -93.560478)
			(xy 240.375009 -93.622508) (xy 240.307403 -93.678165) (xy 240.234655 -93.72691) (xy 240.15747 -93.768272)
			(xy 240.076594 -93.80185) (xy 239.992811 -93.82732) (xy 239.906931 -93.844434) (xy 239.819785 -93.853028)
			(xy 239.776 -93.853508) (xy 239.729604 -93.852923) (xy 239.637314 -93.84329) (xy 239.546529 -93.824097)
			(xy 239.458236 -93.795553) (xy 239.415574 -93.777308) (xy 239.405632 -93.773502) (xy 239.384368 -93.773502)
			(xy 239.374426 -93.777308) (xy 239.331761 -93.795546) (xy 239.243468 -93.824084) (xy 239.152684 -93.84328)
			(xy 239.060396 -93.852925) (xy 239.014 -93.853508) (xy 238.970215 -93.852998) (xy 238.883067 -93.844421)
			(xy 238.797183 -93.827319) (xy 238.713397 -93.801858) (xy 238.632518 -93.768286) (xy 238.555331 -93.726927)
			(xy 238.482583 -93.678181) (xy 238.414979 -93.622521) (xy 238.353172 -93.560486) (xy 238.297762 -93.492676)
			(xy 238.273082 -93.456506) (xy 238.26597 -93.446092) (xy 238.243618 -93.4339) (xy 238.133382 -93.4339)
			(xy 238.11103 -93.446092) (xy 238.103918 -93.456506) (xy 238.079238 -93.492676) (xy 238.02382 -93.560478)
			(xy 237.962009 -93.622508) (xy 237.894403 -93.678165) (xy 237.821655 -93.72691) (xy 237.74447 -93.768272)
			(xy 237.663594 -93.80185) (xy 237.579811 -93.82732) (xy 237.493931 -93.844434) (xy 237.406785 -93.853028)
			(xy 237.363 -93.853508) (xy 237.316604 -93.852923) (xy 237.224314 -93.84329) (xy 237.133529 -93.824097)
			(xy 237.045236 -93.795553) (xy 237.002574 -93.777308) (xy 236.992632 -93.773502) (xy 236.971368 -93.773502)
			(xy 236.961426 -93.777308) (xy 236.918761 -93.795546) (xy 236.830468 -93.824084) (xy 236.739684 -93.84328)
			(xy 236.647396 -93.852925) (xy 236.601 -93.853508) (xy 236.557215 -93.852998) (xy 236.470067 -93.844421)
			(xy 236.384183 -93.827319) (xy 236.300397 -93.801858) (xy 236.219518 -93.768286) (xy 236.142331 -93.726927)
			(xy 236.069583 -93.678181) (xy 236.001979 -93.622521) (xy 235.940172 -93.560486) (xy 235.884762 -93.492676)
			(xy 235.860082 -93.456506) (xy 235.85297 -93.446092) (xy 235.830618 -93.4339) (xy 235.720382 -93.4339)
			(xy 235.69803 -93.446092) (xy 235.690918 -93.456506) (xy 235.666238 -93.492676) (xy 235.61082 -93.560478)
			(xy 235.549009 -93.622508) (xy 235.481403 -93.678165) (xy 235.408655 -93.72691) (xy 235.33147 -93.768272)
			(xy 235.250594 -93.80185) (xy 235.166811 -93.82732) (xy 235.080931 -93.844434) (xy 234.993785 -93.853028)
			(xy 234.95 -93.853508) (xy 234.903604 -93.852923) (xy 234.811314 -93.84329) (xy 234.720529 -93.824097)
			(xy 234.632236 -93.795553) (xy 234.589574 -93.777308) (xy 234.579632 -93.773502) (xy 234.558368 -93.773502)
			(xy 234.548426 -93.777308) (xy 234.505761 -93.795546) (xy 234.417468 -93.824084) (xy 234.326684 -93.84328)
			(xy 234.234396 -93.852925) (xy 234.188 -93.853508) (xy 234.144215 -93.852998) (xy 234.057067 -93.844421)
			(xy 233.971183 -93.827319) (xy 233.887397 -93.801858) (xy 233.806518 -93.768286) (xy 233.729331 -93.726927)
			(xy 233.656583 -93.678181) (xy 233.588979 -93.622521) (xy 233.527172 -93.560486) (xy 233.471762 -93.492676)
			(xy 233.447082 -93.456506) (xy 233.43997 -93.446092) (xy 233.417618 -93.4339) (xy 233.307382 -93.4339)
			(xy 233.28503 -93.446092) (xy 233.277918 -93.456506) (xy 233.253238 -93.492676) (xy 233.19782 -93.560478)
			(xy 233.136009 -93.622508) (xy 233.068403 -93.678165) (xy 232.995655 -93.72691) (xy 232.91847 -93.768272)
			(xy 232.837594 -93.80185) (xy 232.753811 -93.82732) (xy 232.667931 -93.844434) (xy 232.580785 -93.853028)
			(xy 232.537 -93.853508) (xy 232.490604 -93.852923) (xy 232.398314 -93.84329) (xy 232.307529 -93.824097)
			(xy 232.219236 -93.795553) (xy 232.176574 -93.777308) (xy 232.166632 -93.773502) (xy 232.145368 -93.773502)
			(xy 232.135426 -93.777308) (xy 232.092761 -93.795546) (xy 232.004468 -93.824084) (xy 231.913684 -93.84328)
			(xy 231.821396 -93.852925) (xy 231.775 -93.853508) (xy 231.731215 -93.852998) (xy 231.644067 -93.844421)
			(xy 231.558183 -93.827319) (xy 231.474397 -93.801858) (xy 231.393518 -93.768286) (xy 231.316331 -93.726927)
			(xy 231.243583 -93.678181) (xy 231.175979 -93.622521) (xy 231.114172 -93.560486) (xy 231.058762 -93.492676)
			(xy 231.034082 -93.456506) (xy 231.02697 -93.446092) (xy 231.004618 -93.4339) (xy 230.894382 -93.4339)
			(xy 230.87203 -93.446092) (xy 230.864918 -93.456506) (xy 230.840238 -93.492676) (xy 230.78482 -93.560478)
			(xy 230.723009 -93.622508) (xy 230.655403 -93.678165) (xy 230.582655 -93.72691) (xy 230.50547 -93.768272)
			(xy 230.424594 -93.80185) (xy 230.340811 -93.82732) (xy 230.254931 -93.844434) (xy 230.167785 -93.853028)
			(xy 230.124 -93.853508) (xy 230.077604 -93.852923) (xy 229.985314 -93.84329) (xy 229.894529 -93.824097)
			(xy 229.806236 -93.795553) (xy 229.763574 -93.777308) (xy 229.753632 -93.773502) (xy 229.732368 -93.773502)
			(xy 229.722426 -93.777308) (xy 229.679761 -93.795546) (xy 229.591468 -93.824084) (xy 229.500684 -93.84328)
			(xy 229.408396 -93.852925) (xy 229.362 -93.853508) (xy 229.318215 -93.852998) (xy 229.231067 -93.844421)
			(xy 229.145183 -93.827319) (xy 229.061397 -93.801858) (xy 228.980518 -93.768286) (xy 228.903331 -93.726927)
			(xy 228.830583 -93.678181) (xy 228.762979 -93.622521) (xy 228.701172 -93.560486) (xy 228.645762 -93.492676)
			(xy 228.621082 -93.456506) (xy 228.61397 -93.446092) (xy 228.591618 -93.4339) (xy 228.481382 -93.4339)
			(xy 228.45903 -93.446092) (xy 228.451918 -93.456506) (xy 228.427238 -93.492676) (xy 228.37182 -93.560478)
			(xy 228.310009 -93.622508) (xy 228.242403 -93.678165) (xy 228.169655 -93.72691) (xy 228.09247 -93.768272)
			(xy 228.011594 -93.80185) (xy 227.927811 -93.82732) (xy 227.841931 -93.844434) (xy 227.754785 -93.853028)
			(xy 227.711 -93.853508) (xy 227.664604 -93.852923) (xy 227.572314 -93.84329) (xy 227.481529 -93.824097)
			(xy 227.393236 -93.795553) (xy 227.350574 -93.777308) (xy 227.340632 -93.773502) (xy 227.319368 -93.773502)
			(xy 227.309426 -93.777308) (xy 227.266761 -93.795546) (xy 227.178468 -93.824084) (xy 227.087684 -93.84328)
			(xy 226.995396 -93.852925) (xy 226.949 -93.853508) (xy 226.905215 -93.852998) (xy 226.818067 -93.844421)
			(xy 226.732183 -93.827319) (xy 226.648397 -93.801858) (xy 226.567518 -93.768286) (xy 226.490331 -93.726927)
			(xy 226.417583 -93.678181) (xy 226.349979 -93.622521) (xy 226.288172 -93.560486) (xy 226.232762 -93.492676)
			(xy 226.208082 -93.456506) (xy 226.20097 -93.446092) (xy 226.178618 -93.4339) (xy 226.068382 -93.4339)
			(xy 226.04603 -93.446092) (xy 226.038918 -93.456506) (xy 226.014238 -93.492676) (xy 225.95882 -93.560478)
			(xy 225.897009 -93.622508) (xy 225.829403 -93.678165) (xy 225.756655 -93.72691) (xy 225.67947 -93.768272)
			(xy 225.598594 -93.80185) (xy 225.514811 -93.82732) (xy 225.428931 -93.844434) (xy 225.341785 -93.853028)
			(xy 225.298 -93.853508) (xy 225.251604 -93.852923) (xy 225.159314 -93.84329) (xy 225.068529 -93.824097)
			(xy 224.980236 -93.795553) (xy 224.937574 -93.777308) (xy 224.927632 -93.773502) (xy 224.906368 -93.773502)
			(xy 224.896426 -93.777308) (xy 224.853761 -93.795546) (xy 224.765468 -93.824084) (xy 224.674684 -93.84328)
			(xy 224.582396 -93.852925) (xy 224.536 -93.853508) (xy 224.492215 -93.852998) (xy 224.405067 -93.844421)
			(xy 224.319183 -93.827319) (xy 224.235397 -93.801858) (xy 224.154518 -93.768286) (xy 224.077331 -93.726927)
			(xy 224.004583 -93.678181) (xy 223.936979 -93.622521) (xy 223.875172 -93.560486) (xy 223.819762 -93.492676)
			(xy 223.795082 -93.456506) (xy 223.78797 -93.446092) (xy 223.765618 -93.4339) (xy 223.655382 -93.4339)
			(xy 223.63303 -93.446092) (xy 223.625918 -93.456506) (xy 223.601238 -93.492676) (xy 223.54582 -93.560478)
			(xy 223.484009 -93.622508) (xy 223.416403 -93.678165) (xy 223.343655 -93.72691) (xy 223.26647 -93.768272)
			(xy 223.185594 -93.80185) (xy 223.101811 -93.82732) (xy 223.015931 -93.844434) (xy 222.928785 -93.853028)
			(xy 222.885 -93.853508) (xy 222.838604 -93.852923) (xy 222.746314 -93.84329) (xy 222.655529 -93.824097)
			(xy 222.567236 -93.795553) (xy 222.524574 -93.777308) (xy 222.514632 -93.773502) (xy 222.493368 -93.773502)
			(xy 222.483426 -93.777308) (xy 222.440761 -93.795546) (xy 222.352468 -93.824084) (xy 222.261684 -93.84328)
			(xy 222.169396 -93.852925) (xy 222.123 -93.853508) (xy 222.079649 -93.852998) (xy 221.993356 -93.844582)
			(xy 221.908292 -93.827812) (xy 221.825262 -93.802845) (xy 221.745055 -93.769919) (xy 221.668433 -93.729346)
			(xy 221.59612 -93.681511) (xy 221.528805 -93.626868) (xy 221.467124 -93.565936) (xy 221.438978 -93.53296)
			(xy 221.431866 -93.524324) (xy 221.411546 -93.514672) (xy 221.310454 -93.514672) (xy 221.290134 -93.524324)
			(xy 221.283022 -93.53296) (xy 221.254895 -93.565954) (xy 221.193217 -93.626893) (xy 221.125902 -93.681542)
			(xy 221.053588 -93.729381) (xy 220.976962 -93.769956) (xy 220.896752 -93.802882) (xy 220.813718 -93.827846)
			(xy 220.728649 -93.844612) (xy 220.642353 -93.85302) (xy 220.599 -93.853508) (xy 220.552604 -93.852923)
			(xy 220.460314 -93.84329) (xy 220.369529 -93.824097) (xy 220.281236 -93.795553) (xy 220.238574 -93.777308)
			(xy 220.228632 -93.773502) (xy 220.207368 -93.773502) (xy 220.197426 -93.777308) (xy 220.154761 -93.795546)
			(xy 220.066468 -93.824084) (xy 219.975684 -93.84328) (xy 219.883396 -93.852925) (xy 219.837 -93.853508)
			(xy 219.793649 -93.852998) (xy 219.707356 -93.844582) (xy 219.622292 -93.827812) (xy 219.539262 -93.802845)
			(xy 219.459055 -93.769919) (xy 219.382433 -93.729346) (xy 219.31012 -93.681511) (xy 219.242805 -93.626868)
			(xy 219.181124 -93.565936) (xy 219.152978 -93.53296) (xy 219.145866 -93.524324) (xy 219.125546 -93.514672)
			(xy 219.024454 -93.514672) (xy 219.004134 -93.524324) (xy 218.997022 -93.53296) (xy 218.968895 -93.565954)
			(xy 218.907217 -93.626893) (xy 218.839902 -93.681542) (xy 218.767588 -93.729381) (xy 218.690962 -93.769956)
			(xy 218.610752 -93.802882) (xy 218.527718 -93.827846) (xy 218.442649 -93.844612) (xy 218.356353 -93.85302)
			(xy 218.313 -93.853508) (xy 218.266604 -93.852923) (xy 218.174314 -93.84329) (xy 218.083529 -93.824097)
			(xy 217.995236 -93.795553) (xy 217.952574 -93.777308) (xy 217.942632 -93.773502) (xy 217.921368 -93.773502)
			(xy 217.911426 -93.777308) (xy 217.868761 -93.795546) (xy 217.780468 -93.824084) (xy 217.689684 -93.84328)
			(xy 217.597396 -93.852925) (xy 217.551 -93.853508) (xy 217.507649 -93.852998) (xy 217.421356 -93.844582)
			(xy 217.336292 -93.827812) (xy 217.253262 -93.802845) (xy 217.173055 -93.769919) (xy 217.096433 -93.729346)
			(xy 217.02412 -93.681511) (xy 216.956805 -93.626868) (xy 216.895124 -93.565936) (xy 216.866978 -93.53296)
			(xy 216.859866 -93.524324) (xy 216.839546 -93.514672) (xy 216.738454 -93.514672) (xy 216.718134 -93.524324)
			(xy 216.711022 -93.53296) (xy 216.682895 -93.565954) (xy 216.621217 -93.626893) (xy 216.553902 -93.681542)
			(xy 216.481588 -93.729381) (xy 216.404962 -93.769956) (xy 216.324752 -93.802882) (xy 216.241718 -93.827846)
			(xy 216.156649 -93.844612) (xy 216.070353 -93.85302) (xy 216.027 -93.853508) (xy 215.980604 -93.852923)
			(xy 215.888314 -93.84329) (xy 215.797529 -93.824097) (xy 215.709236 -93.795553) (xy 215.666574 -93.777308)
			(xy 215.656632 -93.773502) (xy 215.635368 -93.773502) (xy 215.625426 -93.777308) (xy 215.582821 -93.795523)
			(xy 215.494652 -93.824035) (xy 215.403998 -93.843231) (xy 215.31184 -93.852902) (xy 215.265508 -93.853508)
			(xy 215.265 -93.853508) (xy 215.223898 -93.853033) (xy 215.142043 -93.845448) (xy 215.061238 -93.830343)
			(xy 214.982171 -93.807847) (xy 214.905517 -93.778151) (xy 214.83193 -93.741509) (xy 214.762038 -93.698234)
			(xy 214.696437 -93.648694) (xy 214.635687 -93.593313) (xy 214.580306 -93.532563) (xy 214.530766 -93.466962)
			(xy 214.487491 -93.39707) (xy 214.450849 -93.323483) (xy 214.421153 -93.246829) (xy 214.398657 -93.167762)
			(xy 214.383552 -93.086957) (xy 214.375967 -93.005102) (xy 214.375492 -92.964) (xy 214.375967 -92.922672)
			(xy 214.383643 -92.840374) (xy 214.398918 -92.759143) (xy 214.421662 -92.679678) (xy 214.451679 -92.602666)
			(xy 214.488709 -92.528769) (xy 214.532433 -92.458626) (xy 214.582474 -92.39284) (xy 214.638402 -92.33198)
			(xy 214.699733 -92.276569) (xy 214.76594 -92.227085) (xy 214.83645 -92.183956) (xy 214.910657 -92.147552)
			(xy 214.98792 -92.118188) (xy 215.067574 -92.096116) (xy 215.148932 -92.081528) (xy 215.19007 -92.07754)
			(xy 215.203278 -92.076524) (xy 215.225122 -92.061792) (xy 215.276176 -91.960954) (xy 215.27516 -91.934792)
			(xy 215.268302 -91.923362) (xy 215.257377 -91.905314) (xy 215.237049 -91.868341) (xy 215.227662 -91.849448)
			(xy 215.223171 -91.841117) (xy 215.209268 -91.828297) (xy 215.191652 -91.821415) (xy 215.182196 -91.821)
			(xy 210.945476 -91.821) (xy 210.934977 -91.821519) (xy 210.915729 -91.829915) (xy 210.901438 -91.845301)
			(xy 210.89747 -91.855036) (xy 210.883032 -91.894706) (xy 210.847671 -91.97137) (xy 210.805206 -92.044338)
			(xy 210.756018 -92.112955) (xy 210.700551 -92.176603) (xy 210.639303 -92.23471) (xy 210.572825 -92.286753)
			(xy 210.501716 -92.332263) (xy 210.426615 -92.370831) (xy 210.348197 -92.40211) (xy 210.267169 -92.425819)
			(xy 210.184259 -92.441745) (xy 210.100213 -92.449744) (xy 210.015787 -92.449744) (xy 209.931741 -92.441745)
			(xy 209.848831 -92.425819) (xy 209.767803 -92.40211) (xy 209.689385 -92.370831) (xy 209.614284 -92.332263)
			(xy 209.543175 -92.286753) (xy 209.476697 -92.23471) (xy 209.415449 -92.176603) (xy 209.359982 -92.112955)
			(xy 209.310794 -92.044338) (xy 209.268329 -91.97137) (xy 209.232968 -91.894706) (xy 209.21853 -91.855036)
			(xy 209.214587 -91.84528) (xy 209.200303 -91.82986) (xy 209.181034 -91.821461) (xy 209.170524 -91.821)
			(xy 207.740504 -91.821) (xy 207.730344 -91.82144) (xy 207.711602 -91.829288) (xy 207.704182 -91.83624)
			(xy 207.646016 -91.89593) (xy 207.63865 -91.914726) (xy 207.638904 -91.92514) (xy 207.639412 -91.947746)
			(xy 207.639412 -91.948254) (xy 207.638896 -91.990607) (xy 207.630822 -92.074927) (xy 207.61477 -92.158098)
			(xy 207.590887 -92.239367) (xy 207.559388 -92.317998) (xy 207.520559 -92.39328) (xy 207.47475 -92.464531)
			(xy 207.422378 -92.531105) (xy 207.363915 -92.592401) (xy 207.299892 -92.647863) (xy 207.230887 -92.69699)
			(xy 207.157525 -92.739336) (xy 207.080471 -92.774518) (xy 207.000423 -92.802218) (xy 206.918104 -92.822184)
			(xy 206.83426 -92.834237) (xy 206.74965 -92.838267) (xy 206.66504 -92.834237) (xy 206.581196 -92.822184)
			(xy 206.498877 -92.802218) (xy 206.418829 -92.774518) (xy 206.341775 -92.739336) (xy 206.268413 -92.69699)
			(xy 206.199408 -92.647863) (xy 206.135385 -92.592401) (xy 206.076922 -92.531105) (xy 206.02455 -92.464531)
			(xy 205.978741 -92.39328) (xy 205.939912 -92.317998) (xy 205.908413 -92.239367) (xy 205.88453 -92.158098)
			(xy 205.868478 -92.074927) (xy 205.860404 -91.990607) (xy 205.859888 -91.948254) (xy 205.859888 -91.947746)
			(xy 205.860396 -91.925394) (xy 205.860396 -91.924886) (xy 205.86065 -91.914726) (xy 205.853284 -91.89593)
			(xy 205.795118 -91.83624) (xy 205.787695 -91.829286) (xy 205.768958 -91.821416) (xy 205.758796 -91.821)
			(xy 204.946504 -91.821) (xy 204.936344 -91.82144) (xy 204.917602 -91.829288) (xy 204.910182 -91.83624)
			(xy 204.852016 -91.89593) (xy 204.84465 -91.914726) (xy 204.844904 -91.92514) (xy 204.845412 -91.947746)
			(xy 204.845412 -91.948254) (xy 204.844896 -91.990607) (xy 204.836822 -92.074927) (xy 204.82077 -92.158098)
			(xy 204.796887 -92.239367) (xy 204.765388 -92.317998) (xy 204.726559 -92.39328) (xy 204.68075 -92.464531)
			(xy 204.628378 -92.531105) (xy 204.569915 -92.592401) (xy 204.505892 -92.647863) (xy 204.436887 -92.69699)
			(xy 204.363525 -92.739336) (xy 204.286471 -92.774518) (xy 204.206423 -92.802218) (xy 204.124104 -92.822184)
			(xy 204.04026 -92.834237) (xy 203.95565 -92.838267) (xy 203.87104 -92.834237) (xy 203.787196 -92.822184)
			(xy 203.704877 -92.802218) (xy 203.624829 -92.774518) (xy 203.547775 -92.739336) (xy 203.474413 -92.69699)
			(xy 203.405408 -92.647863) (xy 203.341385 -92.592401) (xy 203.282922 -92.531105) (xy 203.23055 -92.464531)
			(xy 203.184741 -92.39328) (xy 203.145912 -92.317998) (xy 203.114413 -92.239367) (xy 203.09053 -92.158098)
			(xy 203.074478 -92.074927) (xy 203.066404 -91.990607) (xy 203.065888 -91.948254) (xy 203.065888 -91.947746)
			(xy 203.066396 -91.925394) (xy 203.066396 -91.924886) (xy 203.06665 -91.914726) (xy 203.059284 -91.89593)
			(xy 203.001118 -91.83624) (xy 202.993695 -91.829286) (xy 202.974958 -91.821416) (xy 202.964796 -91.821)
			(xy 201.197972 -91.821) (xy 201.196448 -91.821) (xy 201.168 -91.821508) (xy 201.139552 -91.821) (xy 199.471026 -91.821)
			(xy 199.459701 -91.821614) (xy 199.439267 -91.831384) (xy 199.431656 -91.839796) (xy 199.381872 -91.901264)
			(xy 199.375307 -91.910416) (xy 199.370043 -91.932288) (xy 199.371712 -91.943428) (xy 199.380481 -91.988254)
			(xy 199.389899 -92.079112) (xy 199.390508 -92.124784) (xy 199.390508 -92.1258) (xy 199.390004 -92.168148)
			(xy 199.381953 -92.252462) (xy 199.365924 -92.335628) (xy 199.342063 -92.416895) (xy 199.310584 -92.495525)
			(xy 199.271773 -92.570806) (xy 199.225983 -92.642058) (xy 199.173627 -92.708634) (xy 199.115179 -92.769932)
			(xy 199.051169 -92.825397) (xy 198.982177 -92.874526) (xy 198.908827 -92.916875) (xy 198.831784 -92.952059)
			(xy 198.751745 -92.979761) (xy 198.669436 -92.999729) (xy 198.585601 -93.011782) (xy 198.501 -93.015813)
			(xy 198.416399 -93.011782) (xy 198.332564 -92.999729) (xy 198.250255 -92.979761) (xy 198.170216 -92.952059)
			(xy 198.093173 -92.916875) (xy 198.019823 -92.874526) (xy 197.950831 -92.825397) (xy 197.886821 -92.769932)
			(xy 197.828373 -92.708634) (xy 197.776017 -92.642058) (xy 197.730227 -92.570806) (xy 197.691416 -92.495525)
			(xy 197.659937 -92.416895) (xy 197.636076 -92.335628) (xy 197.620047 -92.252462) (xy 197.611996 -92.168148)
			(xy 197.611492 -92.1258) (xy 197.611492 -92.124784) (xy 197.612102 -92.079112) (xy 197.621523 -91.988255)
			(xy 197.630288 -91.943428) (xy 197.632022 -91.932286) (xy 197.626746 -91.910394) (xy 197.620128 -91.901264)
			(xy 197.570344 -91.839796) (xy 197.562722 -91.831409) (xy 197.542289 -91.821674) (xy 197.530974 -91.821)
			(xy 189.534038 -91.821) (xy 189.524402 -91.821422) (xy 189.506487 -91.828529) (xy 189.49244 -91.841724)
			(xy 189.484227 -91.859159) (xy 189.483238 -91.868752) (xy 189.483238 -91.869006) (xy 189.480468 -91.91109)
			(xy 189.467964 -91.994502) (xy 189.447621 -92.076356) (xy 189.419621 -92.155917) (xy 189.384215 -92.232471)
			(xy 189.341723 -92.305329) (xy 189.292524 -92.373838) (xy 189.237061 -92.437382) (xy 189.175833 -92.49539)
			(xy 189.109388 -92.547343) (xy 189.038324 -92.592772) (xy 188.963279 -92.631271) (xy 188.884927 -92.662494)
			(xy 188.80397 -92.686159) (xy 188.721138 -92.702055) (xy 188.637172 -92.710039) (xy 188.552828 -92.710039)
			(xy 188.468862 -92.702055) (xy 188.38603 -92.686159) (xy 188.305073 -92.662494) (xy 188.226721 -92.631271)
			(xy 188.151676 -92.592772) (xy 188.080612 -92.547343) (xy 188.014167 -92.49539) (xy 187.952939 -92.437382)
			(xy 187.897476 -92.373838) (xy 187.848277 -92.305329) (xy 187.805785 -92.232471) (xy 187.770379 -92.155917)
			(xy 187.742379 -92.076356) (xy 187.722036 -91.994502) (xy 187.709532 -91.91109) (xy 187.706762 -91.869006)
			(xy 187.706762 -91.868752) (xy 187.705783 -91.859144) (xy 187.697616 -91.841659) (xy 187.683561 -91.828434)
			(xy 187.665612 -91.821346) (xy 187.655962 -91.821) (xy 180.336444 -91.821) (xy 180.328166 -91.821326)
			(xy 180.31249 -91.826651) (xy 180.30571 -91.831414) (xy 180.272589 -91.855937) (xy 180.202585 -91.899434)
			(xy 180.128856 -91.936266) (xy 180.052034 -91.966116) (xy 179.97278 -91.988729) (xy 179.891773 -92.003909)
			(xy 179.809709 -92.011528) (xy 179.7685 -92.012008) (xy 179.722676 -92.011452) (xy 179.631512 -92.002053)
			(xy 179.541799 -91.983324) (xy 179.45449 -91.955463) (xy 179.37051 -91.918767) (xy 179.33035 -91.896692)
			(xy 179.319566 -91.891372) (xy 179.295577 -91.890293) (xy 179.284376 -91.89466) (xy 179.241058 -91.913595)
			(xy 179.151287 -91.943249) (xy 179.058877 -91.963214) (xy 178.964871 -91.973263) (xy 178.9176 -91.973908)
			(xy 178.87473 -91.973413) (xy 178.789386 -91.965193) (xy 178.70523 -91.948791) (xy 178.623045 -91.924359)
			(xy 178.543596 -91.892126) (xy 178.46762 -91.852389) (xy 178.431444 -91.829382) (xy 178.425171 -91.82555)
			(xy 178.411104 -91.821302) (xy 178.403758 -91.821) (xy 157.099 -91.821) (xy 157.06574 -91.820479)
			(xy 156.99979 -91.811791) (xy 156.935539 -91.794566) (xy 156.874088 -91.769097) (xy 156.816489 -91.735821)
			(xy 156.763729 -91.695308) (xy 156.739844 -91.672156) (xy 148.902674 -83.834986) (xy 148.895278 -83.828134)
			(xy 148.876679 -83.820396) (xy 148.866606 -83.82) (xy 37.213794 -83.82) (xy 37.203724 -83.820424)
			(xy 37.185121 -83.82814) (xy 37.177726 -83.834986) (xy 36.034726 -84.977986) (xy 36.02789 -84.985388)
			(xy 36.020183 -85.003986) (xy 36.01974 -85.014054) (xy 36.01974 -86.542569) (xy 43.120052 -86.542569)
			(xy 43.120052 -86.457847) (xy 43.128105 -86.37351) (xy 43.144139 -86.29032) (xy 43.168007 -86.20903)
			(xy 43.199495 -86.130378) (xy 43.238317 -86.055075) (xy 43.28412 -85.983803) (xy 43.336491 -85.917207)
			(xy 43.394956 -85.855892) (xy 43.458984 -85.800411) (xy 43.527996 -85.751268) (xy 43.601366 -85.708908)
			(xy 43.678431 -85.673713) (xy 43.758493 -85.646004) (xy 43.840826 -85.62603) (xy 43.924685 -85.613973)
			(xy 44.00931 -85.609942) (xy 44.093935 -85.613973) (xy 44.177794 -85.62603) (xy 44.260127 -85.646004)
			(xy 44.340189 -85.673713) (xy 44.417254 -85.708908) (xy 44.490624 -85.751268) (xy 44.559636 -85.800411)
			(xy 44.623664 -85.855892) (xy 44.682129 -85.917207) (xy 44.7345 -85.983803) (xy 44.780303 -86.055075)
			(xy 44.819125 -86.130378) (xy 44.850613 -86.20903) (xy 44.874481 -86.29032) (xy 44.890515 -86.37351)
			(xy 44.898568 -86.457847) (xy 44.898929 -86.488213) (xy 72.953622 -86.488213) (xy 72.953622 -86.403491)
			(xy 72.961675 -86.319154) (xy 72.977709 -86.235964) (xy 73.001577 -86.154674) (xy 73.033065 -86.076022)
			(xy 73.071887 -86.000719) (xy 73.11769 -85.929447) (xy 73.170061 -85.862851) (xy 73.228526 -85.801536)
			(xy 73.292554 -85.746055) (xy 73.361566 -85.696912) (xy 73.434936 -85.654552) (xy 73.512001 -85.619357)
			(xy 73.592063 -85.591648) (xy 73.674396 -85.571674) (xy 73.758255 -85.559617) (xy 73.84288 -85.555586)
			(xy 73.927505 -85.559617) (xy 74.011364 -85.571674) (xy 74.093697 -85.591648) (xy 74.173759 -85.619357)
			(xy 74.250824 -85.654552) (xy 74.324194 -85.696912) (xy 74.393206 -85.746055) (xy 74.457234 -85.801536)
			(xy 74.515699 -85.862851) (xy 74.56807 -85.929447) (xy 74.613873 -86.000719) (xy 74.652695 -86.076022)
			(xy 74.684183 -86.154674) (xy 74.708051 -86.235964) (xy 74.724085 -86.319154) (xy 74.732138 -86.403491)
			(xy 74.732642 -86.445852) (xy 74.732138 -86.488213) (xy 74.726948 -86.542569) (xy 78.757776 -86.542569)
			(xy 78.757776 -86.457847) (xy 78.765829 -86.37351) (xy 78.781863 -86.29032) (xy 78.805731 -86.20903)
			(xy 78.837219 -86.130378) (xy 78.876041 -86.055075) (xy 78.921844 -85.983803) (xy 78.974215 -85.917207)
			(xy 79.03268 -85.855892) (xy 79.096708 -85.800411) (xy 79.16572 -85.751268) (xy 79.23909 -85.708908)
			(xy 79.316155 -85.673713) (xy 79.396217 -85.646004) (xy 79.47855 -85.62603) (xy 79.562409 -85.613973)
			(xy 79.647034 -85.609942) (xy 79.731659 -85.613973) (xy 79.815518 -85.62603) (xy 79.897851 -85.646004)
			(xy 79.977913 -85.673713) (xy 80.054978 -85.708908) (xy 80.128348 -85.751268) (xy 80.19736 -85.800411)
			(xy 80.261388 -85.855892) (xy 80.319853 -85.917207) (xy 80.372224 -85.983803) (xy 80.418027 -86.055075)
			(xy 80.456849 -86.130378) (xy 80.488337 -86.20903) (xy 80.512205 -86.29032) (xy 80.528239 -86.37351)
			(xy 80.536292 -86.457847) (xy 80.536656 -86.488467) (xy 112.713512 -86.488467) (xy 112.713512 -86.403745)
			(xy 112.721565 -86.319408) (xy 112.737599 -86.236218) (xy 112.761467 -86.154928) (xy 112.792955 -86.076276)
			(xy 112.831777 -86.000973) (xy 112.87758 -85.929701) (xy 112.929951 -85.863105) (xy 112.988416 -85.80179)
			(xy 113.052444 -85.746309) (xy 113.121456 -85.697166) (xy 113.194826 -85.654806) (xy 113.271891 -85.619611)
			(xy 113.351953 -85.591902) (xy 113.434286 -85.571928) (xy 113.518145 -85.559871) (xy 113.60277 -85.55584)
			(xy 113.687395 -85.559871) (xy 113.771254 -85.571928) (xy 113.853587 -85.591902) (xy 113.933649 -85.619611)
			(xy 114.010714 -85.654806) (xy 114.084084 -85.697166) (xy 114.153096 -85.746309) (xy 114.217124 -85.80179)
			(xy 114.275589 -85.863105) (xy 114.32796 -85.929701) (xy 114.373763 -86.000973) (xy 114.412585 -86.076276)
			(xy 114.444073 -86.154928) (xy 114.467941 -86.236218) (xy 114.483975 -86.319408) (xy 114.492028 -86.403745)
			(xy 114.492532 -86.446106) (xy 114.492028 -86.488467) (xy 119.276872 -86.488467) (xy 119.276872 -86.403745)
			(xy 119.284925 -86.319408) (xy 119.300959 -86.236218) (xy 119.324827 -86.154928) (xy 119.356315 -86.076276)
			(xy 119.395137 -86.000973) (xy 119.44094 -85.929701) (xy 119.493311 -85.863105) (xy 119.551776 -85.80179)
			(xy 119.615804 -85.746309) (xy 119.684816 -85.697166) (xy 119.758186 -85.654806) (xy 119.835251 -85.619611)
			(xy 119.915313 -85.591902) (xy 119.997646 -85.571928) (xy 120.081505 -85.559871) (xy 120.16613 -85.55584)
			(xy 120.250755 -85.559871) (xy 120.334614 -85.571928) (xy 120.416947 -85.591902) (xy 120.497009 -85.619611)
			(xy 120.574074 -85.654806) (xy 120.647444 -85.697166) (xy 120.716456 -85.746309) (xy 120.780484 -85.80179)
			(xy 120.838949 -85.863105) (xy 120.89132 -85.929701) (xy 120.937123 -86.000973) (xy 120.975945 -86.076276)
			(xy 121.007433 -86.154928) (xy 121.031301 -86.236218) (xy 121.047335 -86.319408) (xy 121.055388 -86.403745)
			(xy 121.055892 -86.446106) (xy 121.055388 -86.488467) (xy 137.556744 -86.488467) (xy 137.556744 -86.403745)
			(xy 137.564797 -86.319408) (xy 137.580831 -86.236218) (xy 137.604699 -86.154928) (xy 137.636187 -86.076276)
			(xy 137.675009 -86.000973) (xy 137.720812 -85.929701) (xy 137.773183 -85.863105) (xy 137.831648 -85.80179)
			(xy 137.895676 -85.746309) (xy 137.964688 -85.697166) (xy 138.038058 -85.654806) (xy 138.115123 -85.619611)
			(xy 138.195185 -85.591902) (xy 138.277518 -85.571928) (xy 138.361377 -85.559871) (xy 138.446002 -85.55584)
			(xy 138.530627 -85.559871) (xy 138.614486 -85.571928) (xy 138.696819 -85.591902) (xy 138.776881 -85.619611)
			(xy 138.853946 -85.654806) (xy 138.927316 -85.697166) (xy 138.996328 -85.746309) (xy 139.060356 -85.80179)
			(xy 139.118821 -85.863105) (xy 139.171192 -85.929701) (xy 139.216995 -86.000973) (xy 139.255817 -86.076276)
			(xy 139.287305 -86.154928) (xy 139.311173 -86.236218) (xy 139.327207 -86.319408) (xy 139.33526 -86.403745)
			(xy 139.335764 -86.446106) (xy 139.33526 -86.488467) (xy 139.327207 -86.572804) (xy 139.311173 -86.655994)
			(xy 139.287305 -86.737284) (xy 139.255817 -86.815936) (xy 139.216995 -86.891239) (xy 139.171192 -86.962511)
			(xy 139.118821 -87.029107) (xy 139.060356 -87.090422) (xy 138.996328 -87.145903) (xy 138.927316 -87.195046)
			(xy 138.853946 -87.237406) (xy 138.776881 -87.272601) (xy 138.696819 -87.30031) (xy 138.614486 -87.320284)
			(xy 138.530627 -87.332341) (xy 138.446002 -87.336373) (xy 138.361377 -87.332341) (xy 138.277518 -87.320284)
			(xy 138.195185 -87.30031) (xy 138.115123 -87.272601) (xy 138.038058 -87.237406) (xy 137.964688 -87.195046)
			(xy 137.895676 -87.145903) (xy 137.831648 -87.090422) (xy 137.773183 -87.029107) (xy 137.720812 -86.962511)
			(xy 137.675009 -86.891239) (xy 137.636187 -86.815936) (xy 137.604699 -86.737284) (xy 137.580831 -86.655994)
			(xy 137.564797 -86.572804) (xy 137.556744 -86.488467) (xy 121.055388 -86.488467) (xy 121.047335 -86.572804)
			(xy 121.031301 -86.655994) (xy 121.007433 -86.737284) (xy 120.975945 -86.815936) (xy 120.937123 -86.891239)
			(xy 120.89132 -86.962511) (xy 120.838949 -87.029107) (xy 120.780484 -87.090422) (xy 120.716456 -87.145903)
			(xy 120.647444 -87.195046) (xy 120.574074 -87.237406) (xy 120.497009 -87.272601) (xy 120.416947 -87.30031)
			(xy 120.334614 -87.320284) (xy 120.250755 -87.332341) (xy 120.16613 -87.336373) (xy 120.081505 -87.332341)
			(xy 119.997646 -87.320284) (xy 119.915313 -87.30031) (xy 119.835251 -87.272601) (xy 119.758186 -87.237406)
			(xy 119.684816 -87.195046) (xy 119.615804 -87.145903) (xy 119.551776 -87.090422) (xy 119.493311 -87.029107)
			(xy 119.44094 -86.962511) (xy 119.395137 -86.891239) (xy 119.356315 -86.815936) (xy 119.324827 -86.737284)
			(xy 119.300959 -86.655994) (xy 119.284925 -86.572804) (xy 119.276872 -86.488467) (xy 114.492028 -86.488467)
			(xy 114.483975 -86.572804) (xy 114.467941 -86.655994) (xy 114.444073 -86.737284) (xy 114.412585 -86.815936)
			(xy 114.373763 -86.891239) (xy 114.32796 -86.962511) (xy 114.275589 -87.029107) (xy 114.217124 -87.090422)
			(xy 114.153096 -87.145903) (xy 114.084084 -87.195046) (xy 114.010714 -87.237406) (xy 113.933649 -87.272601)
			(xy 113.853587 -87.30031) (xy 113.771254 -87.320284) (xy 113.687395 -87.332341) (xy 113.60277 -87.336373)
			(xy 113.518145 -87.332341) (xy 113.434286 -87.320284) (xy 113.351953 -87.30031) (xy 113.271891 -87.272601)
			(xy 113.194826 -87.237406) (xy 113.121456 -87.195046) (xy 113.052444 -87.145903) (xy 112.988416 -87.090422)
			(xy 112.929951 -87.029107) (xy 112.87758 -86.962511) (xy 112.831777 -86.891239) (xy 112.792955 -86.815936)
			(xy 112.761467 -86.737284) (xy 112.737599 -86.655994) (xy 112.721565 -86.572804) (xy 112.713512 -86.488467)
			(xy 80.536656 -86.488467) (xy 80.536796 -86.500208) (xy 80.536292 -86.542569) (xy 80.528239 -86.626906)
			(xy 80.512205 -86.710096) (xy 80.488337 -86.791386) (xy 80.456849 -86.870038) (xy 80.418027 -86.945341)
			(xy 80.372224 -87.016613) (xy 80.319853 -87.083209) (xy 80.261388 -87.144524) (xy 80.19736 -87.200005)
			(xy 80.128348 -87.249148) (xy 80.054978 -87.291508) (xy 79.977913 -87.326703) (xy 79.897851 -87.354412)
			(xy 79.815518 -87.374386) (xy 79.731659 -87.386443) (xy 79.647034 -87.390475) (xy 79.562409 -87.386443)
			(xy 79.47855 -87.374386) (xy 79.396217 -87.354412) (xy 79.316155 -87.326703) (xy 79.23909 -87.291508)
			(xy 79.16572 -87.249148) (xy 79.096708 -87.200005) (xy 79.03268 -87.144524) (xy 78.974215 -87.083209)
			(xy 78.921844 -87.016613) (xy 78.876041 -86.945341) (xy 78.837219 -86.870038) (xy 78.805731 -86.791386)
			(xy 78.781863 -86.710096) (xy 78.765829 -86.626906) (xy 78.757776 -86.542569) (xy 74.726948 -86.542569)
			(xy 74.724085 -86.57255) (xy 74.708051 -86.65574) (xy 74.684183 -86.73703) (xy 74.652695 -86.815682)
			(xy 74.613873 -86.890985) (xy 74.56807 -86.962257) (xy 74.515699 -87.028853) (xy 74.457234 -87.090168)
			(xy 74.393206 -87.145649) (xy 74.324194 -87.194792) (xy 74.250824 -87.237152) (xy 74.173759 -87.272347)
			(xy 74.093697 -87.300056) (xy 74.011364 -87.32003) (xy 73.927505 -87.332087) (xy 73.84288 -87.336119)
			(xy 73.758255 -87.332087) (xy 73.674396 -87.32003) (xy 73.592063 -87.300056) (xy 73.512001 -87.272347)
			(xy 73.434936 -87.237152) (xy 73.361566 -87.194792) (xy 73.292554 -87.145649) (xy 73.228526 -87.090168)
			(xy 73.170061 -87.028853) (xy 73.11769 -86.962257) (xy 73.071887 -86.890985) (xy 73.033065 -86.815682)
			(xy 73.001577 -86.73703) (xy 72.977709 -86.65574) (xy 72.961675 -86.57255) (xy 72.953622 -86.488213)
			(xy 44.898929 -86.488213) (xy 44.899072 -86.500208) (xy 44.898568 -86.542569) (xy 44.890515 -86.626906)
			(xy 44.874481 -86.710096) (xy 44.850613 -86.791386) (xy 44.819125 -86.870038) (xy 44.780303 -86.945341)
			(xy 44.7345 -87.016613) (xy 44.682129 -87.083209) (xy 44.623664 -87.144524) (xy 44.559636 -87.200005)
			(xy 44.490624 -87.249148) (xy 44.417254 -87.291508) (xy 44.340189 -87.326703) (xy 44.260127 -87.354412)
			(xy 44.177794 -87.374386) (xy 44.093935 -87.386443) (xy 44.00931 -87.390475) (xy 43.924685 -87.386443)
			(xy 43.840826 -87.374386) (xy 43.758493 -87.354412) (xy 43.678431 -87.326703) (xy 43.601366 -87.291508)
			(xy 43.527996 -87.249148) (xy 43.458984 -87.200005) (xy 43.394956 -87.144524) (xy 43.336491 -87.083209)
			(xy 43.28412 -87.016613) (xy 43.238317 -86.945341) (xy 43.199495 -86.870038) (xy 43.168007 -86.791386)
			(xy 43.144139 -86.710096) (xy 43.128105 -86.626906) (xy 43.120052 -86.542569) (xy 36.01974 -86.542569)
			(xy 36.01974 -93.133361) (xy 189.121792 -93.133361) (xy 189.121792 -93.048639) (xy 189.129845 -92.964302)
			(xy 189.145879 -92.881112) (xy 189.169747 -92.799822) (xy 189.201235 -92.72117) (xy 189.240057 -92.645867)
			(xy 189.28586 -92.574595) (xy 189.338231 -92.507999) (xy 189.396696 -92.446684) (xy 189.460724 -92.391203)
			(xy 189.529736 -92.34206) (xy 189.603106 -92.2997) (xy 189.680171 -92.264505) (xy 189.760233 -92.236796)
			(xy 189.842566 -92.216822) (xy 189.926425 -92.204765) (xy 190.01105 -92.200734) (xy 190.095675 -92.204765)
			(xy 190.179534 -92.216822) (xy 190.261867 -92.236796) (xy 190.341929 -92.264505) (xy 190.418994 -92.2997)
			(xy 190.492364 -92.34206) (xy 190.561376 -92.391203) (xy 190.625404 -92.446684) (xy 190.683869 -92.507999)
			(xy 190.73624 -92.574595) (xy 190.782043 -92.645867) (xy 190.820865 -92.72117) (xy 190.852353 -92.799822)
			(xy 190.876221 -92.881112) (xy 190.892255 -92.964302) (xy 190.900308 -93.048639) (xy 190.900812 -93.091)
			(xy 190.900308 -93.133361) (xy 190.892255 -93.217698) (xy 190.876221 -93.300888) (xy 190.852353 -93.382178)
			(xy 190.820865 -93.46083) (xy 190.782043 -93.536133) (xy 190.73624 -93.607405) (xy 190.683869 -93.674001)
			(xy 190.625404 -93.735316) (xy 190.561376 -93.790797) (xy 190.492364 -93.83994) (xy 190.418994 -93.8823)
			(xy 190.341929 -93.917495) (xy 190.261867 -93.945204) (xy 190.179534 -93.965178) (xy 190.095675 -93.977235)
			(xy 190.01105 -93.981267) (xy 189.926425 -93.977235) (xy 189.842566 -93.965178) (xy 189.760233 -93.945204)
			(xy 189.680171 -93.917495) (xy 189.603106 -93.8823) (xy 189.529736 -93.83994) (xy 189.460724 -93.790797)
			(xy 189.396696 -93.735316) (xy 189.338231 -93.674001) (xy 189.28586 -93.607405) (xy 189.240057 -93.536133)
			(xy 189.201235 -93.46083) (xy 189.169747 -93.382178) (xy 189.145879 -93.300888) (xy 189.129845 -93.217698)
			(xy 189.121792 -93.133361) (xy 36.01974 -93.133361) (xy 36.01974 -113.078711) (xy 55.960768 -113.078711)
			(xy 55.960768 -112.993989) (xy 55.968821 -112.909652) (xy 55.984855 -112.826462) (xy 56.008723 -112.745172)
			(xy 56.040211 -112.66652) (xy 56.079033 -112.591217) (xy 56.124836 -112.519945) (xy 56.177207 -112.453349)
			(xy 56.235672 -112.392034) (xy 56.2997 -112.336553) (xy 56.368712 -112.28741) (xy 56.442082 -112.24505)
			(xy 56.519147 -112.209855) (xy 56.599209 -112.182146) (xy 56.681542 -112.162172) (xy 56.765401 -112.150115)
			(xy 56.850026 -112.146084) (xy 56.934651 -112.150115) (xy 57.01851 -112.162172) (xy 57.100843 -112.182146)
			(xy 57.180905 -112.209855) (xy 57.25797 -112.24505) (xy 57.33134 -112.28741) (xy 57.400352 -112.336553)
			(xy 57.46438 -112.392034) (xy 57.522845 -112.453349) (xy 57.575216 -112.519945) (xy 57.621019 -112.591217)
			(xy 57.659841 -112.66652) (xy 57.691329 -112.745172) (xy 57.715197 -112.826462) (xy 57.731231 -112.909652)
			(xy 57.739284 -112.993989) (xy 57.739788 -113.03635) (xy 57.739284 -113.078711) (xy 95.960688 -113.078711)
			(xy 95.960688 -112.993989) (xy 95.968741 -112.909652) (xy 95.984775 -112.826462) (xy 96.008643 -112.745172)
			(xy 96.040131 -112.66652) (xy 96.078953 -112.591217) (xy 96.124756 -112.519945) (xy 96.177127 -112.453349)
			(xy 96.235592 -112.392034) (xy 96.29962 -112.336553) (xy 96.368632 -112.28741) (xy 96.442002 -112.24505)
			(xy 96.519067 -112.209855) (xy 96.599129 -112.182146) (xy 96.681462 -112.162172) (xy 96.765321 -112.150115)
			(xy 96.849946 -112.146084) (xy 96.934571 -112.150115) (xy 97.01843 -112.162172) (xy 97.100763 -112.182146)
			(xy 97.180825 -112.209855) (xy 97.25789 -112.24505) (xy 97.33126 -112.28741) (xy 97.400272 -112.336553)
			(xy 97.4643 -112.392034) (xy 97.522765 -112.453349) (xy 97.575136 -112.519945) (xy 97.620939 -112.591217)
			(xy 97.659761 -112.66652) (xy 97.691249 -112.745172) (xy 97.715117 -112.826462) (xy 97.726284 -112.884401)
			(xy 108.335568 -112.884401) (xy 108.335568 -112.799679) (xy 108.343621 -112.715342) (xy 108.359655 -112.632152)
			(xy 108.383523 -112.550862) (xy 108.415011 -112.47221) (xy 108.453833 -112.396907) (xy 108.499636 -112.325635)
			(xy 108.552007 -112.259039) (xy 108.610472 -112.197724) (xy 108.6745 -112.142243) (xy 108.743512 -112.0931)
			(xy 108.816882 -112.05074) (xy 108.893947 -112.015545) (xy 108.974009 -111.987836) (xy 109.056342 -111.967862)
			(xy 109.140201 -111.955805) (xy 109.224826 -111.951774) (xy 109.309451 -111.955805) (xy 109.39331 -111.967862)
			(xy 109.475643 -111.987836) (xy 109.555705 -112.015545) (xy 109.63277 -112.05074) (xy 109.70614 -112.0931)
			(xy 109.775152 -112.142243) (xy 109.83918 -112.197724) (xy 109.897645 -112.259039) (xy 109.950016 -112.325635)
			(xy 109.995819 -112.396907) (xy 110.034641 -112.47221) (xy 110.066129 -112.550862) (xy 110.089997 -112.632152)
			(xy 110.106031 -112.715342) (xy 110.114084 -112.799679) (xy 110.114588 -112.84204) (xy 110.114084 -112.884401)
			(xy 110.106031 -112.968738) (xy 110.089997 -113.051928) (xy 110.082133 -113.078711) (xy 135.960862 -113.078711)
			(xy 135.960862 -112.993989) (xy 135.968915 -112.909652) (xy 135.984949 -112.826462) (xy 136.008817 -112.745172)
			(xy 136.040305 -112.66652) (xy 136.079127 -112.591217) (xy 136.12493 -112.519945) (xy 136.177301 -112.453349)
			(xy 136.235766 -112.392034) (xy 136.299794 -112.336553) (xy 136.368806 -112.28741) (xy 136.442176 -112.24505)
			(xy 136.519241 -112.209855) (xy 136.599303 -112.182146) (xy 136.681636 -112.162172) (xy 136.765495 -112.150115)
			(xy 136.85012 -112.146084) (xy 136.934745 -112.150115) (xy 137.018604 -112.162172) (xy 137.100937 -112.182146)
			(xy 137.180999 -112.209855) (xy 137.258064 -112.24505) (xy 137.331434 -112.28741) (xy 137.400446 -112.336553)
			(xy 137.464474 -112.392034) (xy 137.522939 -112.453349) (xy 137.57531 -112.519945) (xy 137.621113 -112.591217)
			(xy 137.659935 -112.66652) (xy 137.691423 -112.745172) (xy 137.715291 -112.826462) (xy 137.731325 -112.909652)
			(xy 137.739378 -112.993989) (xy 137.739882 -113.03635) (xy 137.739381 -113.078457) (xy 138.683742 -113.078457)
			(xy 138.683742 -112.993735) (xy 138.691795 -112.909398) (xy 138.707829 -112.826208) (xy 138.731697 -112.744918)
			(xy 138.763185 -112.666266) (xy 138.802007 -112.590963) (xy 138.84781 -112.519691) (xy 138.900181 -112.453095)
			(xy 138.958646 -112.39178) (xy 139.022674 -112.336299) (xy 139.091686 -112.287156) (xy 139.165056 -112.244796)
			(xy 139.242121 -112.209601) (xy 139.322183 -112.181892) (xy 139.404516 -112.161918) (xy 139.488375 -112.149861)
			(xy 139.573 -112.14583) (xy 139.657625 -112.149861) (xy 139.741484 -112.161918) (xy 139.823817 -112.181892)
			(xy 139.903879 -112.209601) (xy 139.980944 -112.244796) (xy 140.054314 -112.287156) (xy 140.123326 -112.336299)
			(xy 140.187354 -112.39178) (xy 140.245819 -112.453095) (xy 140.29819 -112.519691) (xy 140.343993 -112.590963)
			(xy 140.382815 -112.666266) (xy 140.414303 -112.744918) (xy 140.438171 -112.826208) (xy 140.441222 -112.84204)
			(xy 148.335492 -112.84204) (xy 148.33599 -112.800937) (xy 148.343572 -112.719083) (xy 148.358674 -112.638277)
			(xy 148.381167 -112.559209) (xy 148.41086 -112.482554) (xy 148.4475 -112.408966) (xy 148.490773 -112.339073)
			(xy 148.540311 -112.273471) (xy 148.595691 -112.212719) (xy 148.65644 -112.157337) (xy 148.72204 -112.107796)
			(xy 148.791931 -112.06452) (xy 148.865518 -112.027877) (xy 148.942171 -111.99818) (xy 149.021238 -111.975683)
			(xy 149.102043 -111.960577) (xy 149.183898 -111.952992) (xy 149.225 -111.952532) (xy 149.268098 -111.953004)
			(xy 149.353887 -111.961357) (xy 149.438467 -111.977965) (xy 149.521045 -112.002674) (xy 149.600847 -112.035251)
			(xy 149.677125 -112.075391) (xy 149.749165 -112.122718) (xy 149.816292 -112.176789) (xy 149.877876 -112.237097)
			(xy 149.933341 -112.303076) (xy 149.982167 -112.374109) (xy 150.023896 -112.44953) (xy 150.058137 -112.528632)
			(xy 150.071836 -112.569498) (xy 150.075523 -112.579517) (xy 150.089733 -112.595429) (xy 150.099268 -112.600232)
			(xy 150.137803 -112.618172) (xy 150.211568 -112.660421) (xy 150.280968 -112.709511) (xy 150.345369 -112.764997)
			(xy 150.404186 -112.826371) (xy 150.456881 -112.893075) (xy 150.502974 -112.964501) (xy 150.542046 -113.039997)
			(xy 150.557499 -113.078457) (xy 175.961036 -113.078457) (xy 175.961036 -112.993735) (xy 175.969089 -112.909398)
			(xy 175.985123 -112.826208) (xy 176.008991 -112.744918) (xy 176.040479 -112.666266) (xy 176.079301 -112.590963)
			(xy 176.125104 -112.519691) (xy 176.177475 -112.453095) (xy 176.23594 -112.39178) (xy 176.299968 -112.336299)
			(xy 176.36898 -112.287156) (xy 176.44235 -112.244796) (xy 176.519415 -112.209601) (xy 176.599477 -112.181892)
			(xy 176.68181 -112.161918) (xy 176.765669 -112.149861) (xy 176.850294 -112.14583) (xy 176.934919 -112.149861)
			(xy 177.018778 -112.161918) (xy 177.101111 -112.181892) (xy 177.181173 -112.209601) (xy 177.258238 -112.244796)
			(xy 177.331608 -112.287156) (xy 177.40062 -112.336299) (xy 177.464648 -112.39178) (xy 177.523113 -112.453095)
			(xy 177.575484 -112.519691) (xy 177.621287 -112.590963) (xy 177.660109 -112.666266) (xy 177.691597 -112.744918)
			(xy 177.715465 -112.826208) (xy 177.731499 -112.909398) (xy 177.739552 -112.993735) (xy 177.740056 -113.036096)
			(xy 177.739552 -113.078457) (xy 177.731499 -113.162794) (xy 177.715465 -113.245984) (xy 177.691597 -113.327274)
			(xy 177.660109 -113.405926) (xy 177.621287 -113.481229) (xy 177.575484 -113.552501) (xy 177.523113 -113.619097)
			(xy 177.464648 -113.680412) (xy 177.40062 -113.735893) (xy 177.331608 -113.785036) (xy 177.258238 -113.827396)
			(xy 177.181173 -113.862591) (xy 177.101111 -113.8903) (xy 177.018778 -113.910274) (xy 176.934919 -113.922331)
			(xy 176.850294 -113.926363) (xy 176.765669 -113.922331) (xy 176.68181 -113.910274) (xy 176.599477 -113.8903)
			(xy 176.519415 -113.862591) (xy 176.44235 -113.827396) (xy 176.36898 -113.785036) (xy 176.299968 -113.735893)
			(xy 176.23594 -113.680412) (xy 176.177475 -113.619097) (xy 176.125104 -113.552501) (xy 176.079301 -113.481229)
			(xy 176.040479 -113.405926) (xy 176.008991 -113.327274) (xy 175.985123 -113.245984) (xy 175.969089 -113.162794)
			(xy 175.961036 -113.078457) (xy 150.557499 -113.078457) (xy 150.573739 -113.118875) (xy 150.597765 -113.200416)
			(xy 150.613906 -113.283877) (xy 150.622013 -113.368496) (xy 150.622508 -113.411) (xy 150.622033 -113.452102)
			(xy 150.614448 -113.533957) (xy 150.599343 -113.614762) (xy 150.576847 -113.693829) (xy 150.547151 -113.770483)
			(xy 150.510509 -113.84407) (xy 150.467234 -113.913962) (xy 150.417694 -113.979563) (xy 150.362313 -114.040313)
			(xy 150.301563 -114.095694) (xy 150.235962 -114.145234) (xy 150.16607 -114.188509) (xy 150.092483 -114.225151)
			(xy 150.015829 -114.254847) (xy 149.936762 -114.277343) (xy 149.855957 -114.292448) (xy 149.774102 -114.300033)
			(xy 149.733 -114.300508) (xy 149.689903 -114.300009) (xy 149.604115 -114.291656) (xy 149.519537 -114.275048)
			(xy 149.436961 -114.250341) (xy 149.35716 -114.217766) (xy 149.280882 -114.177627) (xy 149.208843 -114.130303)
			(xy 149.141716 -114.076235) (xy 149.080132 -114.01593) (xy 149.024666 -113.949953) (xy 148.975839 -113.878923)
			(xy 148.934108 -113.803506) (xy 148.899864 -113.724406) (xy 148.886164 -113.683542) (xy 148.8825 -113.673512)
			(xy 148.868273 -113.657607) (xy 148.858732 -113.652808) (xy 148.820213 -113.634836) (xy 148.746449 -113.59259)
			(xy 148.677049 -113.543502) (xy 148.612648 -113.488019) (xy 148.553831 -113.426648) (xy 148.501135 -113.359947)
			(xy 148.45504 -113.288524) (xy 148.415967 -113.213032) (xy 148.384272 -113.134156) (xy 148.360243 -113.052618)
			(xy 148.3441 -112.96916) (xy 148.335989 -112.884543) (xy 148.335492 -112.84204) (xy 140.441222 -112.84204)
			(xy 140.454205 -112.909398) (xy 140.462258 -112.993735) (xy 140.462762 -113.036096) (xy 140.462258 -113.078457)
			(xy 140.454205 -113.162794) (xy 140.438171 -113.245984) (xy 140.414303 -113.327274) (xy 140.382815 -113.405926)
			(xy 140.343993 -113.481229) (xy 140.29819 -113.552501) (xy 140.245819 -113.619097) (xy 140.187354 -113.680412)
			(xy 140.123326 -113.735893) (xy 140.054314 -113.785036) (xy 139.980944 -113.827396) (xy 139.903879 -113.862591)
			(xy 139.823817 -113.8903) (xy 139.741484 -113.910274) (xy 139.657625 -113.922331) (xy 139.573 -113.926363)
			(xy 139.488375 -113.922331) (xy 139.404516 -113.910274) (xy 139.322183 -113.8903) (xy 139.242121 -113.862591)
			(xy 139.165056 -113.827396) (xy 139.091686 -113.785036) (xy 139.022674 -113.735893) (xy 138.958646 -113.680412)
			(xy 138.900181 -113.619097) (xy 138.84781 -113.552501) (xy 138.802007 -113.481229) (xy 138.763185 -113.405926)
			(xy 138.731697 -113.327274) (xy 138.707829 -113.245984) (xy 138.691795 -113.162794) (xy 138.683742 -113.078457)
			(xy 137.739381 -113.078457) (xy 137.739378 -113.078711) (xy 137.731325 -113.163048) (xy 137.715291 -113.246238)
			(xy 137.691423 -113.327528) (xy 137.659935 -113.40618) (xy 137.621113 -113.481483) (xy 137.57531 -113.552755)
			(xy 137.522939 -113.619351) (xy 137.464474 -113.680666) (xy 137.400446 -113.736147) (xy 137.331434 -113.78529)
			(xy 137.258064 -113.82765) (xy 137.180999 -113.862845) (xy 137.100937 -113.890554) (xy 137.018604 -113.910528)
			(xy 136.934745 -113.922585) (xy 136.85012 -113.926617) (xy 136.765495 -113.922585) (xy 136.681636 -113.910528)
			(xy 136.599303 -113.890554) (xy 136.519241 -113.862845) (xy 136.442176 -113.82765) (xy 136.368806 -113.78529)
			(xy 136.299794 -113.736147) (xy 136.235766 -113.680666) (xy 136.177301 -113.619351) (xy 136.12493 -113.552755)
			(xy 136.079127 -113.481483) (xy 136.040305 -113.40618) (xy 136.008817 -113.327528) (xy 135.984949 -113.246238)
			(xy 135.968915 -113.163048) (xy 135.960862 -113.078711) (xy 110.082133 -113.078711) (xy 110.066129 -113.133218)
			(xy 110.034641 -113.21187) (xy 109.995819 -113.287173) (xy 109.950016 -113.358445) (xy 109.897645 -113.425041)
			(xy 109.83918 -113.486356) (xy 109.775152 -113.541837) (xy 109.70614 -113.59098) (xy 109.63277 -113.63334)
			(xy 109.555705 -113.668535) (xy 109.475643 -113.696244) (xy 109.39331 -113.716218) (xy 109.309451 -113.728275)
			(xy 109.224826 -113.732307) (xy 109.140201 -113.728275) (xy 109.056342 -113.716218) (xy 108.974009 -113.696244)
			(xy 108.893947 -113.668535) (xy 108.816882 -113.63334) (xy 108.743512 -113.59098) (xy 108.6745 -113.541837)
			(xy 108.610472 -113.486356) (xy 108.552007 -113.425041) (xy 108.499636 -113.358445) (xy 108.453833 -113.287173)
			(xy 108.415011 -113.21187) (xy 108.383523 -113.133218) (xy 108.359655 -113.051928) (xy 108.343621 -112.968738)
			(xy 108.335568 -112.884401) (xy 97.726284 -112.884401) (xy 97.731151 -112.909652) (xy 97.739204 -112.993989)
			(xy 97.739708 -113.03635) (xy 97.739204 -113.078711) (xy 97.731151 -113.163048) (xy 97.715117 -113.246238)
			(xy 97.691249 -113.327528) (xy 97.659761 -113.40618) (xy 97.620939 -113.481483) (xy 97.575136 -113.552755)
			(xy 97.522765 -113.619351) (xy 97.4643 -113.680666) (xy 97.400272 -113.736147) (xy 97.33126 -113.78529)
			(xy 97.25789 -113.82765) (xy 97.180825 -113.862845) (xy 97.100763 -113.890554) (xy 97.01843 -113.910528)
			(xy 96.934571 -113.922585) (xy 96.849946 -113.926617) (xy 96.765321 -113.922585) (xy 96.681462 -113.910528)
			(xy 96.599129 -113.890554) (xy 96.519067 -113.862845) (xy 96.442002 -113.82765) (xy 96.368632 -113.78529)
			(xy 96.29962 -113.736147) (xy 96.235592 -113.680666) (xy 96.177127 -113.619351) (xy 96.124756 -113.552755)
			(xy 96.078953 -113.481483) (xy 96.040131 -113.40618) (xy 96.008643 -113.327528) (xy 95.984775 -113.246238)
			(xy 95.968741 -113.163048) (xy 95.960688 -113.078711) (xy 57.739284 -113.078711) (xy 57.731231 -113.163048)
			(xy 57.715197 -113.246238) (xy 57.691329 -113.327528) (xy 57.659841 -113.40618) (xy 57.621019 -113.481483)
			(xy 57.575216 -113.552755) (xy 57.522845 -113.619351) (xy 57.46438 -113.680666) (xy 57.400352 -113.736147)
			(xy 57.33134 -113.78529) (xy 57.25797 -113.82765) (xy 57.180905 -113.862845) (xy 57.100843 -113.890554)
			(xy 57.01851 -113.910528) (xy 56.934651 -113.922585) (xy 56.850026 -113.926617) (xy 56.765401 -113.922585)
			(xy 56.681542 -113.910528) (xy 56.599209 -113.890554) (xy 56.519147 -113.862845) (xy 56.442082 -113.82765)
			(xy 56.368712 -113.78529) (xy 56.2997 -113.736147) (xy 56.235672 -113.680666) (xy 56.177207 -113.619351)
			(xy 56.124836 -113.552755) (xy 56.079033 -113.481483) (xy 56.040211 -113.40618) (xy 56.008723 -113.327528)
			(xy 55.984855 -113.246238) (xy 55.968821 -113.163048) (xy 55.960768 -113.078711) (xy 36.01974 -113.078711)
			(xy 36.01974 -114.856711) (xy 108.843568 -114.856711) (xy 108.843568 -114.771989) (xy 108.851621 -114.687652)
			(xy 108.867655 -114.604462) (xy 108.891523 -114.523172) (xy 108.923011 -114.44452) (xy 108.961833 -114.369217)
			(xy 109.007636 -114.297945) (xy 109.060007 -114.231349) (xy 109.118472 -114.170034) (xy 109.1825 -114.114553)
			(xy 109.251512 -114.06541) (xy 109.324882 -114.02305) (xy 109.401947 -113.987855) (xy 109.482009 -113.960146)
			(xy 109.564342 -113.940172) (xy 109.648201 -113.928115) (xy 109.732826 -113.924084) (xy 109.817451 -113.928115)
			(xy 109.90131 -113.940172) (xy 109.983643 -113.960146) (xy 110.063705 -113.987855) (xy 110.14077 -114.02305)
			(xy 110.21414 -114.06541) (xy 110.283152 -114.114553) (xy 110.34718 -114.170034) (xy 110.405645 -114.231349)
			(xy 110.458016 -114.297945) (xy 110.503819 -114.369217) (xy 110.542641 -114.44452) (xy 110.574129 -114.523172)
			(xy 110.597997 -114.604462) (xy 110.614031 -114.687652) (xy 110.622084 -114.771989) (xy 110.622588 -114.81435)
			(xy 110.622084 -114.856711) (xy 110.614031 -114.941048) (xy 110.597997 -115.024238) (xy 110.574129 -115.105528)
			(xy 110.542641 -115.18418) (xy 110.503819 -115.259483) (xy 110.458016 -115.330755) (xy 110.405645 -115.397351)
			(xy 110.34718 -115.458666) (xy 110.283152 -115.514147) (xy 110.21414 -115.56329) (xy 110.14077 -115.60565)
			(xy 110.063705 -115.640845) (xy 109.983643 -115.668554) (xy 109.90131 -115.688528) (xy 109.817451 -115.700585)
			(xy 109.732826 -115.704617) (xy 109.648201 -115.700585) (xy 109.564342 -115.688528) (xy 109.482009 -115.668554)
			(xy 109.401947 -115.640845) (xy 109.324882 -115.60565) (xy 109.251512 -115.56329) (xy 109.1825 -115.514147)
			(xy 109.118472 -115.458666) (xy 109.060007 -115.397351) (xy 109.007636 -115.330755) (xy 108.961833 -115.259483)
			(xy 108.923011 -115.18418) (xy 108.891523 -115.105528) (xy 108.867655 -115.024238) (xy 108.851621 -114.941048)
			(xy 108.843568 -114.856711) (xy 36.01974 -114.856711) (xy 36.01974 -117.625114) (xy 36.020167 -117.635182)
			(xy 36.027889 -117.653779) (xy 36.034726 -117.661182) (xy 36.768532 -118.394988) (xy 36.775932 -118.401831)
			(xy 36.79453 -118.409555) (xy 36.8046 -118.409974) (xy 222.159322 -118.409974) (xy 222.192582 -118.410497)
			(xy 222.258531 -118.419186) (xy 222.322781 -118.436413) (xy 222.384231 -118.461883) (xy 222.441828 -118.495159)
			(xy 222.494587 -118.535672) (xy 222.518478 -118.558818) (xy 223.615758 -119.656098) (xy 223.638917 -119.679977)
			(xy 223.679428 -119.73274) (xy 223.712703 -119.79034) (xy 223.738173 -119.851792) (xy 223.755401 -119.916043)
			(xy 223.764092 -119.981994) (xy 223.764602 -120.015254) (xy 223.764602 -137.795) (xy 234.745787 -137.795)
			(xy 234.749742 -137.596168) (xy 234.761597 -137.397649) (xy 234.781336 -137.19976) (xy 234.808927 -137.002811)
			(xy 234.844325 -136.807115) (xy 234.887476 -136.612981) (xy 234.938311 -136.420716) (xy 234.99675 -136.230624)
			(xy 235.0627 -136.043006) (xy 235.136056 -135.858158) (xy 235.216704 -135.676373) (xy 235.304515 -135.497937)
			(xy 235.39935 -135.323134) (xy 235.501061 -135.152239) (xy 235.609484 -134.985523) (xy 235.724451 -134.823249)
			(xy 235.845778 -134.665675) (xy 235.973273 -134.513048) (xy 236.106736 -134.365611) (xy 236.245954 -134.223596)
			(xy 236.390709 -134.087229) (xy 236.540771 -133.956724) (xy 236.695902 -133.832288) (xy 236.855858 -133.714119)
			(xy 237.020385 -133.602402) (xy 237.189224 -133.497314) (xy 237.362108 -133.399022) (xy 237.538762 -133.307681)
			(xy 237.718908 -133.223435) (xy 237.902261 -133.146418) (xy 238.088531 -133.076751) (xy 238.277424 -133.014545)
			(xy 238.46864 -132.959897) (xy 238.661878 -132.912895) (xy 238.856831 -132.873613) (xy 239.053192 -132.842112)
			(xy 239.25065 -132.818443) (xy 239.448894 -132.802642) (xy 239.647608 -132.794736) (xy 239.747044 -132.794248)
			(xy 261.747 -132.794248) (xy 261.846436 -132.794742) (xy 262.04515 -132.802649) (xy 262.243393 -132.818449)
			(xy 262.440851 -132.842118) (xy 262.637211 -132.873619) (xy 262.832165 -132.912902) (xy 263.025402 -132.959904)
			(xy 263.216618 -133.014551) (xy 263.40551 -133.076758) (xy 263.591779 -133.146424) (xy 263.775132 -133.223442)
			(xy 263.955278 -133.307687) (xy 264.131932 -133.399028) (xy 264.304815 -133.49732) (xy 264.473653 -133.602408)
			(xy 264.638181 -133.714125) (xy 264.798136 -133.832295) (xy 264.953267 -133.95673) (xy 265.103329 -134.087235)
			(xy 265.248083 -134.223602) (xy 265.387301 -134.365616) (xy 265.520764 -134.513053) (xy 265.648259 -134.66568)
			(xy 265.769585 -134.823254) (xy 265.884551 -134.985528) (xy 265.992975 -135.152243) (xy 266.094685 -135.323138)
			(xy 266.18952 -135.497941) (xy 266.277331 -135.676376) (xy 266.357979 -135.858161) (xy 266.431335 -136.043009)
			(xy 266.497285 -136.230627) (xy 266.555723 -136.420719) (xy 266.606558 -136.612983) (xy 266.649709 -136.807117)
			(xy 266.685107 -137.002812) (xy 266.712698 -137.199761) (xy 266.732437 -137.39765) (xy 266.744293 -137.596168)
			(xy 266.748247 -137.795) (xy 266.744293 -137.993832) (xy 266.732437 -138.19235) (xy 266.712698 -138.390239)
			(xy 266.685107 -138.587188) (xy 266.649709 -138.782883) (xy 266.606558 -138.977017) (xy 266.555723 -139.169281)
			(xy 266.497285 -139.359373) (xy 266.431335 -139.546991) (xy 266.357979 -139.731839) (xy 266.277331 -139.913624)
			(xy 266.18952 -140.092059) (xy 266.094685 -140.266862) (xy 265.992975 -140.437757) (xy 265.884551 -140.604472)
			(xy 265.769585 -140.766746) (xy 265.648259 -140.92432) (xy 265.520764 -141.076947) (xy 265.387301 -141.224384)
			(xy 265.248083 -141.366398) (xy 265.103329 -141.502765) (xy 264.953267 -141.63327) (xy 264.798136 -141.757705)
			(xy 264.638181 -141.875875) (xy 264.473653 -141.987592) (xy 264.304815 -142.09268) (xy 264.131932 -142.190972)
			(xy 263.955278 -142.282313) (xy 263.775132 -142.366558) (xy 263.591779 -142.443576) (xy 263.40551 -142.513242)
			(xy 263.216618 -142.575449) (xy 263.025402 -142.630096) (xy 262.832165 -142.677098) (xy 262.637211 -142.716381)
			(xy 262.440851 -142.747882) (xy 262.243393 -142.771551) (xy 262.04515 -142.787351) (xy 261.846436 -142.795258)
			(xy 261.747 -142.795752) (xy 239.747044 -142.795752) (xy 239.647608 -142.795264) (xy 239.448894 -142.787358)
			(xy 239.25065 -142.771557) (xy 239.053192 -142.747888) (xy 238.856831 -142.716387) (xy 238.661878 -142.677105)
			(xy 238.46864 -142.630103) (xy 238.277424 -142.575455) (xy 238.088531 -142.513249) (xy 237.902261 -142.443582)
			(xy 237.718908 -142.366565) (xy 237.538762 -142.282319) (xy 237.362108 -142.190978) (xy 237.189224 -142.092686)
			(xy 237.020385 -141.987598) (xy 236.855858 -141.875881) (xy 236.695902 -141.757712) (xy 236.540771 -141.633276)
			(xy 236.390709 -141.502771) (xy 236.245954 -141.366404) (xy 236.106736 -141.224389) (xy 235.973273 -141.076952)
			(xy 235.845778 -140.924325) (xy 235.724451 -140.766751) (xy 235.609484 -140.604477) (xy 235.501061 -140.437761)
			(xy 235.39935 -140.266866) (xy 235.304515 -140.092063) (xy 235.216704 -139.913627) (xy 235.136056 -139.731842)
			(xy 235.0627 -139.546994) (xy 234.99675 -139.359376) (xy 234.938311 -139.169284) (xy 234.887476 -138.977019)
			(xy 234.844325 -138.782885) (xy 234.808927 -138.587189) (xy 234.781336 -138.39024) (xy 234.761597 -138.192351)
			(xy 234.749742 -137.993832) (xy 234.745787 -137.795) (xy 223.764602 -137.795) (xy 223.764602 -139.67587)
			(xy 223.765001 -139.685857) (xy 223.772629 -139.704316) (xy 223.786766 -139.718425) (xy 223.795844 -139.722606)
			(xy 223.859244 -139.749731) (xy 223.983087 -139.810416) (xy 224.103157 -139.878262) (xy 224.219041 -139.953035)
			(xy 224.330339 -140.034476) (xy 224.436668 -140.122306) (xy 224.537663 -140.216221) (xy 224.632974 -140.315899)
			(xy 224.722274 -140.420996) (xy 224.805256 -140.531151) (xy 224.881633 -140.645983) (xy 224.951142 -140.765098)
			(xy 225.013545 -140.888085) (xy 225.068626 -141.014521) (xy 225.116196 -141.14397) (xy 225.15609 -141.275987)
			(xy 225.188172 -141.410116) (xy 225.21233 -141.545897) (xy 225.228482 -141.682861) (xy 225.236573 -141.820536)
			(xy 225.236573 -141.958449) (xy 225.228484 -142.096124) (xy 225.212333 -142.233088) (xy 225.188175 -142.368868)
			(xy 225.156094 -142.502998) (xy 225.116201 -142.635015) (xy 225.068632 -142.764464) (xy 225.013552 -142.890901)
			(xy 224.95115 -143.013888) (xy 224.881641 -143.133004) (xy 224.805264 -143.247837) (xy 224.722284 -143.357992)
			(xy 224.632984 -143.463089) (xy 224.537674 -143.562768) (xy 224.43668 -143.656684) (xy 224.330351 -143.744515)
			(xy 224.219054 -143.825956) (xy 224.10317 -143.90073) (xy 223.983101 -143.968576) (xy 223.859258 -144.029263)
			(xy 223.795844 -144.056354) (xy 223.786857 -144.060656) (xy 223.772817 -144.074765) (xy 223.765166 -144.093141)
			(xy 223.764602 -144.10309) (xy 223.764602 -144.991582) (xy 223.76504 -145.001645) (xy 223.772776 -145.020228)
			(xy 223.779588 -145.02765) (xy 224.720912 -145.968974) (xy 224.72831 -145.975821) (xy 224.746908 -145.983556)
			(xy 224.75698 -145.98396)
		)
		(stroke
			(width 0)
			(type solid)
		)
		(fill yes)
		(layer "In5.Cu")
		(net "P52V_HS")
	)
	(gr_poly
		(pts
			(xy 78.2447 -74.324972) (xy 78.25477 -74.324548) (xy 78.273371 -74.316831) (xy 78.280768 -74.309986)
			(xy 84.49691 -68.093844) (xy 84.520789 -68.070686) (xy 84.573552 -68.030176) (xy 84.631152 -67.996902)
			(xy 84.692604 -67.971434) (xy 84.756855 -67.954207) (xy 84.822806 -67.945517) (xy 84.856066 -67.945)
			(xy 89.45245 -67.945) (xy 89.462325 -67.944534) (xy 89.480615 -67.937083) (xy 89.48801 -67.930522)
			(xy 89.53881 -67.880738) (xy 89.545512 -67.873534) (xy 89.553338 -67.855501) (xy 89.55405 -67.845686)
			(xy 89.55405 -67.845432) (xy 89.555483 -67.79516) (xy 89.565185 -67.695049) (xy 89.582619 -67.595991)
			(xy 89.607677 -67.498583) (xy 89.64021 -67.40341) (xy 89.680022 -67.311044) (xy 89.726874 -67.222042)
			(xy 89.780483 -67.13694) (xy 89.840526 -67.056249) (xy 89.906644 -66.980454) (xy 89.978437 -66.910012)
			(xy 90.055474 -66.845346) (xy 90.137292 -66.786846) (xy 90.223398 -66.734864) (xy 90.313273 -66.689712)
			(xy 90.406378 -66.651662) (xy 90.502153 -66.620943) (xy 90.60002 -66.59774) (xy 90.699391 -66.582192)
			(xy 90.799668 -66.574392) (xy 90.849958 -66.573908) (xy 90.850466 -66.573908) (xy 90.902115 -66.574422)
			(xy 91.005082 -66.582666) (xy 91.107067 -66.59908) (xy 91.207422 -66.623561) (xy 91.305509 -66.655952)
			(xy 91.400707 -66.696049) (xy 91.49241 -66.743597) (xy 91.580038 -66.798294) (xy 91.663034 -66.859792)
			(xy 91.74087 -66.927702) (xy 91.777312 -66.964306) (xy 91.78476 -66.971367) (xy 91.803635 -66.97938)
			(xy 91.813888 -66.9798) (xy 91.886024 -66.9798) (xy 91.89627 -66.979336) (xy 91.915142 -66.971346)
			(xy 91.9226 -66.964306) (xy 91.959056 -66.927697) (xy 92.036906 -66.85976) (xy 92.119919 -66.798239)
			(xy 92.207569 -66.743525) (xy 92.299297 -66.695966) (xy 92.394523 -66.655864) (xy 92.49264 -66.623474)
			(xy 92.593025 -66.599002) (xy 92.69504 -66.582603) (xy 92.798037 -66.574382) (xy 92.8497 -66.573908)
			(xy 92.850208 -66.573908) (xy 92.901869 -66.574412) (xy 93.004864 -66.582639) (xy 93.106877 -66.599042)
			(xy 93.20726 -66.623514) (xy 93.305375 -66.655902) (xy 93.4006 -66.695999) (xy 93.49233 -66.743551)
			(xy 93.579983 -66.798256) (xy 93.663002 -66.859766) (xy 93.740859 -66.927692) (xy 93.777308 -66.964306)
			(xy 93.784756 -66.971368) (xy 93.80363 -66.979382) (xy 93.813884 -66.9798) (xy 93.88602 -66.9798)
			(xy 93.896267 -66.979337) (xy 93.915139 -66.971348) (xy 93.922596 -66.964306) (xy 93.959052 -66.927697)
			(xy 94.036902 -66.859759) (xy 94.119915 -66.798238) (xy 94.207564 -66.743524) (xy 94.299293 -66.695965)
			(xy 94.394519 -66.655863) (xy 94.492636 -66.623473) (xy 94.593021 -66.599) (xy 94.695036 -66.582601)
			(xy 94.798033 -66.574379) (xy 94.849696 -66.573908) (xy 94.850204 -66.573908) (xy 94.901865 -66.574412)
			(xy 95.00486 -66.582639) (xy 95.106873 -66.599041) (xy 95.207256 -66.623513) (xy 95.305372 -66.655901)
			(xy 95.400597 -66.695998) (xy 95.492328 -66.74355) (xy 95.57998 -66.798254) (xy 95.662999 -66.859765)
			(xy 95.740857 -66.92769) (xy 95.777304 -66.964306) (xy 95.784757 -66.971353) (xy 95.803632 -66.979332)
			(xy 95.81388 -66.9798) (xy 95.886016 -66.9798) (xy 95.896263 -66.979338) (xy 95.915136 -66.97135)
			(xy 95.922592 -66.964306) (xy 95.959048 -66.927697) (xy 96.036897 -66.859759) (xy 96.119911 -66.798237)
			(xy 96.20756 -66.743523) (xy 96.299289 -66.695964) (xy 96.394514 -66.655861) (xy 96.492631 -66.623471)
			(xy 96.593017 -66.598998) (xy 96.695032 -66.582598) (xy 96.798029 -66.574376) (xy 96.849692 -66.573908)
			(xy 96.8502 -66.573908) (xy 96.901862 -66.574412) (xy 97.004857 -66.582639) (xy 97.10687 -66.59904)
			(xy 97.207253 -66.623512) (xy 97.305369 -66.6559) (xy 97.400594 -66.695996) (xy 97.492325 -66.743548)
			(xy 97.579978 -66.798253) (xy 97.662997 -66.859763) (xy 97.740855 -66.927688) (xy 97.7773 -66.964306)
			(xy 97.784753 -66.971353) (xy 97.803628 -66.979334) (xy 97.813876 -66.9798) (xy 97.886012 -66.9798)
			(xy 97.896259 -66.979339) (xy 97.915134 -66.971352) (xy 97.922588 -66.964306) (xy 97.959044 -66.927697)
			(xy 98.036893 -66.859759) (xy 98.119906 -66.798237) (xy 98.207556 -66.743522) (xy 98.299285 -66.695962)
			(xy 98.39451 -66.65586) (xy 98.492627 -66.623469) (xy 98.593012 -66.598996) (xy 98.695028 -66.582596)
			(xy 98.798025 -66.574373) (xy 98.849688 -66.573908) (xy 98.850196 -66.573908) (xy 98.901858 -66.574411)
			(xy 99.004853 -66.582638) (xy 99.106866 -66.599039) (xy 99.207249 -66.623511) (xy 99.305365 -66.655898)
			(xy 99.400591 -66.695995) (xy 99.492322 -66.743546) (xy 99.579975 -66.798251) (xy 99.662995 -66.859761)
			(xy 99.740853 -66.927686) (xy 99.777296 -66.964306) (xy 99.784749 -66.971354) (xy 99.803624 -66.979336)
			(xy 99.813872 -66.9798) (xy 99.886008 -66.9798) (xy 99.896256 -66.979339) (xy 99.915131 -66.971353)
			(xy 99.922584 -66.964306) (xy 99.95904 -66.927697) (xy 100.036889 -66.859758) (xy 100.119902 -66.798236)
			(xy 100.207552 -66.743521) (xy 100.299281 -66.695961) (xy 100.394506 -66.655858) (xy 100.492623 -66.623467)
			(xy 100.593008 -66.598994) (xy 100.695024 -66.582594) (xy 100.798021 -66.574371) (xy 100.849684 -66.573908)
			(xy 100.850192 -66.573908) (xy 100.901852 -66.574415) (xy 101.004844 -66.582649) (xy 101.106853 -66.599057)
			(xy 101.207232 -66.623535) (xy 101.305343 -66.655928) (xy 101.400564 -66.696029) (xy 101.492289 -66.743585)
			(xy 101.579937 -66.798293) (xy 101.66295 -66.859806) (xy 101.740803 -66.927733) (xy 101.777292 -66.964306)
			(xy 101.784744 -66.971355) (xy 101.803619 -66.979338) (xy 101.813868 -66.9798) (xy 101.886004 -66.9798)
			(xy 101.896252 -66.97934) (xy 101.915129 -66.971355) (xy 101.92258 -66.964306) (xy 101.959027 -66.927705)
			(xy 102.036855 -66.859782) (xy 102.119846 -66.798271) (xy 102.20747 -66.743564) (xy 102.299173 -66.696009)
			(xy 102.394371 -66.655906) (xy 102.49246 -66.623511) (xy 102.592817 -66.59903) (xy 102.694805 -66.582617)
			(xy 102.797776 -66.574378) (xy 102.849426 -66.573908) (xy 102.849934 -66.573908) (xy 102.900829 -66.574409)
			(xy 103.002306 -66.582398) (xy 103.102843 -66.598324) (xy 103.20182 -66.622088) (xy 103.298628 -66.653545)
			(xy 103.39267 -66.692501) (xy 103.483365 -66.738714) (xy 103.570154 -66.791901) (xy 103.652504 -66.851734)
			(xy 103.729905 -66.917842) (xy 103.801881 -66.98982) (xy 103.867988 -67.067223) (xy 103.927818 -67.149574)
			(xy 103.981002 -67.236365) (xy 104.027213 -67.327061) (xy 104.066166 -67.421104) (xy 104.097621 -67.517913)
			(xy 104.121383 -67.616891) (xy 104.137306 -67.717428) (xy 104.145293 -67.818905) (xy 104.145293 -67.920695)
			(xy 104.137306 -68.022172) (xy 104.121383 -68.122709) (xy 104.097621 -68.221687) (xy 104.066166 -68.318496)
			(xy 104.027213 -68.412539) (xy 103.981002 -68.503235) (xy 103.927818 -68.590026) (xy 103.867988 -68.672377)
			(xy 103.801881 -68.74978) (xy 103.729905 -68.821758) (xy 103.652504 -68.887866) (xy 103.570154 -68.947699)
			(xy 103.483365 -69.000886) (xy 103.39267 -69.047099) (xy 103.298628 -69.086055) (xy 103.20182 -69.117512)
			(xy 103.102843 -69.141276) (xy 103.002306 -69.157202) (xy 102.900829 -69.165191) (xy 102.849934 -69.165724)
			(xy 102.849426 -69.165724) (xy 102.797777 -69.16521) (xy 102.69481 -69.156966) (xy 102.592825 -69.140551)
			(xy 102.49247 -69.11607) (xy 102.394383 -69.083679) (xy 102.299185 -69.043582) (xy 102.207481 -68.996035)
			(xy 102.119853 -68.941339) (xy 102.036857 -68.879841) (xy 101.959019 -68.811932) (xy 101.92258 -68.775326)
			(xy 101.915133 -68.768262) (xy 101.896258 -68.760247) (xy 101.886004 -68.759832) (xy 101.813868 -68.759832)
			(xy 101.803621 -68.760295) (xy 101.784745 -68.768279) (xy 101.777292 -68.775326) (xy 101.740835 -68.811934)
			(xy 101.662985 -68.879869) (xy 101.579971 -68.941388) (xy 101.492321 -68.9961) (xy 101.400592 -69.043657)
			(xy 101.305367 -69.083757) (xy 101.20725 -69.116146) (xy 101.106866 -69.140617) (xy 101.004851 -69.157015)
			(xy 100.901854 -69.165235) (xy 100.850192 -69.165724) (xy 100.849684 -69.165724) (xy 100.798023 -69.16522)
			(xy 100.695028 -69.156992) (xy 100.593015 -69.140589) (xy 100.492632 -69.116117) (xy 100.394517 -69.083729)
			(xy 100.299292 -69.043632) (xy 100.207561 -68.996081) (xy 100.119908 -68.941377) (xy 100.036889 -68.879867)
			(xy 99.959031 -68.811943) (xy 99.922584 -68.775326) (xy 99.915137 -68.768262) (xy 99.896262 -68.760245)
			(xy 99.886008 -68.759832) (xy 99.813872 -68.759832) (xy 99.803624 -68.760294) (xy 99.784747 -68.768278)
			(xy 99.777296 -68.775326) (xy 99.740839 -68.811934) (xy 99.662989 -68.87987) (xy 99.579975 -68.941389)
			(xy 99.492325 -68.996101) (xy 99.400596 -69.043658) (xy 99.305371 -69.083759) (xy 99.207254 -69.116148)
			(xy 99.10687 -69.140619) (xy 99.004855 -69.157017) (xy 98.901858 -69.165238) (xy 98.850196 -69.165724)
			(xy 98.849688 -69.165724) (xy 98.798027 -69.16522) (xy 98.695032 -69.156992) (xy 98.593019 -69.14059)
			(xy 98.492636 -69.116118) (xy 98.39452 -69.08373) (xy 98.299295 -69.043634) (xy 98.207564 -68.996082)
			(xy 98.119911 -68.941378) (xy 98.036891 -68.879869) (xy 97.959033 -68.811945) (xy 97.922588 -68.775326)
			(xy 97.915142 -68.768261) (xy 97.896267 -68.760243) (xy 97.886012 -68.759832) (xy 97.813876 -68.759832)
			(xy 97.803628 -68.760293) (xy 97.78475 -68.768276) (xy 97.7773 -68.775326) (xy 97.740843 -68.811934)
			(xy 97.662993 -68.87987) (xy 97.579979 -68.94139) (xy 97.49233 -68.996102) (xy 97.400601 -69.04366)
			(xy 97.305375 -69.08376) (xy 97.207259 -69.116149) (xy 97.106874 -69.140621) (xy 97.004859 -69.157019)
			(xy 96.901862 -69.165241) (xy 96.8502 -69.165724) (xy 96.849692 -69.165724) (xy 96.79803 -69.16522)
			(xy 96.695035 -69.156993) (xy 96.593022 -69.140591) (xy 96.492639 -69.116119) (xy 96.394523 -69.083732)
			(xy 96.299298 -69.043635) (xy 96.207567 -68.996084) (xy 96.119913 -68.94138) (xy 96.036894 -68.879871)
			(xy 95.959035 -68.811946) (xy 95.922592 -68.775326) (xy 95.915146 -68.76826) (xy 95.896271 -68.760241)
			(xy 95.886016 -68.759832) (xy 95.81388 -68.759832) (xy 95.803632 -68.760293) (xy 95.784753 -68.768274)
			(xy 95.777304 -68.775326) (xy 95.740847 -68.811934) (xy 95.662997 -68.87987) (xy 95.579984 -68.94139)
			(xy 95.492334 -68.996103) (xy 95.400605 -69.043661) (xy 95.30538 -69.083762) (xy 95.207263 -69.116151)
			(xy 95.106878 -69.140623) (xy 95.004863 -69.157022) (xy 94.901866 -69.165244) (xy 94.850204 -69.165724)
			(xy 94.849696 -69.165724) (xy 94.798034 -69.16522) (xy 94.695039 -69.156993) (xy 94.593026 -69.140592)
			(xy 94.492643 -69.11612) (xy 94.394527 -69.083733) (xy 94.299301 -69.043637) (xy 94.20757 -68.996086)
			(xy 94.119916 -68.941382) (xy 94.036896 -68.879873) (xy 93.959037 -68.811948) (xy 93.922596 -68.775326)
			(xy 93.915144 -68.768276) (xy 93.896269 -68.760292) (xy 93.88602 -68.759832) (xy 93.813884 -68.759832)
			(xy 93.803635 -68.760292) (xy 93.784755 -68.768272) (xy 93.777308 -68.775326) (xy 93.740852 -68.811934)
			(xy 93.663001 -68.879871) (xy 93.579988 -68.941391) (xy 93.492338 -68.996104) (xy 93.400609 -69.043662)
			(xy 93.305384 -69.083763) (xy 93.207267 -69.116153) (xy 93.106882 -69.140625) (xy 93.004867 -69.157024)
			(xy 92.90187 -69.165246) (xy 92.850208 -69.165724) (xy 92.8497 -69.165724) (xy 92.798038 -69.16522)
			(xy 92.695043 -69.156994) (xy 92.59303 -69.140592) (xy 92.492646 -69.116121) (xy 92.39453 -69.083734)
			(xy 92.299304 -69.043638) (xy 92.207572 -68.996087) (xy 92.119918 -68.941384) (xy 92.036898 -68.879874)
			(xy 91.959039 -68.81195) (xy 91.9226 -68.775326) (xy 91.915149 -68.768275) (xy 91.896273 -68.760289)
			(xy 91.886024 -68.759832) (xy 91.813888 -68.759832) (xy 91.803639 -68.760291) (xy 91.784758 -68.768271)
			(xy 91.777312 -68.775326) (xy 91.739221 -68.813527) (xy 91.657675 -68.884167) (xy 91.570536 -68.94778)
			(xy 91.478409 -69.003925) (xy 91.38193 -69.052213) (xy 91.33205 -69.07276) (xy 91.320112 -69.077586)
			(xy 91.303856 -69.097144) (xy 91.284298 -69.192902) (xy 91.282418 -69.205366) (xy 91.289594 -69.229498)
			(xy 91.298014 -69.238876) (xy 96.369124 -74.309986) (xy 96.376523 -74.31683) (xy 96.395121 -74.324558)
			(xy 96.405192 -74.324972) (xy 118.244874 -74.324972) (xy 118.254938 -74.324535) (xy 118.27352 -74.316798)
			(xy 118.280942 -74.309986) (xy 124.497084 -68.093844) (xy 124.520965 -68.07069) (xy 124.573729 -68.030188)
			(xy 124.631331 -67.996922) (xy 124.692783 -67.971463) (xy 124.757033 -67.954245) (xy 124.822981 -67.945565)
			(xy 124.85624 -67.945) (xy 129.452624 -67.945) (xy 129.462501 -67.944539) (xy 129.480798 -67.937094)
			(xy 129.488184 -67.930522) (xy 129.538984 -67.880738) (xy 129.545689 -67.873535) (xy 129.553519 -67.855502)
			(xy 129.554224 -67.845686) (xy 129.554224 -67.845432) (xy 129.555657 -67.79516) (xy 129.565359 -67.695048)
			(xy 129.582792 -67.595989) (xy 129.607851 -67.49858) (xy 129.640384 -67.403406) (xy 129.680196 -67.31104)
			(xy 129.727047 -67.222037) (xy 129.780655 -67.136934) (xy 129.840699 -67.056241) (xy 129.906816 -66.980445)
			(xy 129.978609 -66.910002) (xy 130.055646 -66.845335) (xy 130.137464 -66.786834) (xy 130.223569 -66.73485)
			(xy 130.313445 -66.689696) (xy 130.40655 -66.651644) (xy 130.502325 -66.620924) (xy 130.600192 -66.597718)
			(xy 130.699564 -66.582169) (xy 130.799842 -66.574367) (xy 130.850132 -66.573908) (xy 130.85064 -66.573908)
			(xy 130.902287 -66.574425) (xy 131.005253 -66.582674) (xy 131.107234 -66.599094) (xy 131.207585 -66.623579)
			(xy 131.305669 -66.655975) (xy 131.400863 -66.696075) (xy 131.492562 -66.743626) (xy 131.580185 -66.798326)
			(xy 131.663177 -66.859827) (xy 131.741009 -66.927739) (xy 131.777486 -66.964306) (xy 131.784938 -66.971356)
			(xy 131.803813 -66.979341) (xy 131.814062 -66.9798) (xy 131.886198 -66.9798) (xy 131.896446 -66.979341)
			(xy 131.915325 -66.971358) (xy 131.922774 -66.964306) (xy 131.95923 -66.927696) (xy 132.037079 -66.859757)
			(xy 132.120092 -66.798235) (xy 132.207741 -66.743519) (xy 132.29947 -66.695958) (xy 132.394695 -66.655855)
			(xy 132.492812 -66.623463) (xy 132.593198 -66.598989) (xy 132.695213 -66.582588) (xy 132.798211 -66.574364)
			(xy 132.849874 -66.573908) (xy 132.850382 -66.573908) (xy 132.902042 -66.574415) (xy 133.005034 -66.582648)
			(xy 133.107044 -66.599055) (xy 133.207423 -66.623533) (xy 133.305535 -66.655924) (xy 133.400756 -66.696025)
			(xy 133.492482 -66.743581) (xy 133.58013 -66.798288) (xy 133.663144 -66.859801) (xy 133.740997 -66.927728)
			(xy 133.777482 -66.964306) (xy 133.784934 -66.971356) (xy 133.803809 -66.979343) (xy 133.814058 -66.9798)
			(xy 133.886194 -66.9798) (xy 133.896434 -66.979323) (xy 133.915287 -66.971315) (xy 133.92277 -66.964306)
			(xy 133.959226 -66.927696) (xy 134.037075 -66.859757) (xy 134.120088 -66.798234) (xy 134.207737 -66.743518)
			(xy 134.299466 -66.695957) (xy 134.394691 -66.655853) (xy 134.492808 -66.623461) (xy 134.593193 -66.598987)
			(xy 134.695209 -66.582585) (xy 134.798207 -66.574361) (xy 134.84987 -66.573908) (xy 134.850378 -66.573908)
			(xy 134.902038 -66.574415) (xy 135.005031 -66.582647) (xy 135.10704 -66.599054) (xy 135.20742 -66.623532)
			(xy 135.305532 -66.655923) (xy 135.400753 -66.696024) (xy 135.492479 -66.743579) (xy 135.580128 -66.798287)
			(xy 135.663142 -66.859799) (xy 135.740995 -66.927726) (xy 135.777478 -66.964306) (xy 135.78493 -66.971357)
			(xy 135.803805 -66.979345) (xy 135.814054 -66.9798) (xy 135.88619 -66.9798) (xy 135.896431 -66.979324)
			(xy 135.915284 -66.971317) (xy 135.922766 -66.964306) (xy 135.959223 -66.927699) (xy 136.037074 -66.859766)
			(xy 136.120088 -66.798249) (xy 136.207738 -66.74354) (xy 136.299467 -66.695985) (xy 136.394693 -66.655888)
			(xy 136.49281 -66.623504) (xy 136.593194 -66.599036) (xy 136.695208 -66.582643) (xy 136.798204 -66.574426)
			(xy 136.849866 -66.573908) (xy 136.850374 -66.573908) (xy 136.902034 -66.574414) (xy 137.005027 -66.582647)
			(xy 137.107037 -66.599054) (xy 137.207416 -66.623531) (xy 137.305528 -66.655922) (xy 137.40075 -66.696023)
			(xy 137.492476 -66.743578) (xy 137.580125 -66.798285) (xy 137.66314 -66.859797) (xy 137.740993 -66.927724)
			(xy 137.777474 -66.964306) (xy 137.784926 -66.971357) (xy 137.8038 -66.979347) (xy 137.81405 -66.9798)
			(xy 137.886186 -66.9798) (xy 137.896427 -66.979325) (xy 137.915281 -66.971319) (xy 137.922762 -66.964306)
			(xy 137.959219 -66.927699) (xy 138.037069 -66.859765) (xy 138.120084 -66.798248) (xy 138.207734 -66.743539)
			(xy 138.299463 -66.695984) (xy 138.394689 -66.655887) (xy 138.492805 -66.623502) (xy 138.59319 -66.599034)
			(xy 138.695204 -66.58264) (xy 138.7982 -66.574423) (xy 138.849862 -66.573908) (xy 138.85037 -66.573908)
			(xy 138.90203 -66.574414) (xy 139.005023 -66.582646) (xy 139.107033 -66.599053) (xy 139.207413 -66.62353)
			(xy 139.305525 -66.655921) (xy 139.400747 -66.696021) (xy 139.492474 -66.743576) (xy 139.580123 -66.798283)
			(xy 139.663138 -66.859795) (xy 139.740991 -66.927722) (xy 139.77747 -66.964306) (xy 139.784921 -66.971358)
			(xy 139.803796 -66.97935) (xy 139.814046 -66.9798) (xy 139.886182 -66.9798) (xy 139.896423 -66.979326)
			(xy 139.915279 -66.971321) (xy 139.922758 -66.964306) (xy 139.959215 -66.927699) (xy 140.037065 -66.859765)
			(xy 140.120079 -66.798248) (xy 140.20773 -66.743538) (xy 140.299459 -66.695983) (xy 140.394684 -66.655885)
			(xy 140.492801 -66.6235) (xy 140.593186 -66.599032) (xy 140.6952 -66.582638) (xy 140.798196 -66.574421)
			(xy 140.849858 -66.573908) (xy 140.850366 -66.573908) (xy 140.902027 -66.574414) (xy 141.005019 -66.582646)
			(xy 141.107029 -66.599052) (xy 141.207409 -66.623529) (xy 141.305522 -66.65592) (xy 141.400744 -66.69602)
			(xy 141.492471 -66.743574) (xy 141.58012 -66.798281) (xy 141.663135 -66.859794) (xy 141.740989 -66.92772)
			(xy 141.777466 -66.964306) (xy 141.784917 -66.971359) (xy 141.803792 -66.979352) (xy 141.814042 -66.9798)
			(xy 141.886178 -66.9798) (xy 141.89642 -66.979326) (xy 141.915276 -66.971323) (xy 141.922754 -66.964306)
			(xy 141.959201 -66.927707) (xy 142.037032 -66.859788) (xy 142.120023 -66.798283) (xy 142.207648 -66.743581)
			(xy 142.299351 -66.69603) (xy 142.394549 -66.655933) (xy 142.492638 -66.623544) (xy 142.592995 -66.599068)
			(xy 142.694982 -66.582661) (xy 142.797951 -66.574428) (xy 142.8496 -66.573908) (xy 142.850108 -66.573908)
			(xy 142.901004 -66.574408) (xy 143.002482 -66.582395) (xy 143.10302 -66.598319) (xy 143.202 -66.622083)
			(xy 143.298809 -66.653538) (xy 143.392852 -66.692493) (xy 143.483549 -66.738706) (xy 143.570341 -66.791892)
			(xy 143.652692 -66.851724) (xy 143.730095 -66.917833) (xy 143.802072 -66.989811) (xy 143.868181 -67.067214)
			(xy 143.928012 -67.149566) (xy 143.981198 -67.236358) (xy 144.02741 -67.327055) (xy 144.066364 -67.421098)
			(xy 144.09782 -67.517908) (xy 144.121582 -67.616887) (xy 144.137506 -67.717426) (xy 144.145493 -67.818904)
			(xy 144.145493 -67.920696) (xy 144.137506 -68.022174) (xy 144.121582 -68.122713) (xy 144.09782 -68.221692)
			(xy 144.066364 -68.318502) (xy 144.02741 -68.412545) (xy 143.981198 -68.503242) (xy 143.928012 -68.590034)
			(xy 143.868181 -68.672386) (xy 143.802072 -68.749789) (xy 143.730095 -68.821767) (xy 143.652692 -68.887876)
			(xy 143.570341 -68.947708) (xy 143.483549 -69.000894) (xy 143.392852 -69.047107) (xy 143.298809 -69.086062)
			(xy 143.202 -69.117517) (xy 143.10302 -69.141281) (xy 143.002482 -69.157205) (xy 142.901004 -69.165192)
			(xy 142.850108 -69.165724) (xy 142.8496 -69.165724) (xy 142.797952 -69.165209) (xy 142.694985 -69.156963)
			(xy 142.593001 -69.140546) (xy 142.492648 -69.116064) (xy 142.394562 -69.083671) (xy 142.299365 -69.043573)
			(xy 142.207663 -68.996025) (xy 142.120036 -68.941328) (xy 142.037042 -68.879829) (xy 141.959206 -68.811919)
			(xy 141.922754 -68.775326) (xy 141.915306 -68.768266) (xy 141.89643 -68.760261) (xy 141.886178 -68.759832)
			(xy 141.814042 -68.759832) (xy 141.803797 -68.7603) (xy 141.784928 -68.768291) (xy 141.777466 -68.775326)
			(xy 141.741009 -68.811933) (xy 141.663158 -68.879867) (xy 141.580144 -68.941384) (xy 141.492494 -68.996094)
			(xy 141.400765 -69.04365) (xy 141.305539 -69.083748) (xy 141.207423 -69.116134) (xy 141.107038 -69.140603)
			(xy 141.005024 -69.156999) (xy 140.902028 -69.165218) (xy 140.850366 -69.165724) (xy 140.849858 -69.165724)
			(xy 140.798197 -69.165219) (xy 140.695203 -69.156989) (xy 140.593192 -69.140585) (xy 140.49281 -69.11611)
			(xy 140.394696 -69.083721) (xy 140.299472 -69.043623) (xy 140.207743 -68.99607) (xy 140.120091 -68.941365)
			(xy 140.037074 -68.879855) (xy 139.959217 -68.81193) (xy 139.922758 -68.775326) (xy 139.91531 -68.768266)
			(xy 139.896435 -68.760259) (xy 139.886182 -68.759832) (xy 139.814046 -68.759832) (xy 139.803801 -68.760299)
			(xy 139.784931 -68.768289) (xy 139.77747 -68.775326) (xy 139.741013 -68.811933) (xy 139.663162 -68.879867)
			(xy 139.580148 -68.941385) (xy 139.492498 -68.996095) (xy 139.400769 -69.043651) (xy 139.305543 -69.083749)
			(xy 139.207427 -69.116136) (xy 139.107042 -69.140605) (xy 139.005028 -69.157002) (xy 138.902032 -69.165221)
			(xy 138.85037 -69.165724) (xy 138.849862 -69.165724) (xy 138.798201 -69.165219) (xy 138.695207 -69.156989)
			(xy 138.593195 -69.140585) (xy 138.492813 -69.116111) (xy 138.394699 -69.083722) (xy 138.299475 -69.043624)
			(xy 138.207746 -68.996072) (xy 138.120094 -68.941367) (xy 138.037076 -68.879857) (xy 137.959219 -68.811932)
			(xy 137.922762 -68.775326) (xy 137.915314 -68.768265) (xy 137.896439 -68.760257) (xy 137.886186 -68.759832)
			(xy 137.81405 -68.759832) (xy 137.803804 -68.760298) (xy 137.784933 -68.768287) (xy 137.777474 -68.775326)
			(xy 137.741017 -68.811933) (xy 137.663166 -68.879868) (xy 137.580152 -68.941385) (xy 137.492502 -68.996096)
			(xy 137.400773 -69.043652) (xy 137.305548 -69.083751) (xy 137.207431 -69.116138) (xy 137.107047 -69.140607)
			(xy 137.005032 -69.157004) (xy 136.902036 -69.165223) (xy 136.850374 -69.165724) (xy 136.849866 -69.165724)
			(xy 136.798205 -69.165219) (xy 136.695211 -69.15699) (xy 136.593199 -69.140586) (xy 136.492817 -69.116112)
			(xy 136.394702 -69.083724) (xy 136.299478 -69.043626) (xy 136.207749 -68.996074) (xy 136.120097 -68.941369)
			(xy 136.037078 -68.879859) (xy 135.959221 -68.811934) (xy 135.922766 -68.775326) (xy 135.915318 -68.768265)
			(xy 135.896443 -68.760255) (xy 135.88619 -68.759832) (xy 135.814054 -68.759832) (xy 135.803808 -68.760298)
			(xy 135.784936 -68.768286) (xy 135.777478 -68.775326) (xy 135.741021 -68.811934) (xy 135.663171 -68.879868)
			(xy 135.580156 -68.941386) (xy 135.492506 -68.996097) (xy 135.400777 -69.043653) (xy 135.305552 -69.083752)
			(xy 135.207435 -69.11614) (xy 135.107051 -69.140609) (xy 135.005036 -69.157006) (xy 134.90204 -69.165226)
			(xy 134.850378 -69.165724) (xy 134.84987 -69.165724) (xy 134.798209 -69.165219) (xy 134.695215 -69.15699)
			(xy 134.593203 -69.140587) (xy 134.49282 -69.116113) (xy 134.394706 -69.083725) (xy 134.299481 -69.043627)
			(xy 134.207751 -68.996075) (xy 134.120099 -68.94137) (xy 134.037081 -68.87986) (xy 133.959223 -68.811936)
			(xy 133.92277 -68.775326) (xy 133.915322 -68.768264) (xy 133.896447 -68.760252) (xy 133.886194 -68.759832)
			(xy 133.814058 -68.759832) (xy 133.803812 -68.760297) (xy 133.784938 -68.768284) (xy 133.777482 -68.775326)
			(xy 133.741025 -68.811934) (xy 133.663175 -68.879868) (xy 133.580161 -68.941387) (xy 133.492511 -68.996098)
			(xy 133.400782 -69.043654) (xy 133.305556 -69.083754) (xy 133.20744 -69.116141) (xy 133.107055 -69.140612)
			(xy 133.00504 -69.157009) (xy 132.902044 -69.165229) (xy 132.850382 -69.165724) (xy 132.849874 -69.165724)
			(xy 132.798213 -69.165219) (xy 132.695218 -69.156991) (xy 132.593206 -69.140588) (xy 132.492824 -69.116114)
			(xy 132.394709 -69.083726) (xy 132.299484 -69.043629) (xy 132.207754 -68.996077) (xy 132.120102 -68.941372)
			(xy 132.037083 -68.879862) (xy 131.959226 -68.811938) (xy 131.922774 -68.775326) (xy 131.915327 -68.768263)
			(xy 131.896452 -68.76025) (xy 131.886198 -68.759832) (xy 131.814062 -68.759832) (xy 131.803815 -68.760296)
			(xy 131.784941 -68.768282) (xy 131.777486 -68.775326) (xy 131.739395 -68.813527) (xy 131.657848 -68.884165)
			(xy 131.570708 -68.947776) (xy 131.47858 -69.003919) (xy 131.382101 -69.052205) (xy 131.332224 -69.07276)
			(xy 131.320286 -69.077586) (xy 131.30403 -69.097144) (xy 131.284472 -69.192902) (xy 131.282592 -69.205365)
			(xy 131.289776 -69.229492) (xy 131.298188 -69.238876) (xy 136.369298 -74.309986) (xy 136.376696 -74.316834)
			(xy 136.395294 -74.324571) (xy 136.405366 -74.324972) (xy 158.245048 -74.324972) (xy 158.255114 -74.324539)
			(xy 158.273703 -74.31681) (xy 158.281116 -74.309986) (xy 164.497258 -68.093844) (xy 164.521138 -68.070689)
			(xy 164.573902 -68.030184) (xy 164.631503 -67.996915) (xy 164.692955 -67.971453) (xy 164.757206 -67.954232)
			(xy 164.823155 -67.945548) (xy 164.856414 -67.945) (xy 169.452798 -67.945) (xy 169.462677 -67.944544)
			(xy 169.48098 -67.937105) (xy 169.488358 -67.930522) (xy 169.539158 -67.880738) (xy 169.545866 -67.873537)
			(xy 169.5537 -67.855503) (xy 169.554398 -67.845686) (xy 169.554398 -67.845432) (xy 169.555831 -67.795161)
			(xy 169.565534 -67.695051) (xy 169.582967 -67.595995) (xy 169.608026 -67.498588) (xy 169.640559 -67.403416)
			(xy 169.680372 -67.311052) (xy 169.727223 -67.222052) (xy 169.780833 -67.136952) (xy 169.840877 -67.056262)
			(xy 169.906995 -66.98047) (xy 169.978788 -66.91003) (xy 170.055826 -66.845367) (xy 170.137644 -66.78687)
			(xy 170.223749 -66.73489) (xy 170.313625 -66.689741) (xy 170.40673 -66.651694) (xy 170.502504 -66.620978)
			(xy 170.60037 -66.597779) (xy 170.69974 -66.582234) (xy 170.800017 -66.574439) (xy 170.850306 -66.573908)
			(xy 170.850814 -66.573908) (xy 170.902462 -66.574424) (xy 171.005428 -66.582671) (xy 171.107411 -66.599089)
			(xy 171.207763 -66.623573) (xy 171.305848 -66.655967) (xy 171.401043 -66.696066) (xy 171.492744 -66.743616)
			(xy 171.580369 -66.798314) (xy 171.663361 -66.859815) (xy 171.741195 -66.927726) (xy 171.77766 -66.964306)
			(xy 171.785111 -66.97136) (xy 171.803986 -66.979355) (xy 171.814236 -66.9798) (xy 171.886372 -66.9798)
			(xy 171.896614 -66.979328) (xy 171.915472 -66.971325) (xy 171.922948 -66.964306) (xy 171.959405 -66.927698)
			(xy 172.037255 -66.859764) (xy 172.120269 -66.798246) (xy 172.207919 -66.743536) (xy 172.299648 -66.69598)
			(xy 172.394874 -66.655882) (xy 172.492991 -66.623496) (xy 172.593375 -66.599027) (xy 172.69539 -66.582632)
			(xy 172.798386 -66.574414) (xy 172.850048 -66.573908) (xy 172.850556 -66.573908) (xy 172.902217 -66.574414)
			(xy 173.00521 -66.582645) (xy 173.10722 -66.59905) (xy 173.207601 -66.623526) (xy 173.305714 -66.655917)
			(xy 173.400936 -66.696016) (xy 173.492664 -66.74357) (xy 173.580314 -66.798277) (xy 173.663329 -66.859789)
			(xy 173.741184 -66.927715) (xy 173.777656 -66.964306) (xy 173.785107 -66.97136) (xy 173.803981 -66.979357)
			(xy 173.814232 -66.9798) (xy 173.886368 -66.9798) (xy 173.896611 -66.979328) (xy 173.91547 -66.971327)
			(xy 173.922944 -66.964306) (xy 173.959401 -66.927698) (xy 174.037251 -66.859764) (xy 174.120265 -66.798245)
			(xy 174.207915 -66.743535) (xy 174.299644 -66.695979) (xy 174.39487 -66.65588) (xy 174.492986 -66.623494)
			(xy 174.593371 -66.599025) (xy 174.695386 -66.582629) (xy 174.798382 -66.574411) (xy 174.850044 -66.573908)
			(xy 174.850552 -66.573908) (xy 174.902213 -66.574414) (xy 175.005206 -66.582644) (xy 175.107217 -66.59905)
			(xy 175.207597 -66.623525) (xy 175.305711 -66.655915) (xy 175.400933 -66.696015) (xy 175.492661 -66.743569)
			(xy 175.580311 -66.798275) (xy 175.663327 -66.859787) (xy 175.741182 -66.927713) (xy 175.777652 -66.964306)
			(xy 175.785102 -66.971361) (xy 175.803977 -66.979359) (xy 175.814228 -66.9798) (xy 175.886364 -66.9798)
			(xy 175.896607 -66.979329) (xy 175.915467 -66.971329) (xy 175.92294 -66.964306) (xy 175.959397 -66.927698)
			(xy 176.037247 -66.859763) (xy 176.120261 -66.798245) (xy 176.207911 -66.743534) (xy 176.29964 -66.695978)
			(xy 176.394865 -66.655879) (xy 176.492982 -66.623492) (xy 176.593367 -66.599023) (xy 176.695382 -66.582627)
			(xy 176.798378 -66.574409) (xy 176.85004 -66.573908) (xy 176.850548 -66.573908) (xy 176.902209 -66.574413)
			(xy 177.005202 -66.582644) (xy 177.107213 -66.599049) (xy 177.207594 -66.623524) (xy 177.305707 -66.655914)
			(xy 177.40093 -66.696013) (xy 177.492658 -66.743567) (xy 177.580309 -66.798274) (xy 177.663325 -66.859785)
			(xy 177.74118 -66.927711) (xy 177.777648 -66.964306) (xy 177.785098 -66.971362) (xy 177.803973 -66.979362)
			(xy 177.814224 -66.9798) (xy 177.88636 -66.9798) (xy 177.896603 -66.97933) (xy 177.915465 -66.97133)
			(xy 177.922936 -66.964306) (xy 177.959392 -66.927698) (xy 178.037243 -66.859763) (xy 178.120256 -66.798244)
			(xy 178.207906 -66.743533) (xy 178.299636 -66.695977) (xy 178.394861 -66.655877) (xy 178.492978 -66.62349)
			(xy 178.593363 -66.599021) (xy 178.695377 -66.582625) (xy 178.798374 -66.574406) (xy 178.850036 -66.573908)
			(xy 178.850544 -66.573908) (xy 178.902205 -66.574413) (xy 179.005198 -66.582644) (xy 179.107209 -66.599048)
			(xy 179.207591 -66.623523) (xy 179.305704 -66.655913) (xy 179.400927 -66.696012) (xy 179.492655 -66.743566)
			(xy 179.580306 -66.798272) (xy 179.663322 -66.859783) (xy 179.741178 -66.927709) (xy 179.777644 -66.964306)
			(xy 179.785094 -66.971362) (xy 179.803969 -66.979364) (xy 179.81422 -66.9798) (xy 179.886356 -66.9798)
			(xy 179.8966 -66.979331) (xy 179.915462 -66.971332) (xy 179.922932 -66.964306) (xy 179.959388 -66.927698)
			(xy 180.037239 -66.859763) (xy 180.120252 -66.798244) (xy 180.207902 -66.743532) (xy 180.299631 -66.695975)
			(xy 180.394857 -66.655876) (xy 180.492974 -66.623488) (xy 180.593358 -66.599019) (xy 180.695373 -66.582622)
			(xy 180.79837 -66.574403) (xy 180.850032 -66.573908) (xy 180.85054 -66.573908) (xy 180.902201 -66.574413)
			(xy 181.005195 -66.582643) (xy 181.107206 -66.599047) (xy 181.207587 -66.623522) (xy 181.305701 -66.655912)
			(xy 181.400924 -66.696011) (xy 181.492653 -66.743564) (xy 181.580303 -66.79827) (xy 181.66332 -66.859781)
			(xy 181.741176 -66.927707) (xy 181.77764 -66.964306) (xy 181.78509 -66.971363) (xy 181.803964 -66.979366)
			(xy 181.814216 -66.9798) (xy 181.886352 -66.9798) (xy 181.896596 -66.979331) (xy 181.91546 -66.971334)
			(xy 181.922928 -66.964306) (xy 181.959375 -66.927707) (xy 182.037205 -66.859786) (xy 182.120196 -66.798279)
			(xy 182.207821 -66.743575) (xy 182.299524 -66.696023) (xy 182.394722 -66.655924) (xy 182.492811 -66.623532)
			(xy 182.593167 -66.599054) (xy 182.695155 -66.582646) (xy 182.798125 -66.57441) (xy 182.849774 -66.573908)
			(xy 182.850282 -66.573908) (xy 182.901179 -66.574394) (xy 183.002659 -66.58238) (xy 183.103201 -66.598302)
			(xy 183.202182 -66.622065) (xy 183.298995 -66.65352) (xy 183.393041 -66.692474) (xy 183.48374 -66.738686)
			(xy 183.570534 -66.791873) (xy 183.652888 -66.851705) (xy 183.730293 -66.917815) (xy 183.802273 -66.989793)
			(xy 183.868384 -67.067198) (xy 183.928217 -67.149551) (xy 183.981405 -67.236344) (xy 184.027619 -67.327043)
			(xy 184.066574 -67.421088) (xy 184.09803 -67.5179) (xy 184.121794 -67.616882) (xy 184.137718 -67.717423)
			(xy 184.145705 -67.818903) (xy 184.145705 -67.920697) (xy 184.137718 -68.022177) (xy 184.121794 -68.122718)
			(xy 184.09803 -68.2217) (xy 184.066574 -68.318512) (xy 184.027619 -68.412557) (xy 183.981405 -68.503256)
			(xy 183.928217 -68.590049) (xy 183.868384 -68.672402) (xy 183.802273 -68.749807) (xy 183.730293 -68.821785)
			(xy 183.652888 -68.887895) (xy 183.570534 -68.947727) (xy 183.48374 -69.000914) (xy 183.393041 -69.047126)
			(xy 183.298995 -69.08608) (xy 183.202182 -69.117535) (xy 183.103201 -69.141298) (xy 183.002659 -69.15722)
			(xy 182.901179 -69.165206) (xy 182.850282 -69.165724) (xy 182.849774 -69.165724) (xy 182.798126 -69.165208)
			(xy 182.69516 -69.15696) (xy 182.593178 -69.140541) (xy 182.492825 -69.116057) (xy 182.394741 -69.083663)
			(xy 182.299546 -69.043564) (xy 182.207845 -68.996014) (xy 182.12022 -68.941316) (xy 182.037227 -68.879817)
			(xy 181.959392 -68.811906) (xy 181.922928 -68.775326) (xy 181.915478 -68.76827) (xy 181.896603 -68.760274)
			(xy 181.886352 -68.759832) (xy 181.814216 -68.759832) (xy 181.803973 -68.760305) (xy 181.785111 -68.768302)
			(xy 181.77764 -68.775326) (xy 181.741183 -68.811932) (xy 181.663331 -68.879865) (xy 181.580317 -68.94138)
			(xy 181.492666 -68.996089) (xy 181.400937 -69.043642) (xy 181.305712 -69.083738) (xy 181.207595 -69.116123)
			(xy 181.107211 -69.14059) (xy 181.005197 -69.156984) (xy 180.902201 -69.1652) (xy 180.85054 -69.165724)
			(xy 180.850032 -69.165724) (xy 180.798371 -69.165218) (xy 180.695379 -69.156986) (xy 180.593368 -69.14058)
			(xy 180.492988 -69.116104) (xy 180.394875 -69.083713) (xy 180.299652 -69.043614) (xy 180.207925 -68.99606)
			(xy 180.120275 -68.941354) (xy 180.037259 -68.879843) (xy 179.959404 -68.811917) (xy 179.922932 -68.775326)
			(xy 179.915483 -68.76827) (xy 179.896607 -68.760272) (xy 179.886356 -68.759832) (xy 179.81422 -68.759832)
			(xy 179.803977 -68.760304) (xy 179.785114 -68.768301) (xy 179.777644 -68.775326) (xy 179.741187 -68.811933)
			(xy 179.663336 -68.879865) (xy 179.580321 -68.941381) (xy 179.492671 -68.996089) (xy 179.400941 -69.043643)
			(xy 179.305716 -69.08374) (xy 179.207599 -69.116125) (xy 179.107215 -69.140592) (xy 179.005201 -69.156986)
			(xy 178.902206 -69.165203) (xy 178.850544 -69.165724) (xy 178.850036 -69.165724) (xy 178.798375 -69.165218)
			(xy 178.695382 -69.156986) (xy 178.593372 -69.140581) (xy 178.492991 -69.116105) (xy 178.394878 -69.083715)
			(xy 178.299655 -69.043615) (xy 178.207928 -68.996062) (xy 178.120277 -68.941356) (xy 178.037261 -68.879845)
			(xy 177.959406 -68.811919) (xy 177.922936 -68.775326) (xy 177.915487 -68.768269) (xy 177.896611 -68.76027)
			(xy 177.88636 -68.759832) (xy 177.814224 -68.759832) (xy 177.80398 -68.760303) (xy 177.785117 -68.768299)
			(xy 177.777648 -68.775326) (xy 177.741191 -68.811933) (xy 177.66334 -68.879865) (xy 177.580325 -68.941381)
			(xy 177.492675 -68.99609) (xy 177.400946 -69.043644) (xy 177.30572 -69.083741) (xy 177.207604 -69.116126)
			(xy 177.107219 -69.140594) (xy 177.005205 -69.156988) (xy 176.90221 -69.165206) (xy 176.850548 -69.165724)
			(xy 176.85004 -69.165724) (xy 176.798379 -69.165218) (xy 176.695386 -69.156987) (xy 176.593375 -69.140581)
			(xy 176.492995 -69.116106) (xy 176.394881 -69.083716) (xy 176.299658 -69.043617) (xy 176.20793 -68.996063)
			(xy 176.12028 -68.941357) (xy 176.037263 -68.879846) (xy 175.959408 -68.811921) (xy 175.92294 -68.775326)
			(xy 175.915491 -68.768269) (xy 175.896616 -68.760268) (xy 175.886364 -68.759832) (xy 175.814228 -68.759832)
			(xy 175.803984 -68.760302) (xy 175.785119 -68.768297) (xy 175.777652 -68.775326) (xy 175.741195 -68.811933)
			(xy 175.663344 -68.879866) (xy 175.580329 -68.941382) (xy 175.492679 -68.996091) (xy 175.40095 -69.043645)
			(xy 175.305724 -69.083743) (xy 175.207608 -69.116128) (xy 175.107224 -69.140596) (xy 175.005209 -69.156991)
			(xy 174.902214 -69.165208) (xy 174.850552 -69.165724) (xy 174.850044 -69.165724) (xy 174.798383 -69.165218)
			(xy 174.69539 -69.156987) (xy 174.593379 -69.140582) (xy 174.492998 -69.116107) (xy 174.394884 -69.083717)
			(xy 174.299661 -69.043618) (xy 174.207933 -68.996065) (xy 174.120282 -68.941359) (xy 174.037266 -68.879848)
			(xy 173.95941 -68.811923) (xy 173.922944 -68.775326) (xy 173.915495 -68.768268) (xy 173.89662 -68.760266)
			(xy 173.886368 -68.759832) (xy 173.814232 -68.759832) (xy 173.803988 -68.760302) (xy 173.785122 -68.768295)
			(xy 173.777656 -68.775326) (xy 173.741199 -68.811933) (xy 173.663348 -68.879866) (xy 173.580334 -68.941383)
			(xy 173.492683 -68.996092) (xy 173.400954 -69.043647) (xy 173.305729 -69.083744) (xy 173.207612 -69.11613)
			(xy 173.107228 -69.140598) (xy 173.005214 -69.156993) (xy 172.902218 -69.165211) (xy 172.850556 -69.165724)
			(xy 172.850048 -69.165724) (xy 172.798387 -69.165218) (xy 172.695394 -69.156988) (xy 172.593383 -69.140583)
			(xy 172.493001 -69.116108) (xy 172.394888 -69.083718) (xy 172.299664 -69.04362) (xy 172.207936 -68.996066)
			(xy 172.120285 -68.941361) (xy 172.037268 -68.87985) (xy 171.959412 -68.811925) (xy 171.922948 -68.775326)
			(xy 171.915499 -68.768267) (xy 171.896624 -68.760264) (xy 171.886372 -68.759832) (xy 171.814236 -68.759832)
			(xy 171.803991 -68.760301) (xy 171.785124 -68.768293) (xy 171.77766 -68.775326) (xy 171.739568 -68.813526)
			(xy 171.658021 -68.884163) (xy 171.57088 -68.947773) (xy 171.478751 -69.003914) (xy 171.382272 -69.052198)
			(xy 171.332398 -69.07276) (xy 171.32046 -69.077586) (xy 171.304204 -69.097144) (xy 171.284646 -69.192902)
			(xy 171.282766 -69.205365) (xy 171.289947 -69.229494) (xy 171.298362 -69.238876) (xy 172.182536 -70.12305)
			(xy 204.468984 -70.12305) (xy 204.469397 -70.083893) (xy 204.476297 -70.005883) (xy 204.490029 -69.928782)
			(xy 204.510487 -69.853188) (xy 204.537513 -69.779685) (xy 204.55382 -69.744082) (xy 204.558058 -69.733696)
			(xy 204.558055 -69.71129) (xy 204.55382 -69.700902) (xy 204.537594 -69.665382) (xy 204.51069 -69.592065)
			(xy 204.490309 -69.516675) (xy 204.476609 -69.439788) (xy 204.469695 -69.361998) (xy 204.469238 -69.32295)
			(xy 204.469742 -69.280589) (xy 204.477795 -69.196252) (xy 204.493829 -69.113062) (xy 204.517697 -69.031772)
			(xy 204.549185 -68.95312) (xy 204.588007 -68.877817) (xy 204.63381 -68.806545) (xy 204.686181 -68.739949)
			(xy 204.744646 -68.678634) (xy 204.808674 -68.623153) (xy 204.877686 -68.57401) (xy 204.951056 -68.53165)
			(xy 205.028121 -68.496455) (xy 205.108183 -68.468746) (xy 205.190516 -68.448772) (xy 205.274375 -68.436715)
			(xy 205.359 -68.432684) (xy 205.443625 -68.436715) (xy 205.527484 -68.448772) (xy 205.609817 -68.468746)
			(xy 205.689879 -68.496455) (xy 205.766944 -68.53165) (xy 205.840314 -68.57401) (xy 205.909326 -68.623153)
			(xy 205.973354 -68.678634) (xy 206.031819 -68.739949) (xy 206.08419 -68.806545) (xy 206.129993 -68.877817)
			(xy 206.168815 -68.95312) (xy 206.200303 -69.031772) (xy 206.224171 -69.113062) (xy 206.240205 -69.196252)
			(xy 206.248258 -69.280589) (xy 206.248762 -69.32295) (xy 206.248327 -69.362) (xy 206.241428 -69.439794)
			(xy 206.227732 -69.516683) (xy 206.207345 -69.592075) (xy 206.180423 -69.665388) (xy 206.16418 -69.700902)
			(xy 206.159952 -69.711291) (xy 206.159949 -69.733694) (xy 206.16418 -69.744082) (xy 206.180462 -69.779695)
			(xy 206.207477 -69.853199) (xy 206.227931 -69.928791) (xy 206.241666 -70.005889) (xy 206.248575 -70.083895)
			(xy 206.249016 -70.12305) (xy 206.248512 -70.165423) (xy 206.240456 -70.249784) (xy 206.224418 -70.332998)
			(xy 206.200543 -70.414311) (xy 206.169046 -70.492986) (xy 206.130213 -70.56831) (xy 206.084397 -70.639603)
			(xy 206.03201 -70.706217) (xy 205.97353 -70.76755) (xy 205.909483 -70.823046) (xy 205.840452 -70.872204)
			(xy 205.76706 -70.914576) (xy 205.689973 -70.949781) (xy 205.609889 -70.977498) (xy 205.527532 -70.997478)
			(xy 205.443649 -71.009538) (xy 205.359 -71.013571) (xy 205.274351 -71.009538) (xy 205.190468 -70.997478)
			(xy 205.108111 -70.977498) (xy 205.028027 -70.949781) (xy 204.95094 -70.914576) (xy 204.877548 -70.872204)
			(xy 204.808517 -70.823046) (xy 204.74447 -70.76755) (xy 204.68599 -70.706217) (xy 204.633603 -70.639603)
			(xy 204.587787 -70.56831) (xy 204.548954 -70.492986) (xy 204.517457 -70.414311) (xy 204.493582 -70.332998)
			(xy 204.477544 -70.249784) (xy 204.469488 -70.165423) (xy 204.468984 -70.12305) (xy 172.182536 -70.12305)
			(xy 176.22012 -74.160634) (xy 176.228816 -74.16856) (xy 176.251069 -74.176109) (xy 176.262792 -74.175112)
			(xy 176.291679 -74.17155) (xy 176.349765 -74.167735) (xy 176.37887 -74.167492) (xy 176.379124 -74.167492)
			(xy 176.422656 -74.168036) (xy 176.509302 -74.176572) (xy 176.5947 -74.193529) (xy 176.678033 -74.218746)
			(xy 176.758505 -74.251982) (xy 176.835346 -74.292918) (xy 176.871884 -74.31659) (xy 176.878212 -74.32046)
			(xy 176.892411 -74.324732) (xy 176.899824 -74.324972) (xy 183.118506 -74.324972) (xy 183.131009 -74.32432)
			(xy 183.153099 -74.312594) (xy 183.16067 -74.30262) (xy 183.184245 -74.268787) (xy 183.236738 -74.205183)
			(xy 183.294894 -74.146713) (xy 183.358214 -74.093878) (xy 183.426154 -74.047132) (xy 183.49813 -74.006877)
			(xy 183.573523 -73.973459) (xy 183.651687 -73.947165) (xy 183.731949 -73.92822) (xy 183.813621 -73.916788)
			(xy 183.896 -73.912966) (xy 183.978379 -73.916788) (xy 184.060051 -73.92822) (xy 184.140313 -73.947165)
			(xy 184.218477 -73.973459) (xy 184.29387 -74.006877) (xy 184.365846 -74.047132) (xy 184.433786 -74.093878)
			(xy 184.497106 -74.146713) (xy 184.555262 -74.205183) (xy 184.607755 -74.268787) (xy 184.63133 -74.30262)
			(xy 184.638857 -74.312643) (xy 184.660974 -74.32437) (xy 184.673494 -74.324972) (xy 203.88834 -74.324972)
			(xy 203.898406 -74.324541) (xy 203.916998 -74.316813) (xy 203.924408 -74.309986) (xy 209.034126 -69.200268)
			(xy 209.038698 -69.16674) (xy 209.030062 -69.151754) (xy 209.007954 -69.111576) (xy 208.971197 -69.027555)
			(xy 208.943282 -68.940196) (xy 208.924508 -68.850428) (xy 208.915073 -68.759205) (xy 208.914492 -68.71335)
			(xy 208.914969 -68.672249) (xy 208.922558 -68.590398) (xy 208.937666 -68.509596) (xy 208.960166 -68.430533)
			(xy 208.989864 -68.353884) (xy 209.026507 -68.280301) (xy 209.069784 -68.210413) (xy 209.119324 -68.144816)
			(xy 209.174705 -68.084069) (xy 209.235454 -68.028692) (xy 209.301054 -67.979155) (xy 209.370944 -67.935883)
			(xy 209.444529 -67.899244) (xy 209.521181 -67.86955) (xy 209.600245 -67.847055) (xy 209.681048 -67.831951)
			(xy 209.762899 -67.824367) (xy 209.804 -67.823842) (xy 209.804254 -67.823842) (xy 209.850084 -67.824425)
			(xy 209.941255 -67.833879) (xy 210.03097 -67.85266) (xy 210.118277 -67.880569) (xy 210.202251 -67.917311)
			(xy 210.242404 -67.939412) (xy 210.252317 -67.944344) (xy 210.274367 -67.946082) (xy 210.295117 -67.938423)
			(xy 210.303364 -67.93103) (xy 211.013294 -67.2211) (xy 211.019754 -67.214153) (xy 211.027415 -67.196812)
			(xy 211.02819 -67.177871) (xy 211.025486 -67.168776) (xy 210.996276 -67.08267) (xy 210.992925 -67.073866)
			(xy 210.980878 -67.059401) (xy 210.964402 -67.050294) (xy 210.955128 -67.048634) (xy 210.954874 -67.048634)
			(xy 210.912279 -67.042368) (xy 210.828466 -67.022647) (xy 210.74695 -66.99492) (xy 210.668495 -66.959447)
			(xy 210.593835 -66.916559) (xy 210.523668 -66.866659) (xy 210.490816 -66.83883) (xy 210.483704 -66.832734)
			(xy 210.466432 -66.82613) (xy 210.417918 -66.826638) (xy 210.401154 -66.832988) (xy 210.394042 -66.839338)
			(xy 210.36356 -66.865742) (xy 210.298602 -66.913544) (xy 210.229584 -66.955271) (xy 210.157073 -66.990581)
			(xy 210.081664 -67.019182) (xy 210.003975 -67.040841) (xy 209.924646 -67.05538) (xy 209.844326 -67.06268)
			(xy 209.804 -67.063112) (xy 209.761637 -67.062608) (xy 209.677295 -67.054554) (xy 209.5941 -67.03852)
			(xy 209.512806 -67.01465) (xy 209.434149 -66.98316) (xy 209.358842 -66.944337) (xy 209.287566 -66.89853)
			(xy 209.220967 -66.846156) (xy 209.159648 -66.787689) (xy 209.104164 -66.723657) (xy 209.055018 -66.654641)
			(xy 209.012655 -66.581267) (xy 208.977459 -66.504197) (xy 208.949748 -66.424131) (xy 208.929773 -66.341794)
			(xy 208.917715 -66.25793) (xy 208.913684 -66.1733) (xy 208.917715 -66.08867) (xy 208.929773 -66.004806)
			(xy 208.949748 -65.922469) (xy 208.977459 -65.842403) (xy 209.012655 -65.765333) (xy 209.055018 -65.691959)
			(xy 209.104164 -65.622943) (xy 209.159648 -65.558911) (xy 209.220967 -65.500444) (xy 209.287566 -65.44807)
			(xy 209.358842 -65.402263) (xy 209.434149 -65.36344) (xy 209.512806 -65.33195) (xy 209.5941 -65.30808)
			(xy 209.677295 -65.292046) (xy 209.761637 -65.283992) (xy 209.804 -65.283588) (xy 209.843758 -65.284041)
			(xy 209.922955 -65.29116) (xy 210.001201 -65.305316) (xy 210.077873 -65.326394) (xy 210.152359 -65.354228)
			(xy 210.224065 -65.388594) (xy 210.29242 -65.42922) (xy 210.356879 -65.475781) (xy 210.387184 -65.50152)
			(xy 210.394296 -65.507616) (xy 210.411568 -65.51422) (xy 210.460082 -65.513712) (xy 210.476846 -65.507362)
			(xy 210.483958 -65.501012) (xy 210.514416 -65.474635) (xy 210.57932 -65.426881) (xy 210.64828 -65.385199)
			(xy 210.720729 -65.349928) (xy 210.796073 -65.32136) (xy 210.873694 -65.299728) (xy 210.952954 -65.28521)
			(xy 211.033203 -65.277925) (xy 211.073492 -65.277492) (xy 211.074 -65.277492) (xy 211.114047 -65.277919)
			(xy 211.193819 -65.285094) (xy 211.272623 -65.299414) (xy 211.34982 -65.320763) (xy 211.424784 -65.348967)
			(xy 211.496908 -65.383798) (xy 211.565608 -65.424974) (xy 211.630326 -65.47216) (xy 211.66074 -65.498218)
			(xy 211.667598 -65.504314) (xy 211.68487 -65.510918) (xy 211.73313 -65.510918) (xy 211.750402 -65.504314)
			(xy 211.75726 -65.498218) (xy 211.787665 -65.472151) (xy 211.852395 -65.424982) (xy 211.9211 -65.383818)
			(xy 211.993227 -65.348994) (xy 212.06819 -65.32079) (xy 212.145384 -65.299436) (xy 212.224184 -65.285102)
			(xy 212.303953 -65.277907) (xy 212.344 -65.277492) (xy 212.344254 -65.277492) (xy 212.390518 -65.278083)
			(xy 212.482547 -65.287689) (xy 212.57308 -65.306803) (xy 212.661139 -65.335216) (xy 212.745769 -65.372622)
			(xy 212.786214 -65.395094) (xy 212.796128 -65.400189) (xy 212.818305 -65.402142) (xy 212.839213 -65.394496)
			(xy 212.847428 -65.386966) (xy 213.627462 -64.606932) (xy 213.634302 -64.599532) (xy 213.642018 -64.580933)
			(xy 213.642448 -64.570864) (xy 213.642448 -47.915068) (xy 213.642018 -47.905002) (xy 213.634289 -47.88641)
			(xy 213.627462 -47.879) (xy 212.403182 -46.65472) (xy 212.395783 -46.647874) (xy 212.377185 -46.640143)
			(xy 212.367114 -46.639734) (xy 205.121002 -46.639734) (xy 205.087742 -46.639213) (xy 205.021791 -46.630526)
			(xy 204.957539 -46.613302) (xy 204.896087 -46.587834) (xy 204.838486 -46.55456) (xy 204.785725 -46.514049)
			(xy 204.761846 -46.49089) (xy 203.856844 -45.585888) (xy 203.833686 -45.562009) (xy 203.793176 -45.509246)
			(xy 203.759902 -45.451646) (xy 203.734434 -45.390194) (xy 203.717208 -45.325942) (xy 203.708518 -45.259992)
			(xy 203.708 -45.226732) (xy 203.708 -25.885394) (xy 203.707576 -25.875324) (xy 203.69986 -25.856721)
			(xy 203.693014 -25.849326) (xy 202.194668 -24.35098) (xy 202.187272 -24.34413) (xy 202.168673 -24.336394)
			(xy 202.1586 -24.335994) (xy 57.762394 -24.335994) (xy 57.752324 -24.336418) (xy 57.733721 -24.344133)
			(xy 57.726326 -24.35098) (xy 49.137316 -32.93999) (xy 59.169563 -32.93999) (xy 59.173559 -32.758124)
			(xy 59.185539 -32.576609) (xy 59.205481 -32.395796) (xy 59.233346 -32.216033) (xy 59.26908 -32.037668)
			(xy 59.312613 -31.861044) (xy 59.363863 -31.686503) (xy 59.42273 -31.514381) (xy 59.489101 -31.345011)
			(xy 59.562847 -31.17872) (xy 59.643826 -31.015829) (xy 59.731881 -30.856652) (xy 59.826844 -30.701496)
			(xy 59.928529 -30.550661) (xy 60.036742 -30.404439) (xy 60.151274 -30.26311) (xy 60.271902 -30.126949)
			(xy 60.398395 -29.996217) (xy 60.530508 -29.871168) (xy 60.667986 -29.752042) (xy 60.810564 -29.63907)
			(xy 60.957967 -29.53247) (xy 61.10991 -29.432447) (xy 61.266099 -29.339195) (xy 61.426234 -29.252893)
			(xy 61.590005 -29.173708) (xy 61.757096 -29.101793) (xy 61.927184 -29.037287) (xy 62.099942 -28.980315)
			(xy 62.275036 -28.930985) (xy 62.452127 -28.889394) (xy 62.630874 -28.855621) (xy 62.810932 -28.829733)
			(xy 62.991954 -28.811778) (xy 63.173589 -28.801792) (xy 63.355488 -28.799794) (xy 63.537299 -28.805788)
			(xy 63.718671 -28.819761) (xy 63.899255 -28.841688) (xy 64.078701 -28.871526) (xy 64.256663 -28.909217)
			(xy 64.432798 -28.954688) (xy 64.606766 -29.007852) (xy 64.77823 -29.068606) (xy 64.946861 -29.136833)
			(xy 65.112332 -29.212401) (xy 65.274324 -29.295164) (xy 65.432524 -29.384963) (xy 65.586627 -29.481624)
			(xy 65.736336 -29.584961) (xy 65.881361 -29.694773) (xy 66.021423 -29.81085) (xy 66.156251 -29.932967)
			(xy 66.285585 -30.060888) (xy 66.409176 -30.194367) (xy 66.526784 -30.333145) (xy 66.638183 -30.476956)
			(xy 66.743158 -30.62552) (xy 66.841506 -30.778552) (xy 66.933037 -30.935757) (xy 67.017575 -31.09683)
			(xy 67.094956 -31.261461) (xy 67.165031 -31.429332) (xy 67.227665 -31.600119) (xy 67.282736 -31.773492)
			(xy 67.33014 -31.949117) (xy 67.369783 -32.126654) (xy 67.40159 -32.305761) (xy 67.425499 -32.486093)
			(xy 67.441464 -32.667301) (xy 67.449454 -32.849035) (xy 67.449954 -32.93999) (xy 67.449454 -33.030945)
			(xy 67.441464 -33.212679) (xy 67.425499 -33.393887) (xy 67.40159 -33.574219) (xy 67.369783 -33.753326)
			(xy 67.33014 -33.930863) (xy 67.282736 -34.106488) (xy 67.227665 -34.279861) (xy 67.165031 -34.450648)
			(xy 67.094956 -34.618519) (xy 67.017575 -34.78315) (xy 66.933037 -34.944223) (xy 66.841506 -35.101428)
			(xy 66.743158 -35.25446) (xy 66.638183 -35.403024) (xy 66.526784 -35.546835) (xy 66.409176 -35.685613)
			(xy 66.285585 -35.819092) (xy 66.156251 -35.947013) (xy 66.021423 -36.06913) (xy 65.881361 -36.185207)
			(xy 65.736336 -36.295019) (xy 65.586627 -36.398356) (xy 65.432524 -36.495017) (xy 65.274324 -36.584816)
			(xy 65.112332 -36.667579) (xy 64.946861 -36.743147) (xy 64.77823 -36.811374) (xy 64.606766 -36.872128)
			(xy 64.432798 -36.925292) (xy 64.256663 -36.970763) (xy 64.078701 -37.008454) (xy 63.899255 -37.038292)
			(xy 63.718671 -37.060219) (xy 63.537299 -37.074192) (xy 63.355488 -37.080186) (xy 63.173589 -37.078188)
			(xy 62.991954 -37.068202) (xy 62.810932 -37.050247) (xy 62.630874 -37.024359) (xy 62.452127 -36.990586)
			(xy 62.275036 -36.948995) (xy 62.099942 -36.899665) (xy 61.927184 -36.842693) (xy 61.757096 -36.778187)
			(xy 61.590005 -36.706272) (xy 61.426234 -36.627087) (xy 61.266099 -36.540785) (xy 61.10991 -36.447533)
			(xy 60.957967 -36.34751) (xy 60.810564 -36.24091) (xy 60.667986 -36.127938) (xy 60.530508 -36.008812)
			(xy 60.398395 -35.883763) (xy 60.271902 -35.753031) (xy 60.151274 -35.61687) (xy 60.036742 -35.475541)
			(xy 59.928529 -35.329319) (xy 59.826844 -35.178484) (xy 59.731881 -35.023328) (xy 59.643826 -34.864151)
			(xy 59.562847 -34.70126) (xy 59.489101 -34.534969) (xy 59.42273 -34.365599) (xy 59.363863 -34.193477)
			(xy 59.312613 -34.018936) (xy 59.26908 -33.842312) (xy 59.233346 -33.663947) (xy 59.205481 -33.484184)
			(xy 59.185539 -33.303371) (xy 59.173559 -33.121856) (xy 59.169563 -32.93999) (xy 49.137316 -32.93999)
			(xy 44.057311 -38.019995) (xy 73.97362 -38.019995) (xy 73.977556 -37.915031) (xy 73.989341 -37.810656)
			(xy 74.008909 -37.707458) (xy 74.03615 -37.606014) (xy 74.070911 -37.506895) (xy 74.112997 -37.410657)
			(xy 74.162172 -37.317842) (xy 74.218159 -37.228969) (xy 74.280644 -37.144538) (xy 74.349276 -37.065024)
			(xy 74.423669 -36.990872) (xy 74.503407 -36.922499) (xy 74.58804 -36.860289) (xy 74.632312 -36.832032)
			(xy 74.639413 -36.827227) (xy 74.650103 -36.813832) (xy 74.655815 -36.797673) (xy 74.656188 -36.789106)
			(xy 74.656188 -36.710874) (xy 74.65584 -36.702302) (xy 74.650147 -36.68613) (xy 74.639414 -36.67276)
			(xy 74.632312 -36.667948) (xy 74.588032 -36.639705) (xy 74.503398 -36.577494) (xy 74.423661 -36.509121)
			(xy 74.349268 -36.434969) (xy 74.280637 -36.355454) (xy 74.218153 -36.271022) (xy 74.162167 -36.182149)
			(xy 74.112993 -36.089333) (xy 74.070908 -35.993095) (xy 74.036147 -35.893976) (xy 74.008907 -35.792532)
			(xy 73.98934 -35.689333) (xy 73.977555 -35.584959) (xy 73.97362 -35.479995) (xy 73.977556 -35.375031)
			(xy 73.989341 -35.270656) (xy 74.008909 -35.167458) (xy 74.03615 -35.066014) (xy 74.070911 -34.966895)
			(xy 74.112997 -34.870657) (xy 74.162172 -34.777842) (xy 74.218159 -34.688969) (xy 74.280644 -34.604538)
			(xy 74.349276 -34.525024) (xy 74.423669 -34.450872) (xy 74.503407 -34.382499) (xy 74.58804 -34.320289)
			(xy 74.632312 -34.292032) (xy 74.639413 -34.287227) (xy 74.650103 -34.273832) (xy 74.655815 -34.257673)
			(xy 74.656188 -34.249106) (xy 74.656188 -34.170874) (xy 74.65584 -34.162302) (xy 74.650147 -34.14613)
			(xy 74.639414 -34.13276) (xy 74.632312 -34.127948) (xy 74.586358 -34.098574) (xy 74.498662 -34.033715)
			(xy 74.416276 -33.962234) (xy 74.339696 -33.884563) (xy 74.269388 -33.801173) (xy 74.205776 -33.712568)
			(xy 74.149246 -33.619286) (xy 74.100141 -33.521891) (xy 74.058757 -33.420972) (xy 74.025346 -33.317141)
			(xy 74.000109 -33.211027) (xy 73.983199 -33.103271) (xy 73.974718 -32.994527) (xy 73.974198 -32.93999)
			(xy 73.97467 -32.887593) (xy 73.982502 -32.783093) (xy 73.998122 -32.679471) (xy 74.021441 -32.577305)
			(xy 74.05233 -32.477168) (xy 74.090616 -32.379619) (xy 74.136085 -32.285204) (xy 74.188482 -32.19445)
			(xy 74.247515 -32.107866) (xy 74.312853 -32.025936) (xy 74.384131 -31.949118) (xy 74.46095 -31.877841)
			(xy 74.542881 -31.812504) (xy 74.629466 -31.753472) (xy 74.720219 -31.701076) (xy 74.814635 -31.655609)
			(xy 74.912185 -31.617324) (xy 75.012322 -31.586436) (xy 75.114488 -31.563118) (xy 75.218111 -31.5475)
			(xy 75.322611 -31.53967) (xy 75.375008 -31.53918) (xy 75.429545 -31.539695) (xy 75.538287 -31.548183)
			(xy 75.646041 -31.565099) (xy 75.752154 -31.590341) (xy 75.855983 -31.623756) (xy 75.9569 -31.665141)
			(xy 76.054294 -31.714246) (xy 76.147577 -31.770775) (xy 76.236182 -31.834384) (xy 76.319574 -31.904689)
			(xy 76.397248 -31.981264) (xy 76.468734 -32.063646) (xy 76.533599 -32.151336) (xy 76.562966 -32.197294)
			(xy 76.567777 -32.20439) (xy 76.581169 -32.215083) (xy 76.597326 -32.220796) (xy 76.605892 -32.22117)
			(xy 76.684124 -32.22117) (xy 76.692697 -32.220829) (xy 76.70887 -32.215134) (xy 76.722239 -32.204398)
			(xy 76.72705 -32.197294) (xy 76.756418 -32.151337) (xy 76.821278 -32.063642) (xy 76.89276 -31.981255)
			(xy 76.970432 -31.904676) (xy 77.053823 -31.834368) (xy 77.142428 -31.770757) (xy 77.235711 -31.714228)
			(xy 77.333106 -31.665123) (xy 77.434025 -31.623739) (xy 77.537856 -31.590328) (xy 77.643971 -31.565091)
			(xy 77.751727 -31.548181) (xy 77.860471 -31.539701) (xy 77.915008 -31.53918) (xy 77.967404 -31.539672)
			(xy 78.071903 -31.547504) (xy 78.175525 -31.563123) (xy 78.27769 -31.586442) (xy 78.377827 -31.61733)
			(xy 78.475375 -31.655615) (xy 78.569789 -31.701083) (xy 78.660542 -31.753479) (xy 78.747126 -31.812511)
			(xy 78.829055 -31.877848) (xy 78.905874 -31.949125) (xy 78.977151 -32.025943) (xy 79.042488 -32.107873)
			(xy 79.101519 -32.194456) (xy 79.153916 -32.285209) (xy 79.199384 -32.379623) (xy 79.237669 -32.477172)
			(xy 79.268558 -32.577308) (xy 79.291877 -32.679473) (xy 79.307496 -32.783095) (xy 79.315328 -32.887594)
			(xy 79.315818 -32.93999) (xy 79.315289 -32.994526) (xy 79.306803 -33.103269) (xy 79.289888 -33.211022)
			(xy 79.264647 -33.317135) (xy 79.231234 -33.420964) (xy 79.18985 -33.521881) (xy 79.140746 -33.619275)
			(xy 79.084218 -33.712557) (xy 79.02061 -33.801163) (xy 78.950306 -33.884555) (xy 78.873732 -33.962229)
			(xy 78.79135 -34.033715) (xy 78.703661 -34.098581) (xy 78.657704 -34.127948) (xy 78.650616 -34.132769)
			(xy 78.639922 -34.146157) (xy 78.634205 -34.162309) (xy 78.633828 -34.170874) (xy 78.633828 -34.249106)
			(xy 78.634182 -34.257678) (xy 78.639871 -34.27385) (xy 78.650602 -34.28722) (xy 78.657704 -34.292032)
			(xy 78.701968 -34.320302) (xy 78.786605 -34.382508) (xy 78.866346 -34.450878) (xy 78.940743 -34.525027)
			(xy 79.009379 -34.604539) (xy 79.071867 -34.688969) (xy 79.127856 -34.77784) (xy 79.177033 -34.870656)
			(xy 79.219122 -34.966893) (xy 79.253885 -35.066012) (xy 79.281127 -35.167456) (xy 79.300696 -35.270655)
			(xy 79.312482 -35.37503) (xy 79.316418 -35.479995) (xy 79.312483 -35.584959) (xy 79.300698 -35.689334)
			(xy 79.28113 -35.792534) (xy 79.253888 -35.893978) (xy 79.219126 -35.993097) (xy 79.177038 -36.089335)
			(xy 79.127862 -36.18215) (xy 79.071873 -36.271023) (xy 79.009385 -36.355452) (xy 78.940751 -36.434965)
			(xy 78.866354 -36.509115) (xy 78.786614 -36.577486) (xy 78.701977 -36.639692) (xy 78.657704 -36.667948)
			(xy 78.650616 -36.672769) (xy 78.639922 -36.686157) (xy 78.634205 -36.702309) (xy 78.633828 -36.710874)
			(xy 78.633828 -36.789106) (xy 78.634182 -36.797678) (xy 78.639871 -36.81385) (xy 78.650602 -36.82722)
			(xy 78.657704 -36.832032) (xy 78.701968 -36.860302) (xy 78.786605 -36.922508) (xy 78.866346 -36.990878)
			(xy 78.940743 -37.065027) (xy 79.009379 -37.144539) (xy 79.071867 -37.228969) (xy 79.127856 -37.31784)
			(xy 79.177033 -37.410656) (xy 79.219122 -37.506893) (xy 79.253885 -37.606012) (xy 79.281127 -37.707456)
			(xy 79.300696 -37.810655) (xy 79.312482 -37.91503) (xy 79.316418 -38.019995) (xy 82.86362 -38.019995)
			(xy 82.867556 -37.915031) (xy 82.879341 -37.810656) (xy 82.898909 -37.707458) (xy 82.92615 -37.606014)
			(xy 82.960911 -37.506895) (xy 83.002997 -37.410657) (xy 83.052172 -37.317842) (xy 83.108159 -37.228969)
			(xy 83.170644 -37.144538) (xy 83.239276 -37.065024) (xy 83.313669 -36.990872) (xy 83.393407 -36.922499)
			(xy 83.47804 -36.860289) (xy 83.522312 -36.832032) (xy 83.529413 -36.827227) (xy 83.540103 -36.813832)
			(xy 83.545815 -36.797673) (xy 83.546188 -36.789106) (xy 83.546188 -36.710874) (xy 83.54584 -36.702302)
			(xy 83.540147 -36.68613) (xy 83.529414 -36.67276) (xy 83.522312 -36.667948) (xy 83.478032 -36.639705)
			(xy 83.393398 -36.577494) (xy 83.313661 -36.509121) (xy 83.239268 -36.434969) (xy 83.170637 -36.355454)
			(xy 83.108153 -36.271022) (xy 83.052167 -36.182149) (xy 83.002993 -36.089333) (xy 82.960908 -35.993095)
			(xy 82.926147 -35.893976) (xy 82.898907 -35.792532) (xy 82.87934 -35.689333) (xy 82.867555 -35.584959)
			(xy 82.86362 -35.479995) (xy 82.867556 -35.375031) (xy 82.879341 -35.270656) (xy 82.898909 -35.167458)
			(xy 82.92615 -35.066014) (xy 82.960911 -34.966895) (xy 83.002997 -34.870657) (xy 83.052172 -34.777842)
			(xy 83.108159 -34.688969) (xy 83.170644 -34.604538) (xy 83.239276 -34.525024) (xy 83.313669 -34.450872)
			(xy 83.393407 -34.382499) (xy 83.47804 -34.320289) (xy 83.522312 -34.292032) (xy 83.529413 -34.287227)
			(xy 83.540103 -34.273832) (xy 83.545815 -34.257673) (xy 83.546188 -34.249106) (xy 83.546188 -34.170874)
			(xy 83.54584 -34.162302) (xy 83.540147 -34.14613) (xy 83.529414 -34.13276) (xy 83.522312 -34.127948)
			(xy 83.476358 -34.098574) (xy 83.388662 -34.033715) (xy 83.306276 -33.962234) (xy 83.229696 -33.884563)
			(xy 83.159388 -33.801173) (xy 83.095776 -33.712568) (xy 83.039246 -33.619286) (xy 82.990141 -33.521891)
			(xy 82.948757 -33.420972) (xy 82.915346 -33.317141) (xy 82.890109 -33.211027) (xy 82.873199 -33.103271)
			(xy 82.864718 -32.994527) (xy 82.864198 -32.93999) (xy 82.86467 -32.887593) (xy 82.872502 -32.783093)
			(xy 82.888122 -32.679471) (xy 82.911441 -32.577305) (xy 82.94233 -32.477168) (xy 82.980616 -32.379619)
			(xy 83.026085 -32.285204) (xy 83.078482 -32.19445) (xy 83.137515 -32.107866) (xy 83.202853 -32.025936)
			(xy 83.274131 -31.949118) (xy 83.35095 -31.877841) (xy 83.432881 -31.812504) (xy 83.519466 -31.753472)
			(xy 83.610219 -31.701076) (xy 83.704635 -31.655609) (xy 83.802185 -31.617324) (xy 83.902322 -31.586436)
			(xy 84.004488 -31.563118) (xy 84.108111 -31.5475) (xy 84.212611 -31.53967) (xy 84.265008 -31.53918)
			(xy 84.319545 -31.539695) (xy 84.428287 -31.548183) (xy 84.536041 -31.565099) (xy 84.642154 -31.590341)
			(xy 84.745983 -31.623756) (xy 84.8469 -31.665141) (xy 84.944294 -31.714246) (xy 85.037577 -31.770775)
			(xy 85.126182 -31.834384) (xy 85.209574 -31.904689) (xy 85.287248 -31.981264) (xy 85.358734 -32.063646)
			(xy 85.423599 -32.151336) (xy 85.452966 -32.197294) (xy 85.457777 -32.20439) (xy 85.471169 -32.215083)
			(xy 85.487326 -32.220796) (xy 85.495892 -32.22117) (xy 85.574124 -32.22117) (xy 85.582697 -32.220829)
			(xy 85.59887 -32.215134) (xy 85.612239 -32.204398) (xy 85.61705 -32.197294) (xy 85.646418 -32.151337)
			(xy 85.711278 -32.063642) (xy 85.78276 -31.981255) (xy 85.860432 -31.904676) (xy 85.943823 -31.834368)
			(xy 86.032428 -31.770757) (xy 86.125711 -31.714228) (xy 86.223106 -31.665123) (xy 86.324025 -31.623739)
			(xy 86.427856 -31.590328) (xy 86.533971 -31.565091) (xy 86.641727 -31.548181) (xy 86.750471 -31.539701)
			(xy 86.805008 -31.53918) (xy 86.857404 -31.539672) (xy 86.961903 -31.547504) (xy 87.065525 -31.563123)
			(xy 87.16769 -31.586442) (xy 87.267827 -31.61733) (xy 87.365375 -31.655615) (xy 87.459789 -31.701083)
			(xy 87.550542 -31.753479) (xy 87.637126 -31.812511) (xy 87.719055 -31.877848) (xy 87.795874 -31.949125)
			(xy 87.867151 -32.025943) (xy 87.932488 -32.107873) (xy 87.991519 -32.194456) (xy 88.043916 -32.285209)
			(xy 88.089384 -32.379623) (xy 88.127669 -32.477172) (xy 88.158558 -32.577308) (xy 88.181877 -32.679473)
			(xy 88.197496 -32.783095) (xy 88.205328 -32.887594) (xy 88.205818 -32.93999) (xy 88.205289 -32.994526)
			(xy 88.196803 -33.103269) (xy 88.179888 -33.211022) (xy 88.154647 -33.317135) (xy 88.121234 -33.420964)
			(xy 88.07985 -33.521881) (xy 88.030746 -33.619275) (xy 87.974218 -33.712557) (xy 87.91061 -33.801163)
			(xy 87.840306 -33.884555) (xy 87.763732 -33.962229) (xy 87.68135 -34.033715) (xy 87.593661 -34.098581)
			(xy 87.547704 -34.127948) (xy 87.540616 -34.132769) (xy 87.529922 -34.146157) (xy 87.524205 -34.162309)
			(xy 87.523828 -34.170874) (xy 87.523828 -34.249106) (xy 87.524182 -34.257678) (xy 87.529871 -34.27385)
			(xy 87.540602 -34.28722) (xy 87.547704 -34.292032) (xy 87.591968 -34.320302) (xy 87.676605 -34.382508)
			(xy 87.756346 -34.450878) (xy 87.830743 -34.525027) (xy 87.899379 -34.604539) (xy 87.961867 -34.688969)
			(xy 88.017856 -34.77784) (xy 88.067033 -34.870656) (xy 88.109122 -34.966893) (xy 88.143885 -35.066012)
			(xy 88.171127 -35.167456) (xy 88.190696 -35.270655) (xy 88.202482 -35.37503) (xy 88.206418 -35.479995)
			(xy 88.202483 -35.584959) (xy 88.190698 -35.689334) (xy 88.17113 -35.792534) (xy 88.143888 -35.893978)
			(xy 88.109126 -35.993097) (xy 88.067038 -36.089335) (xy 88.017862 -36.18215) (xy 87.961873 -36.271023)
			(xy 87.899385 -36.355452) (xy 87.830751 -36.434965) (xy 87.756354 -36.509115) (xy 87.676614 -36.577486)
			(xy 87.591977 -36.639692) (xy 87.547704 -36.667948) (xy 87.540616 -36.672769) (xy 87.529922 -36.686157)
			(xy 87.524205 -36.702309) (xy 87.523828 -36.710874) (xy 87.523828 -36.789106) (xy 87.524182 -36.797678)
			(xy 87.529871 -36.81385) (xy 87.540602 -36.82722) (xy 87.547704 -36.832032) (xy 87.591968 -36.860302)
			(xy 87.676605 -36.922508) (xy 87.756346 -36.990878) (xy 87.830743 -37.065027) (xy 87.899379 -37.144539)
			(xy 87.961867 -37.228969) (xy 88.017856 -37.31784) (xy 88.067033 -37.410656) (xy 88.109122 -37.506893)
			(xy 88.143885 -37.606012) (xy 88.171127 -37.707456) (xy 88.190696 -37.810655) (xy 88.202482 -37.91503)
			(xy 88.206418 -38.019995) (xy 91.75362 -38.019995) (xy 91.757556 -37.915031) (xy 91.769341 -37.810656)
			(xy 91.788909 -37.707458) (xy 91.81615 -37.606014) (xy 91.850911 -37.506895) (xy 91.892997 -37.410657)
			(xy 91.942172 -37.317842) (xy 91.998159 -37.228969) (xy 92.060644 -37.144538) (xy 92.129276 -37.065024)
			(xy 92.203669 -36.990872) (xy 92.283407 -36.922499) (xy 92.36804 -36.860289) (xy 92.412312 -36.832032)
			(xy 92.419413 -36.827227) (xy 92.430103 -36.813832) (xy 92.435815 -36.797673) (xy 92.436188 -36.789106)
			(xy 92.436188 -36.710874) (xy 92.43584 -36.702302) (xy 92.430147 -36.68613) (xy 92.419414 -36.67276)
			(xy 92.412312 -36.667948) (xy 92.368032 -36.639705) (xy 92.283398 -36.577494) (xy 92.203661 -36.509121)
			(xy 92.129268 -36.434969) (xy 92.060637 -36.355454) (xy 91.998153 -36.271022) (xy 91.942167 -36.182149)
			(xy 91.892993 -36.089333) (xy 91.850908 -35.993095) (xy 91.816147 -35.893976) (xy 91.788907 -35.792532)
			(xy 91.76934 -35.689333) (xy 91.757555 -35.584959) (xy 91.75362 -35.479995) (xy 91.757556 -35.375031)
			(xy 91.769341 -35.270656) (xy 91.788909 -35.167458) (xy 91.81615 -35.066014) (xy 91.850911 -34.966895)
			(xy 91.892997 -34.870657) (xy 91.942172 -34.777842) (xy 91.998159 -34.688969) (xy 92.060644 -34.604538)
			(xy 92.129276 -34.525024) (xy 92.203669 -34.450872) (xy 92.283407 -34.382499) (xy 92.36804 -34.320289)
			(xy 92.412312 -34.292032) (xy 92.419413 -34.287227) (xy 92.430103 -34.273832) (xy 92.435815 -34.257673)
			(xy 92.436188 -34.249106) (xy 92.436188 -34.170874) (xy 92.43584 -34.162302) (xy 92.430147 -34.14613)
			(xy 92.419414 -34.13276) (xy 92.412312 -34.127948) (xy 92.366358 -34.098574) (xy 92.278662 -34.033715)
			(xy 92.196276 -33.962234) (xy 92.119696 -33.884563) (xy 92.049388 -33.801173) (xy 91.985776 -33.712568)
			(xy 91.929246 -33.619286) (xy 91.880141 -33.521891) (xy 91.838757 -33.420972) (xy 91.805346 -33.317141)
			(xy 91.780109 -33.211027) (xy 91.763199 -33.103271) (xy 91.754718 -32.994527) (xy 91.754198 -32.93999)
			(xy 91.75467 -32.887593) (xy 91.762502 -32.783093) (xy 91.778122 -32.679471) (xy 91.801441 -32.577305)
			(xy 91.83233 -32.477168) (xy 91.870616 -32.379619) (xy 91.916085 -32.285204) (xy 91.968482 -32.19445)
			(xy 92.027515 -32.107866) (xy 92.092853 -32.025936) (xy 92.164131 -31.949118) (xy 92.24095 -31.877841)
			(xy 92.322881 -31.812504) (xy 92.409466 -31.753472) (xy 92.500219 -31.701076) (xy 92.594635 -31.655609)
			(xy 92.692185 -31.617324) (xy 92.792322 -31.586436) (xy 92.894488 -31.563118) (xy 92.998111 -31.5475)
			(xy 93.102611 -31.53967) (xy 93.155008 -31.53918) (xy 93.209545 -31.539695) (xy 93.318287 -31.548183)
			(xy 93.426041 -31.565099) (xy 93.532154 -31.590341) (xy 93.635983 -31.623756) (xy 93.7369 -31.665141)
			(xy 93.834294 -31.714246) (xy 93.927577 -31.770775) (xy 94.016182 -31.834384) (xy 94.099574 -31.904689)
			(xy 94.177248 -31.981264) (xy 94.248734 -32.063646) (xy 94.313599 -32.151336) (xy 94.342966 -32.197294)
			(xy 94.347777 -32.20439) (xy 94.361169 -32.215083) (xy 94.377326 -32.220796) (xy 94.385892 -32.22117)
			(xy 94.464124 -32.22117) (xy 94.472697 -32.220829) (xy 94.48887 -32.215134) (xy 94.502239 -32.204398)
			(xy 94.50705 -32.197294) (xy 94.536418 -32.151337) (xy 94.601278 -32.063642) (xy 94.67276 -31.981255)
			(xy 94.750432 -31.904676) (xy 94.833823 -31.834368) (xy 94.922428 -31.770757) (xy 95.015711 -31.714228)
			(xy 95.113106 -31.665123) (xy 95.214025 -31.623739) (xy 95.317856 -31.590328) (xy 95.423971 -31.565091)
			(xy 95.531727 -31.548181) (xy 95.640471 -31.539701) (xy 95.695008 -31.53918) (xy 95.747404 -31.539672)
			(xy 95.851903 -31.547504) (xy 95.955525 -31.563123) (xy 96.05769 -31.586442) (xy 96.157827 -31.61733)
			(xy 96.255375 -31.655615) (xy 96.349789 -31.701083) (xy 96.440542 -31.753479) (xy 96.527126 -31.812511)
			(xy 96.609055 -31.877848) (xy 96.685874 -31.949125) (xy 96.757151 -32.025943) (xy 96.822488 -32.107873)
			(xy 96.881519 -32.194456) (xy 96.933916 -32.285209) (xy 96.979384 -32.379623) (xy 97.017669 -32.477172)
			(xy 97.048558 -32.577308) (xy 97.071877 -32.679473) (xy 97.087496 -32.783095) (xy 97.095328 -32.887594)
			(xy 97.095818 -32.93999) (xy 130.289563 -32.93999) (xy 130.293559 -32.758124) (xy 130.305539 -32.576609)
			(xy 130.325481 -32.395796) (xy 130.353346 -32.216033) (xy 130.38908 -32.037668) (xy 130.432613 -31.861044)
			(xy 130.483863 -31.686503) (xy 130.54273 -31.514381) (xy 130.609101 -31.345011) (xy 130.682847 -31.17872)
			(xy 130.763826 -31.015829) (xy 130.851881 -30.856652) (xy 130.946844 -30.701496) (xy 131.048529 -30.550661)
			(xy 131.156742 -30.404439) (xy 131.271274 -30.26311) (xy 131.391902 -30.126949) (xy 131.518395 -29.996217)
			(xy 131.650508 -29.871168) (xy 131.787986 -29.752042) (xy 131.930564 -29.63907) (xy 132.077967 -29.53247)
			(xy 132.22991 -29.432447) (xy 132.386099 -29.339195) (xy 132.546234 -29.252893) (xy 132.710005 -29.173708)
			(xy 132.877096 -29.101793) (xy 133.047184 -29.037287) (xy 133.219942 -28.980315) (xy 133.395036 -28.930985)
			(xy 133.572127 -28.889394) (xy 133.750874 -28.855621) (xy 133.930932 -28.829733) (xy 134.111954 -28.811778)
			(xy 134.293589 -28.801792) (xy 134.475488 -28.799794) (xy 134.657299 -28.805788) (xy 134.838671 -28.819761)
			(xy 135.019255 -28.841688) (xy 135.198701 -28.871526) (xy 135.376663 -28.909217) (xy 135.552798 -28.954688)
			(xy 135.726766 -29.007852) (xy 135.89823 -29.068606) (xy 136.066861 -29.136833) (xy 136.232332 -29.212401)
			(xy 136.394324 -29.295164) (xy 136.552524 -29.384963) (xy 136.706627 -29.481624) (xy 136.856336 -29.584961)
			(xy 137.001361 -29.694773) (xy 137.141423 -29.81085) (xy 137.276251 -29.932967) (xy 137.405585 -30.060888)
			(xy 137.529176 -30.194367) (xy 137.646784 -30.333145) (xy 137.758183 -30.476956) (xy 137.863158 -30.62552)
			(xy 137.961506 -30.778552) (xy 138.053037 -30.935757) (xy 138.137575 -31.09683) (xy 138.214956 -31.261461)
			(xy 138.285031 -31.429332) (xy 138.347665 -31.600119) (xy 138.402736 -31.773492) (xy 138.45014 -31.949117)
			(xy 138.489783 -32.126654) (xy 138.52159 -32.305761) (xy 138.545499 -32.486093) (xy 138.561464 -32.667301)
			(xy 138.569454 -32.849035) (xy 138.569954 -32.93999) (xy 138.569454 -33.030945) (xy 138.561464 -33.212679)
			(xy 138.545499 -33.393887) (xy 138.52159 -33.574219) (xy 138.489783 -33.753326) (xy 138.45014 -33.930863)
			(xy 138.402736 -34.106488) (xy 138.347665 -34.279861) (xy 138.285031 -34.450648) (xy 138.214956 -34.618519)
			(xy 138.137575 -34.78315) (xy 138.053037 -34.944223) (xy 137.961506 -35.101428) (xy 137.863158 -35.25446)
			(xy 137.758183 -35.403024) (xy 137.646784 -35.546835) (xy 137.529176 -35.685613) (xy 137.405585 -35.819092)
			(xy 137.276251 -35.947013) (xy 137.141423 -36.06913) (xy 137.001361 -36.185207) (xy 136.856336 -36.295019)
			(xy 136.706627 -36.398356) (xy 136.552524 -36.495017) (xy 136.394324 -36.584816) (xy 136.232332 -36.667579)
			(xy 136.066861 -36.743147) (xy 135.89823 -36.811374) (xy 135.726766 -36.872128) (xy 135.552798 -36.925292)
			(xy 135.376663 -36.970763) (xy 135.198701 -37.008454) (xy 135.019255 -37.038292) (xy 134.838671 -37.060219)
			(xy 134.657299 -37.074192) (xy 134.475488 -37.080186) (xy 134.293589 -37.078188) (xy 134.111954 -37.068202)
			(xy 133.930932 -37.050247) (xy 133.750874 -37.024359) (xy 133.572127 -36.990586) (xy 133.395036 -36.948995)
			(xy 133.219942 -36.899665) (xy 133.047184 -36.842693) (xy 132.877096 -36.778187) (xy 132.710005 -36.706272)
			(xy 132.546234 -36.627087) (xy 132.386099 -36.540785) (xy 132.22991 -36.447533) (xy 132.077967 -36.34751)
			(xy 131.930564 -36.24091) (xy 131.787986 -36.127938) (xy 131.650508 -36.008812) (xy 131.518395 -35.883763)
			(xy 131.391902 -35.753031) (xy 131.271274 -35.61687) (xy 131.156742 -35.475541) (xy 131.048529 -35.329319)
			(xy 130.946844 -35.178484) (xy 130.851881 -35.023328) (xy 130.763826 -34.864151) (xy 130.682847 -34.70126)
			(xy 130.609101 -34.534969) (xy 130.54273 -34.365599) (xy 130.483863 -34.193477) (xy 130.432613 -34.018936)
			(xy 130.38908 -33.842312) (xy 130.353346 -33.663947) (xy 130.325481 -33.484184) (xy 130.305539 -33.303371)
			(xy 130.293559 -33.121856) (xy 130.289563 -32.93999) (xy 97.095818 -32.93999) (xy 97.095289 -32.994526)
			(xy 97.086803 -33.103269) (xy 97.069888 -33.211022) (xy 97.044647 -33.317135) (xy 97.011234 -33.420964)
			(xy 96.96985 -33.521881) (xy 96.920746 -33.619275) (xy 96.864218 -33.712557) (xy 96.80061 -33.801163)
			(xy 96.730306 -33.884555) (xy 96.653732 -33.962229) (xy 96.57135 -34.033715) (xy 96.483661 -34.098581)
			(xy 96.437704 -34.127948) (xy 96.430616 -34.132769) (xy 96.419922 -34.146157) (xy 96.414205 -34.162309)
			(xy 96.413828 -34.170874) (xy 96.413828 -34.249106) (xy 96.414182 -34.257678) (xy 96.419871 -34.27385)
			(xy 96.430602 -34.28722) (xy 96.437704 -34.292032) (xy 96.481968 -34.320302) (xy 96.566605 -34.382508)
			(xy 96.646346 -34.450878) (xy 96.720743 -34.525027) (xy 96.789379 -34.604539) (xy 96.851867 -34.688969)
			(xy 96.907856 -34.77784) (xy 96.957033 -34.870656) (xy 96.999122 -34.966893) (xy 97.033885 -35.066012)
			(xy 97.061127 -35.167456) (xy 97.080696 -35.270655) (xy 97.092482 -35.37503) (xy 97.096418 -35.479995)
			(xy 97.092483 -35.584959) (xy 97.080698 -35.689334) (xy 97.06113 -35.792534) (xy 97.033888 -35.893978)
			(xy 96.999126 -35.993097) (xy 96.957038 -36.089335) (xy 96.907862 -36.18215) (xy 96.851873 -36.271023)
			(xy 96.789385 -36.355452) (xy 96.720751 -36.434965) (xy 96.646354 -36.509115) (xy 96.566614 -36.577486)
			(xy 96.481977 -36.639692) (xy 96.437704 -36.667948) (xy 96.430616 -36.672769) (xy 96.419922 -36.686157)
			(xy 96.414205 -36.702309) (xy 96.413828 -36.710874) (xy 96.413828 -36.789106) (xy 96.414182 -36.797678)
			(xy 96.419871 -36.81385) (xy 96.430602 -36.82722) (xy 96.437704 -36.832032) (xy 96.481968 -36.860302)
			(xy 96.566605 -36.922508) (xy 96.646346 -36.990878) (xy 96.720743 -37.065027) (xy 96.789379 -37.144539)
			(xy 96.851867 -37.228969) (xy 96.907856 -37.31784) (xy 96.957033 -37.410656) (xy 96.999122 -37.506893)
			(xy 97.033885 -37.606012) (xy 97.061127 -37.707456) (xy 97.080696 -37.810655) (xy 97.092482 -37.91503)
			(xy 97.09378 -37.949632) (xy 164.784541 -37.949632) (xy 164.788537 -37.767766) (xy 164.800517 -37.586251)
			(xy 164.820459 -37.405438) (xy 164.848324 -37.225675) (xy 164.884058 -37.04731) (xy 164.927591 -36.870686)
			(xy 164.978841 -36.696145) (xy 165.037708 -36.524023) (xy 165.104079 -36.354653) (xy 165.177825 -36.188362)
			(xy 165.258804 -36.025471) (xy 165.346859 -35.866294) (xy 165.441822 -35.711138) (xy 165.543507 -35.560303)
			(xy 165.65172 -35.414081) (xy 165.766252 -35.272752) (xy 165.88688 -35.136591) (xy 166.013373 -35.005859)
			(xy 166.145486 -34.88081) (xy 166.282964 -34.761684) (xy 166.425542 -34.648712) (xy 166.572945 -34.542112)
			(xy 166.724888 -34.442089) (xy 166.881077 -34.348837) (xy 167.041212 -34.262535) (xy 167.204983 -34.18335)
			(xy 167.372074 -34.111435) (xy 167.542162 -34.046929) (xy 167.71492 -33.989957) (xy 167.890014 -33.940627)
			(xy 168.067105 -33.899036) (xy 168.245852 -33.865263) (xy 168.42591 -33.839375) (xy 168.606932 -33.82142)
			(xy 168.788567 -33.811434) (xy 168.970466 -33.809436) (xy 169.152277 -33.81543) (xy 169.333649 -33.829403)
			(xy 169.514233 -33.85133) (xy 169.693679 -33.881168) (xy 169.871641 -33.918859) (xy 170.047776 -33.96433)
			(xy 170.221744 -34.017494) (xy 170.393208 -34.078248) (xy 170.561839 -34.146475) (xy 170.72731 -34.222043)
			(xy 170.889302 -34.304806) (xy 171.047502 -34.394605) (xy 171.201605 -34.491266) (xy 171.351314 -34.594603)
			(xy 171.496339 -34.704415) (xy 171.636401 -34.820492) (xy 171.771229 -34.942609) (xy 171.900563 -35.07053)
			(xy 172.024154 -35.204009) (xy 172.141762 -35.342787) (xy 172.253161 -35.486598) (xy 172.358136 -35.635162)
			(xy 172.456484 -35.788194) (xy 172.548015 -35.945399) (xy 172.632553 -36.106472) (xy 172.709934 -36.271103)
			(xy 172.780009 -36.438974) (xy 172.842643 -36.609761) (xy 172.897714 -36.783134) (xy 172.945118 -36.958759)
			(xy 172.984761 -37.136296) (xy 173.016568 -37.315403) (xy 173.040477 -37.495735) (xy 173.056442 -37.676943)
			(xy 173.064432 -37.858677) (xy 173.064932 -37.949632) (xy 173.064432 -38.040587) (xy 173.056442 -38.222321)
			(xy 173.040477 -38.403529) (xy 173.016568 -38.583861) (xy 172.984761 -38.762968) (xy 172.945118 -38.940505)
			(xy 172.897714 -39.11613) (xy 172.842643 -39.289503) (xy 172.780009 -39.46029) (xy 172.709934 -39.628161)
			(xy 172.632553 -39.792792) (xy 172.548015 -39.953865) (xy 172.456484 -40.11107) (xy 172.358136 -40.264102)
			(xy 172.253161 -40.412666) (xy 172.141762 -40.556477) (xy 172.024154 -40.695255) (xy 171.900563 -40.828734)
			(xy 171.771229 -40.956655) (xy 171.636401 -41.078772) (xy 171.496339 -41.194849) (xy 171.351314 -41.304661)
			(xy 171.201605 -41.407998) (xy 171.047502 -41.504659) (xy 170.889302 -41.594458) (xy 170.72731 -41.677221)
			(xy 170.561839 -41.752789) (xy 170.393208 -41.821016) (xy 170.221744 -41.88177) (xy 170.047776 -41.934934)
			(xy 169.871641 -41.980405) (xy 169.693679 -42.018096) (xy 169.514233 -42.047934) (xy 169.333649 -42.069861)
			(xy 169.152277 -42.083834) (xy 168.970466 -42.089828) (xy 168.788567 -42.08783) (xy 168.606932 -42.077844)
			(xy 168.42591 -42.059889) (xy 168.245852 -42.034001) (xy 168.067105 -42.000228) (xy 167.890014 -41.958637)
			(xy 167.71492 -41.909307) (xy 167.542162 -41.852335) (xy 167.372074 -41.787829) (xy 167.204983 -41.715914)
			(xy 167.041212 -41.636729) (xy 166.881077 -41.550427) (xy 166.724888 -41.457175) (xy 166.572945 -41.357152)
			(xy 166.425542 -41.250552) (xy 166.282964 -41.13758) (xy 166.145486 -41.018454) (xy 166.013373 -40.893405)
			(xy 165.88688 -40.762673) (xy 165.766252 -40.626512) (xy 165.65172 -40.485183) (xy 165.543507 -40.338961)
			(xy 165.441822 -40.188126) (xy 165.346859 -40.03297) (xy 165.258804 -39.873793) (xy 165.177825 -39.710902)
			(xy 165.104079 -39.544611) (xy 165.037708 -39.375241) (xy 164.978841 -39.203119) (xy 164.927591 -39.028578)
			(xy 164.884058 -38.851954) (xy 164.848324 -38.673589) (xy 164.820459 -38.493826) (xy 164.800517 -38.313013)
			(xy 164.788537 -38.131498) (xy 164.784541 -37.949632) (xy 97.09378 -37.949632) (xy 97.096418 -38.019995)
			(xy 97.092483 -38.124959) (xy 97.080698 -38.229334) (xy 97.06113 -38.332534) (xy 97.033888 -38.433978)
			(xy 96.999126 -38.533097) (xy 96.957038 -38.629335) (xy 96.907862 -38.72215) (xy 96.851873 -38.811023)
			(xy 96.789385 -38.895452) (xy 96.720751 -38.974965) (xy 96.646354 -39.049115) (xy 96.566614 -39.117486)
			(xy 96.481977 -39.179692) (xy 96.437704 -39.207948) (xy 96.430616 -39.212769) (xy 96.419922 -39.226157)
			(xy 96.414205 -39.242309) (xy 96.413828 -39.250874) (xy 96.413828 -39.329106) (xy 96.414182 -39.337678)
			(xy 96.419871 -39.35385) (xy 96.430602 -39.36722) (xy 96.437704 -39.372032) (xy 96.483653 -39.401414)
			(xy 96.571348 -39.466272) (xy 96.653734 -39.537753) (xy 96.730314 -39.615424) (xy 96.800622 -39.698813)
			(xy 96.864234 -39.787417) (xy 96.920763 -39.880699) (xy 96.969869 -39.978093) (xy 97.011254 -40.079011)
			(xy 97.044666 -40.182841) (xy 97.069904 -40.288955) (xy 97.086815 -40.39671) (xy 97.095297 -40.505453)
			(xy 97.095818 -40.55999) (xy 97.095322 -40.612386) (xy 97.087492 -40.716886) (xy 97.071874 -40.820509)
			(xy 97.048556 -40.922674) (xy 97.017669 -41.022812) (xy 96.979384 -41.120361) (xy 96.933917 -41.214776)
			(xy 96.881521 -41.30553) (xy 96.82249 -41.392114) (xy 96.757153 -41.474045) (xy 96.685877 -41.550864)
			(xy 96.609058 -41.622141) (xy 96.527129 -41.687479) (xy 96.440545 -41.746512) (xy 96.349792 -41.798909)
			(xy 96.255377 -41.844377) (xy 96.157829 -41.882663) (xy 96.057692 -41.913552) (xy 95.955526 -41.936871)
			(xy 95.851904 -41.95249) (xy 95.747404 -41.960322) (xy 95.695008 -41.9608) (xy 95.640471 -41.960281)
			(xy 95.531728 -41.951794) (xy 95.423975 -41.934879) (xy 95.317862 -41.909638) (xy 95.214033 -41.876224)
			(xy 95.113115 -41.834839) (xy 95.015721 -41.785734) (xy 94.922438 -41.729206) (xy 94.833833 -41.665597)
			(xy 94.750441 -41.595292) (xy 94.672767 -41.518716) (xy 94.601282 -41.436334) (xy 94.536417 -41.348644)
			(xy 94.50705 -41.302686) (xy 94.502235 -41.295593) (xy 94.488844 -41.284901) (xy 94.47269 -41.279186)
			(xy 94.464124 -41.27881) (xy 94.385892 -41.27881) (xy 94.377321 -41.279171) (xy 94.36115 -41.284858)
			(xy 94.347779 -41.295586) (xy 94.342966 -41.302686) (xy 94.313579 -41.348631) (xy 94.248721 -41.436327)
			(xy 94.177241 -41.518714) (xy 94.099571 -41.595294) (xy 94.016182 -41.665602) (xy 93.927579 -41.729214)
			(xy 93.834298 -41.785745) (xy 93.736904 -41.834851) (xy 93.635986 -41.876235) (xy 93.532156 -41.909648)
			(xy 93.426043 -41.934886) (xy 93.318288 -41.951797) (xy 93.209545 -41.960279) (xy 93.155008 -41.9608)
			(xy 93.102611 -41.960324) (xy 92.99811 -41.952494) (xy 92.894487 -41.936875) (xy 92.792321 -41.913557)
			(xy 92.692183 -41.882669) (xy 92.594633 -41.844384) (xy 92.500217 -41.798916) (xy 92.409463 -41.746519)
			(xy 92.322878 -41.687487) (xy 92.240947 -41.622149) (xy 92.164128 -41.550871) (xy 92.09285 -41.474052)
			(xy 92.027512 -41.39212) (xy 91.96848 -41.305536) (xy 91.916083 -41.214781) (xy 91.870616 -41.120365)
			(xy 91.83233 -41.022816) (xy 91.801442 -40.922677) (xy 91.778124 -40.820511) (xy 91.762506 -40.716888)
			(xy 91.754676 -40.612387) (xy 91.754198 -40.55999) (xy 91.754703 -40.505453) (xy 91.763191 -40.39671)
			(xy 91.780108 -40.288956) (xy 91.80535 -40.182843) (xy 91.838765 -40.079013) (xy 91.880151 -39.978096)
			(xy 91.929258 -39.880701) (xy 91.985787 -39.787419) (xy 92.049397 -39.698814) (xy 92.119703 -39.615422)
			(xy 92.19628 -39.537749) (xy 92.278663 -39.466263) (xy 92.366354 -39.401399) (xy 92.412312 -39.372032)
			(xy 92.419413 -39.367227) (xy 92.430103 -39.353832) (xy 92.435815 -39.337673) (xy 92.436188 -39.329106)
			(xy 92.436188 -39.250874) (xy 92.43584 -39.242302) (xy 92.430147 -39.22613) (xy 92.419414 -39.21276)
			(xy 92.412312 -39.207948) (xy 92.368032 -39.179705) (xy 92.283398 -39.117494) (xy 92.203661 -39.049121)
			(xy 92.129268 -38.974969) (xy 92.060637 -38.895454) (xy 91.998153 -38.811022) (xy 91.942167 -38.722149)
			(xy 91.892993 -38.629333) (xy 91.850908 -38.533095) (xy 91.816147 -38.433976) (xy 91.788907 -38.332532)
			(xy 91.76934 -38.229333) (xy 91.757555 -38.124959) (xy 91.75362 -38.019995) (xy 88.206418 -38.019995)
			(xy 88.202483 -38.124959) (xy 88.190698 -38.229334) (xy 88.17113 -38.332534) (xy 88.143888 -38.433978)
			(xy 88.109126 -38.533097) (xy 88.067038 -38.629335) (xy 88.017862 -38.72215) (xy 87.961873 -38.811023)
			(xy 87.899385 -38.895452) (xy 87.830751 -38.974965) (xy 87.756354 -39.049115) (xy 87.676614 -39.117486)
			(xy 87.591977 -39.179692) (xy 87.547704 -39.207948) (xy 87.540616 -39.212769) (xy 87.529922 -39.226157)
			(xy 87.524205 -39.242309) (xy 87.523828 -39.250874) (xy 87.523828 -39.329106) (xy 87.524182 -39.337678)
			(xy 87.529871 -39.35385) (xy 87.540602 -39.36722) (xy 87.547704 -39.372032) (xy 87.593653 -39.401414)
			(xy 87.681348 -39.466272) (xy 87.763734 -39.537753) (xy 87.840314 -39.615424) (xy 87.910622 -39.698813)
			(xy 87.974234 -39.787417) (xy 88.030763 -39.880699) (xy 88.079869 -39.978093) (xy 88.121254 -40.079011)
			(xy 88.154666 -40.182841) (xy 88.179904 -40.288955) (xy 88.196815 -40.39671) (xy 88.205297 -40.505453)
			(xy 88.205818 -40.55999) (xy 88.205322 -40.612386) (xy 88.197492 -40.716886) (xy 88.181874 -40.820509)
			(xy 88.158556 -40.922674) (xy 88.127669 -41.022812) (xy 88.089384 -41.120361) (xy 88.043917 -41.214776)
			(xy 87.991521 -41.30553) (xy 87.93249 -41.392114) (xy 87.867153 -41.474045) (xy 87.795877 -41.550864)
			(xy 87.719058 -41.622141) (xy 87.637129 -41.687479) (xy 87.550545 -41.746512) (xy 87.459792 -41.798909)
			(xy 87.365377 -41.844377) (xy 87.267829 -41.882663) (xy 87.167692 -41.913552) (xy 87.065526 -41.936871)
			(xy 86.961904 -41.95249) (xy 86.857404 -41.960322) (xy 86.805008 -41.9608) (xy 86.750471 -41.960281)
			(xy 86.641728 -41.951794) (xy 86.533975 -41.934879) (xy 86.427862 -41.909638) (xy 86.324033 -41.876224)
			(xy 86.223115 -41.834839) (xy 86.125721 -41.785734) (xy 86.032438 -41.729206) (xy 85.943833 -41.665597)
			(xy 85.860441 -41.595292) (xy 85.782767 -41.518716) (xy 85.711282 -41.436334) (xy 85.646417 -41.348644)
			(xy 85.61705 -41.302686) (xy 85.612235 -41.295593) (xy 85.598844 -41.284901) (xy 85.58269 -41.279186)
			(xy 85.574124 -41.27881) (xy 85.495892 -41.27881) (xy 85.487321 -41.279171) (xy 85.47115 -41.284858)
			(xy 85.457779 -41.295586) (xy 85.452966 -41.302686) (xy 85.423579 -41.348631) (xy 85.358721 -41.436327)
			(xy 85.287241 -41.518714) (xy 85.209571 -41.595294) (xy 85.126182 -41.665602) (xy 85.037579 -41.729214)
			(xy 84.944298 -41.785745) (xy 84.846904 -41.834851) (xy 84.745986 -41.876235) (xy 84.642156 -41.909648)
			(xy 84.536043 -41.934886) (xy 84.428288 -41.951797) (xy 84.319545 -41.960279) (xy 84.265008 -41.9608)
			(xy 84.212611 -41.960324) (xy 84.10811 -41.952494) (xy 84.004487 -41.936875) (xy 83.902321 -41.913557)
			(xy 83.802183 -41.882669) (xy 83.704633 -41.844384) (xy 83.610217 -41.798916) (xy 83.519463 -41.746519)
			(xy 83.432878 -41.687487) (xy 83.350947 -41.622149) (xy 83.274128 -41.550871) (xy 83.20285 -41.474052)
			(xy 83.137512 -41.39212) (xy 83.07848 -41.305536) (xy 83.026083 -41.214781) (xy 82.980616 -41.120365)
			(xy 82.94233 -41.022816) (xy 82.911442 -40.922677) (xy 82.888124 -40.820511) (xy 82.872506 -40.716888)
			(xy 82.864676 -40.612387) (xy 82.864198 -40.55999) (xy 82.864703 -40.505453) (xy 82.873191 -40.39671)
			(xy 82.890108 -40.288956) (xy 82.91535 -40.182843) (xy 82.948765 -40.079013) (xy 82.990151 -39.978096)
			(xy 83.039258 -39.880701) (xy 83.095787 -39.787419) (xy 83.159397 -39.698814) (xy 83.229703 -39.615422)
			(xy 83.30628 -39.537749) (xy 83.388663 -39.466263) (xy 83.476354 -39.401399) (xy 83.522312 -39.372032)
			(xy 83.529413 -39.367227) (xy 83.540103 -39.353832) (xy 83.545815 -39.337673) (xy 83.546188 -39.329106)
			(xy 83.546188 -39.250874) (xy 83.54584 -39.242302) (xy 83.540147 -39.22613) (xy 83.529414 -39.21276)
			(xy 83.522312 -39.207948) (xy 83.478032 -39.179705) (xy 83.393398 -39.117494) (xy 83.313661 -39.049121)
			(xy 83.239268 -38.974969) (xy 83.170637 -38.895454) (xy 83.108153 -38.811022) (xy 83.052167 -38.722149)
			(xy 83.002993 -38.629333) (xy 82.960908 -38.533095) (xy 82.926147 -38.433976) (xy 82.898907 -38.332532)
			(xy 82.87934 -38.229333) (xy 82.867555 -38.124959) (xy 82.86362 -38.019995) (xy 79.316418 -38.019995)
			(xy 79.312483 -38.124959) (xy 79.300698 -38.229334) (xy 79.28113 -38.332534) (xy 79.253888 -38.433978)
			(xy 79.219126 -38.533097) (xy 79.177038 -38.629335) (xy 79.127862 -38.72215) (xy 79.071873 -38.811023)
			(xy 79.009385 -38.895452) (xy 78.940751 -38.974965) (xy 78.866354 -39.049115) (xy 78.786614 -39.117486)
			(xy 78.701977 -39.179692) (xy 78.657704 -39.207948) (xy 78.650616 -39.212769) (xy 78.639922 -39.226157)
			(xy 78.634205 -39.242309) (xy 78.633828 -39.250874) (xy 78.633828 -39.329106) (xy 78.634182 -39.337678)
			(xy 78.639871 -39.35385) (xy 78.650602 -39.36722) (xy 78.657704 -39.372032) (xy 78.703653 -39.401414)
			(xy 78.791348 -39.466272) (xy 78.873734 -39.537753) (xy 78.950314 -39.615424) (xy 79.020622 -39.698813)
			(xy 79.084234 -39.787417) (xy 79.140763 -39.880699) (xy 79.189869 -39.978093) (xy 79.231254 -40.079011)
			(xy 79.264666 -40.182841) (xy 79.289904 -40.288955) (xy 79.306815 -40.39671) (xy 79.315297 -40.505453)
			(xy 79.315818 -40.55999) (xy 79.315322 -40.612386) (xy 79.307492 -40.716886) (xy 79.291874 -40.820509)
			(xy 79.268556 -40.922674) (xy 79.237669 -41.022812) (xy 79.199384 -41.120361) (xy 79.153917 -41.214776)
			(xy 79.101521 -41.30553) (xy 79.04249 -41.392114) (xy 78.977153 -41.474045) (xy 78.905877 -41.550864)
			(xy 78.829058 -41.622141) (xy 78.747129 -41.687479) (xy 78.660545 -41.746512) (xy 78.569792 -41.798909)
			(xy 78.475377 -41.844377) (xy 78.377829 -41.882663) (xy 78.277692 -41.913552) (xy 78.175526 -41.936871)
			(xy 78.071904 -41.95249) (xy 77.967404 -41.960322) (xy 77.915008 -41.9608) (xy 77.860471 -41.960281)
			(xy 77.751728 -41.951794) (xy 77.643975 -41.934879) (xy 77.537862 -41.909638) (xy 77.434033 -41.876224)
			(xy 77.333115 -41.834839) (xy 77.235721 -41.785734) (xy 77.142438 -41.729206) (xy 77.053833 -41.665597)
			(xy 76.970441 -41.595292) (xy 76.892767 -41.518716) (xy 76.821282 -41.436334) (xy 76.756417 -41.348644)
			(xy 76.72705 -41.302686) (xy 76.722235 -41.295593) (xy 76.708844 -41.284901) (xy 76.69269 -41.279186)
			(xy 76.684124 -41.27881) (xy 76.605892 -41.27881) (xy 76.597321 -41.279171) (xy 76.58115 -41.284858)
			(xy 76.567779 -41.295586) (xy 76.562966 -41.302686) (xy 76.533579 -41.348631) (xy 76.468721 -41.436327)
			(xy 76.397241 -41.518714) (xy 76.319571 -41.595294) (xy 76.236182 -41.665602) (xy 76.147579 -41.729214)
			(xy 76.054298 -41.785745) (xy 75.956904 -41.834851) (xy 75.855986 -41.876235) (xy 75.752156 -41.909648)
			(xy 75.646043 -41.934886) (xy 75.538288 -41.951797) (xy 75.429545 -41.960279) (xy 75.375008 -41.9608)
			(xy 75.322611 -41.960324) (xy 75.21811 -41.952494) (xy 75.114487 -41.936875) (xy 75.012321 -41.913557)
			(xy 74.912183 -41.882669) (xy 74.814633 -41.844384) (xy 74.720217 -41.798916) (xy 74.629463 -41.746519)
			(xy 74.542878 -41.687487) (xy 74.460947 -41.622149) (xy 74.384128 -41.550871) (xy 74.31285 -41.474052)
			(xy 74.247512 -41.39212) (xy 74.18848 -41.305536) (xy 74.136083 -41.214781) (xy 74.090616 -41.120365)
			(xy 74.05233 -41.022816) (xy 74.021442 -40.922677) (xy 73.998124 -40.820511) (xy 73.982506 -40.716888)
			(xy 73.974676 -40.612387) (xy 73.974198 -40.55999) (xy 73.974703 -40.505453) (xy 73.983191 -40.39671)
			(xy 74.000108 -40.288956) (xy 74.02535 -40.182843) (xy 74.058765 -40.079013) (xy 74.100151 -39.978096)
			(xy 74.149258 -39.880701) (xy 74.205787 -39.787419) (xy 74.269397 -39.698814) (xy 74.339703 -39.615422)
			(xy 74.41628 -39.537749) (xy 74.498663 -39.466263) (xy 74.586354 -39.401399) (xy 74.632312 -39.372032)
			(xy 74.639413 -39.367227) (xy 74.650103 -39.353832) (xy 74.655815 -39.337673) (xy 74.656188 -39.329106)
			(xy 74.656188 -39.250874) (xy 74.65584 -39.242302) (xy 74.650147 -39.22613) (xy 74.639414 -39.21276)
			(xy 74.632312 -39.207948) (xy 74.588032 -39.179705) (xy 74.503398 -39.117494) (xy 74.423661 -39.049121)
			(xy 74.349268 -38.974969) (xy 74.280637 -38.895454) (xy 74.218153 -38.811022) (xy 74.162167 -38.722149)
			(xy 74.112993 -38.629333) (xy 74.070908 -38.533095) (xy 74.036147 -38.433976) (xy 74.008907 -38.332532)
			(xy 73.98934 -38.229333) (xy 73.977555 -38.124959) (xy 73.97362 -38.019995) (xy 44.057311 -38.019995)
			(xy 35.447986 -46.62932) (xy 35.441133 -46.636715) (xy 35.433393 -46.655314) (xy 35.433 -46.665388)
			(xy 35.433 -52.324) (xy 74.548492 -52.324) (xy 74.548492 -52.323238) (xy 74.5489 -52.285018) (xy 74.555465 -52.208859)
			(xy 74.568549 -52.133547) (xy 74.588056 -52.059637) (xy 74.600562 -52.023518) (xy 74.603148 -52.015202)
			(xy 74.603148 -51.997798) (xy 74.600562 -51.989482) (xy 74.588071 -51.953359) (xy 74.568581 -51.879447)
			(xy 74.555497 -51.804136) (xy 74.548915 -51.727981) (xy 74.548492 -51.689762) (xy 74.548492 -51.689)
			(xy 74.548907 -51.648953) (xy 74.556102 -51.569184) (xy 74.570436 -51.490384) (xy 74.59179 -51.41319)
			(xy 74.619994 -51.338227) (xy 74.654818 -51.2661) (xy 74.695982 -51.197395) (xy 74.743151 -51.132665)
			(xy 74.769218 -51.10226) (xy 74.774983 -51.095171) (xy 74.781495 -51.078114) (xy 74.781918 -51.068986)
			(xy 74.781918 -51.039014) (xy 74.781484 -51.029891) (xy 74.774964 -51.012841) (xy 74.769218 -51.00574)
			(xy 74.74316 -50.975326) (xy 74.695974 -50.910608) (xy 74.654798 -50.841908) (xy 74.619967 -50.769784)
			(xy 74.591763 -50.69482) (xy 74.570414 -50.617623) (xy 74.556094 -50.538819) (xy 74.548919 -50.459047)
			(xy 74.548492 -50.419) (xy 74.548492 -50.418238) (xy 74.5489 -50.380018) (xy 74.555465 -50.303859)
			(xy 74.568549 -50.228547) (xy 74.588056 -50.154637) (xy 74.600562 -50.118518) (xy 74.603148 -50.110202)
			(xy 74.603148 -50.092798) (xy 74.600562 -50.084482) (xy 74.588071 -50.048359) (xy 74.568581 -49.974447)
			(xy 74.555497 -49.899136) (xy 74.548915 -49.822981) (xy 74.548492 -49.784762) (xy 74.548492 -49.784)
			(xy 74.548996 -49.741652) (xy 74.557047 -49.657338) (xy 74.573076 -49.574172) (xy 74.596937 -49.492905)
			(xy 74.628416 -49.414275) (xy 74.667227 -49.338994) (xy 74.713017 -49.267742) (xy 74.765373 -49.201166)
			(xy 74.823821 -49.139868) (xy 74.887831 -49.084403) (xy 74.956823 -49.035274) (xy 75.030173 -48.992925)
			(xy 75.107216 -48.957741) (xy 75.187255 -48.930039) (xy 75.269564 -48.910071) (xy 75.353399 -48.898018)
			(xy 75.438 -48.893988) (xy 75.522601 -48.898018) (xy 75.606436 -48.910071) (xy 75.688745 -48.930039)
			(xy 75.768784 -48.957741) (xy 75.845827 -48.992925) (xy 75.919177 -49.035274) (xy 75.988169 -49.084403)
			(xy 76.052179 -49.139868) (xy 76.110627 -49.201166) (xy 76.162983 -49.267742) (xy 76.208773 -49.338994)
			(xy 76.247584 -49.414275) (xy 76.279063 -49.492905) (xy 76.302924 -49.574172) (xy 76.318953 -49.657338)
			(xy 76.327004 -49.741652) (xy 76.327508 -49.784) (xy 76.327508 -49.784762) (xy 76.3271 -49.822982)
			(xy 76.320535 -49.899141) (xy 76.307451 -49.974453) (xy 76.287944 -50.048363) (xy 76.275438 -50.084482)
			(xy 76.272852 -50.092798) (xy 76.272852 -50.110202) (xy 76.275438 -50.118518) (xy 76.287929 -50.154641)
			(xy 76.307419 -50.228553) (xy 76.320503 -50.303864) (xy 76.327085 -50.380019) (xy 76.327508 -50.418238)
			(xy 76.327508 -50.419) (xy 76.327093 -50.459047) (xy 76.319898 -50.538816) (xy 76.305564 -50.617616)
			(xy 76.28421 -50.69481) (xy 76.256006 -50.769773) (xy 76.221182 -50.8419) (xy 76.180018 -50.910605)
			(xy 76.132849 -50.975335) (xy 76.106782 -51.00574) (xy 76.101017 -51.012829) (xy 76.094505 -51.029886)
			(xy 76.094082 -51.039014) (xy 76.094082 -51.068986) (xy 76.094516 -51.078109) (xy 76.101036 -51.095159)
			(xy 76.106782 -51.10226) (xy 76.13284 -51.132674) (xy 76.180026 -51.197392) (xy 76.221202 -51.266092)
			(xy 76.256033 -51.338216) (xy 76.284237 -51.41318) (xy 76.305586 -51.490377) (xy 76.319906 -51.569181)
			(xy 76.327081 -51.648953) (xy 76.327508 -51.689) (xy 76.327508 -51.689762) (xy 76.3271 -51.727982)
			(xy 76.320535 -51.804141) (xy 76.307451 -51.879453) (xy 76.287944 -51.953363) (xy 76.275438 -51.989482)
			(xy 76.272852 -51.997798) (xy 76.272852 -52.015202) (xy 76.275438 -52.023518) (xy 76.287929 -52.059641)
			(xy 76.307419 -52.133553) (xy 76.320503 -52.208864) (xy 76.327085 -52.285019) (xy 76.327508 -52.323238)
			(xy 76.327508 -52.324) (xy 80.009492 -52.324) (xy 80.009492 -52.323238) (xy 80.0099 -52.285018) (xy 80.016465 -52.208859)
			(xy 80.029549 -52.133547) (xy 80.049056 -52.059637) (xy 80.061562 -52.023518) (xy 80.064148 -52.015202)
			(xy 80.064148 -51.997798) (xy 80.061562 -51.989482) (xy 80.049071 -51.953359) (xy 80.029581 -51.879447)
			(xy 80.016497 -51.804136) (xy 80.009915 -51.727981) (xy 80.009492 -51.689762) (xy 80.009492 -51.689)
			(xy 80.009907 -51.648953) (xy 80.017102 -51.569184) (xy 80.031436 -51.490384) (xy 80.05279 -51.41319)
			(xy 80.080994 -51.338227) (xy 80.115818 -51.2661) (xy 80.156982 -51.197395) (xy 80.204151 -51.132665)
			(xy 80.230218 -51.10226) (xy 80.235983 -51.095171) (xy 80.242495 -51.078114) (xy 80.242918 -51.068986)
			(xy 80.242918 -51.039014) (xy 80.242484 -51.029891) (xy 80.235964 -51.012841) (xy 80.230218 -51.00574)
			(xy 80.20416 -50.975326) (xy 80.156974 -50.910608) (xy 80.115798 -50.841908) (xy 80.080967 -50.769784)
			(xy 80.052763 -50.69482) (xy 80.031414 -50.617623) (xy 80.017094 -50.538819) (xy 80.009919 -50.459047)
			(xy 80.009492 -50.419) (xy 80.009492 -50.418238) (xy 80.0099 -50.380018) (xy 80.016465 -50.303859)
			(xy 80.029549 -50.228547) (xy 80.049056 -50.154637) (xy 80.061562 -50.118518) (xy 80.064148 -50.110202)
			(xy 80.064148 -50.092798) (xy 80.061562 -50.084482) (xy 80.049071 -50.048359) (xy 80.029581 -49.974447)
			(xy 80.016497 -49.899136) (xy 80.009915 -49.822981) (xy 80.009492 -49.784762) (xy 80.009492 -49.784)
			(xy 80.009996 -49.741652) (xy 80.018047 -49.657338) (xy 80.034076 -49.574172) (xy 80.057937 -49.492905)
			(xy 80.089416 -49.414275) (xy 80.128227 -49.338994) (xy 80.174017 -49.267742) (xy 80.226373 -49.201166)
			(xy 80.284821 -49.139868) (xy 80.348831 -49.084403) (xy 80.417823 -49.035274) (xy 80.491173 -48.992925)
			(xy 80.568216 -48.957741) (xy 80.648255 -48.930039) (xy 80.730564 -48.910071) (xy 80.814399 -48.898018)
			(xy 80.899 -48.893988) (xy 80.983601 -48.898018) (xy 81.067436 -48.910071) (xy 81.149745 -48.930039)
			(xy 81.229784 -48.957741) (xy 81.306827 -48.992925) (xy 81.380177 -49.035274) (xy 81.449169 -49.084403)
			(xy 81.513179 -49.139868) (xy 81.571627 -49.201166) (xy 81.623983 -49.267742) (xy 81.669773 -49.338994)
			(xy 81.708584 -49.414275) (xy 81.740063 -49.492905) (xy 81.763924 -49.574172) (xy 81.779953 -49.657338)
			(xy 81.788004 -49.741652) (xy 81.788508 -49.784) (xy 81.788508 -49.784762) (xy 81.7881 -49.822982)
			(xy 81.781535 -49.899141) (xy 81.768451 -49.974453) (xy 81.748944 -50.048363) (xy 81.736438 -50.084482)
			(xy 81.733852 -50.092798) (xy 81.733852 -50.110202) (xy 81.736438 -50.118518) (xy 81.748929 -50.154641)
			(xy 81.768419 -50.228553) (xy 81.781503 -50.303864) (xy 81.788085 -50.380019) (xy 81.788508 -50.418238)
			(xy 81.788508 -50.419) (xy 81.788093 -50.459047) (xy 81.780898 -50.538816) (xy 81.766564 -50.617616)
			(xy 81.74521 -50.69481) (xy 81.717006 -50.769773) (xy 81.682182 -50.8419) (xy 81.641018 -50.910605)
			(xy 81.593849 -50.975335) (xy 81.567782 -51.00574) (xy 81.562017 -51.012829) (xy 81.555505 -51.029886)
			(xy 81.555082 -51.039014) (xy 81.555082 -51.068986) (xy 81.555516 -51.078109) (xy 81.562036 -51.095159)
			(xy 81.567782 -51.10226) (xy 81.59384 -51.132674) (xy 81.641026 -51.197392) (xy 81.682202 -51.266092)
			(xy 81.717033 -51.338216) (xy 81.745237 -51.41318) (xy 81.766586 -51.490377) (xy 81.780906 -51.569181)
			(xy 81.788081 -51.648953) (xy 81.788508 -51.689) (xy 81.788508 -51.689762) (xy 81.7881 -51.727982)
			(xy 81.781535 -51.804141) (xy 81.768451 -51.879453) (xy 81.748944 -51.953363) (xy 81.736438 -51.989482)
			(xy 81.733852 -51.997798) (xy 81.733852 -52.015202) (xy 81.736438 -52.023518) (xy 81.748929 -52.059641)
			(xy 81.768419 -52.133553) (xy 81.781503 -52.208864) (xy 81.788085 -52.285019) (xy 81.788508 -52.323238)
			(xy 81.788508 -52.324) (xy 85.470492 -52.324) (xy 85.470492 -52.323238) (xy 85.4709 -52.285018) (xy 85.477465 -52.208859)
			(xy 85.490549 -52.133547) (xy 85.510056 -52.059637) (xy 85.522562 -52.023518) (xy 85.525148 -52.015202)
			(xy 85.525148 -51.997798) (xy 85.522562 -51.989482) (xy 85.510071 -51.953359) (xy 85.490581 -51.879447)
			(xy 85.477497 -51.804136) (xy 85.470915 -51.727981) (xy 85.470492 -51.689762) (xy 85.470492 -51.689)
			(xy 85.470907 -51.648953) (xy 85.478102 -51.569184) (xy 85.492436 -51.490384) (xy 85.51379 -51.41319)
			(xy 85.541994 -51.338227) (xy 85.576818 -51.2661) (xy 85.617982 -51.197395) (xy 85.665151 -51.132665)
			(xy 85.691218 -51.10226) (xy 85.696983 -51.095171) (xy 85.703495 -51.078114) (xy 85.703918 -51.068986)
			(xy 85.703918 -51.039014) (xy 85.703484 -51.029891) (xy 85.696964 -51.012841) (xy 85.691218 -51.00574)
			(xy 85.66516 -50.975326) (xy 85.617974 -50.910608) (xy 85.576798 -50.841908) (xy 85.541967 -50.769784)
			(xy 85.513763 -50.69482) (xy 85.492414 -50.617623) (xy 85.478094 -50.538819) (xy 85.470919 -50.459047)
			(xy 85.470492 -50.419) (xy 85.470492 -50.418238) (xy 85.4709 -50.380018) (xy 85.477465 -50.303859)
			(xy 85.490549 -50.228547) (xy 85.510056 -50.154637) (xy 85.522562 -50.118518) (xy 85.525148 -50.110202)
			(xy 85.525148 -50.092798) (xy 85.522562 -50.084482) (xy 85.510071 -50.048359) (xy 85.490581 -49.974447)
			(xy 85.477497 -49.899136) (xy 85.470915 -49.822981) (xy 85.470492 -49.784762) (xy 85.470492 -49.784)
			(xy 85.470996 -49.741652) (xy 85.479047 -49.657338) (xy 85.495076 -49.574172) (xy 85.518937 -49.492905)
			(xy 85.550416 -49.414275) (xy 85.589227 -49.338994) (xy 85.635017 -49.267742) (xy 85.687373 -49.201166)
			(xy 85.745821 -49.139868) (xy 85.809831 -49.084403) (xy 85.878823 -49.035274) (xy 85.952173 -48.992925)
			(xy 86.029216 -48.957741) (xy 86.109255 -48.930039) (xy 86.191564 -48.910071) (xy 86.275399 -48.898018)
			(xy 86.36 -48.893988) (xy 86.444601 -48.898018) (xy 86.528436 -48.910071) (xy 86.610745 -48.930039)
			(xy 86.690784 -48.957741) (xy 86.767827 -48.992925) (xy 86.841177 -49.035274) (xy 86.910169 -49.084403)
			(xy 86.974179 -49.139868) (xy 87.032627 -49.201166) (xy 87.084983 -49.267742) (xy 87.130773 -49.338994)
			(xy 87.169584 -49.414275) (xy 87.201063 -49.492905) (xy 87.224924 -49.574172) (xy 87.240953 -49.657338)
			(xy 87.249004 -49.741652) (xy 87.249508 -49.784) (xy 87.249508 -49.784762) (xy 87.2491 -49.822982)
			(xy 87.242535 -49.899141) (xy 87.229451 -49.974453) (xy 87.209944 -50.048363) (xy 87.197438 -50.084482)
			(xy 87.194852 -50.092798) (xy 87.194852 -50.110202) (xy 87.197438 -50.118518) (xy 87.209929 -50.154641)
			(xy 87.229419 -50.228553) (xy 87.242503 -50.303864) (xy 87.249085 -50.380019) (xy 87.249508 -50.418238)
			(xy 87.249508 -50.419) (xy 87.249093 -50.459047) (xy 87.241898 -50.538816) (xy 87.227564 -50.617616)
			(xy 87.20621 -50.69481) (xy 87.178006 -50.769773) (xy 87.143182 -50.8419) (xy 87.102018 -50.910605)
			(xy 87.054849 -50.975335) (xy 87.028782 -51.00574) (xy 87.023017 -51.012829) (xy 87.016505 -51.029886)
			(xy 87.016082 -51.039014) (xy 87.016082 -51.068986) (xy 87.016516 -51.078109) (xy 87.023036 -51.095159)
			(xy 87.028782 -51.10226) (xy 87.05484 -51.132674) (xy 87.102026 -51.197392) (xy 87.143202 -51.266092)
			(xy 87.178033 -51.338216) (xy 87.206237 -51.41318) (xy 87.227586 -51.490377) (xy 87.241906 -51.569181)
			(xy 87.249081 -51.648953) (xy 87.249508 -51.689) (xy 87.249508 -51.689762) (xy 87.2491 -51.727982)
			(xy 87.242535 -51.804141) (xy 87.229451 -51.879453) (xy 87.209944 -51.953363) (xy 87.197438 -51.989482)
			(xy 87.194852 -51.997798) (xy 87.194852 -52.015202) (xy 87.197438 -52.023518) (xy 87.209929 -52.059641)
			(xy 87.229419 -52.133553) (xy 87.242503 -52.208864) (xy 87.249085 -52.285019) (xy 87.249508 -52.323238)
			(xy 87.249508 -52.324) (xy 90.931492 -52.324) (xy 90.931492 -52.323238) (xy 90.9319 -52.285018) (xy 90.938465 -52.208859)
			(xy 90.951549 -52.133547) (xy 90.971056 -52.059637) (xy 90.983562 -52.023518) (xy 90.986148 -52.015202)
			(xy 90.986148 -51.997798) (xy 90.983562 -51.989482) (xy 90.971071 -51.953359) (xy 90.951581 -51.879447)
			(xy 90.938497 -51.804136) (xy 90.931915 -51.727981) (xy 90.931492 -51.689762) (xy 90.931492 -51.689)
			(xy 90.931907 -51.648953) (xy 90.939102 -51.569184) (xy 90.953436 -51.490384) (xy 90.97479 -51.41319)
			(xy 91.002994 -51.338227) (xy 91.037818 -51.2661) (xy 91.078982 -51.197395) (xy 91.126151 -51.132665)
			(xy 91.152218 -51.10226) (xy 91.157983 -51.095171) (xy 91.164495 -51.078114) (xy 91.164918 -51.068986)
			(xy 91.164918 -51.039014) (xy 91.164484 -51.029891) (xy 91.157964 -51.012841) (xy 91.152218 -51.00574)
			(xy 91.12616 -50.975326) (xy 91.078974 -50.910608) (xy 91.037798 -50.841908) (xy 91.002967 -50.769784)
			(xy 90.974763 -50.69482) (xy 90.953414 -50.617623) (xy 90.939094 -50.538819) (xy 90.931919 -50.459047)
			(xy 90.931492 -50.419) (xy 90.931492 -50.418238) (xy 90.9319 -50.380018) (xy 90.938465 -50.303859)
			(xy 90.951549 -50.228547) (xy 90.971056 -50.154637) (xy 90.983562 -50.118518) (xy 90.986148 -50.110202)
			(xy 90.986148 -50.092798) (xy 90.983562 -50.084482) (xy 90.971071 -50.048359) (xy 90.951581 -49.974447)
			(xy 90.938497 -49.899136) (xy 90.931915 -49.822981) (xy 90.931492 -49.784762) (xy 90.931492 -49.784)
			(xy 90.931996 -49.741652) (xy 90.940047 -49.657338) (xy 90.956076 -49.574172) (xy 90.979937 -49.492905)
			(xy 91.011416 -49.414275) (xy 91.050227 -49.338994) (xy 91.096017 -49.267742) (xy 91.148373 -49.201166)
			(xy 91.206821 -49.139868) (xy 91.270831 -49.084403) (xy 91.339823 -49.035274) (xy 91.413173 -48.992925)
			(xy 91.490216 -48.957741) (xy 91.570255 -48.930039) (xy 91.652564 -48.910071) (xy 91.736399 -48.898018)
			(xy 91.821 -48.893988) (xy 91.905601 -48.898018) (xy 91.989436 -48.910071) (xy 92.071745 -48.930039)
			(xy 92.151784 -48.957741) (xy 92.228827 -48.992925) (xy 92.302177 -49.035274) (xy 92.371169 -49.084403)
			(xy 92.435179 -49.139868) (xy 92.493627 -49.201166) (xy 92.545983 -49.267742) (xy 92.591773 -49.338994)
			(xy 92.630584 -49.414275) (xy 92.662063 -49.492905) (xy 92.685924 -49.574172) (xy 92.701953 -49.657338)
			(xy 92.710004 -49.741652) (xy 92.710508 -49.784) (xy 92.710508 -49.784762) (xy 92.7101 -49.822982)
			(xy 92.703535 -49.899141) (xy 92.690451 -49.974453) (xy 92.670944 -50.048363) (xy 92.658438 -50.084482)
			(xy 92.655852 -50.092798) (xy 92.655852 -50.110202) (xy 92.658438 -50.118518) (xy 92.670929 -50.154641)
			(xy 92.690419 -50.228553) (xy 92.703503 -50.303864) (xy 92.710085 -50.380019) (xy 92.710508 -50.418238)
			(xy 92.710508 -50.419) (xy 92.710093 -50.459047) (xy 92.702898 -50.538816) (xy 92.688564 -50.617616)
			(xy 92.66721 -50.69481) (xy 92.639006 -50.769773) (xy 92.604182 -50.8419) (xy 92.563018 -50.910605)
			(xy 92.515849 -50.975335) (xy 92.489782 -51.00574) (xy 92.484017 -51.012829) (xy 92.477505 -51.029886)
			(xy 92.477082 -51.039014) (xy 92.477082 -51.068986) (xy 92.477516 -51.078109) (xy 92.484036 -51.095159)
			(xy 92.489782 -51.10226) (xy 92.51584 -51.132674) (xy 92.563026 -51.197392) (xy 92.604202 -51.266092)
			(xy 92.639033 -51.338216) (xy 92.667237 -51.41318) (xy 92.688586 -51.490377) (xy 92.702906 -51.569181)
			(xy 92.710081 -51.648953) (xy 92.710508 -51.689) (xy 92.710508 -51.689762) (xy 92.7101 -51.727982)
			(xy 92.703535 -51.804141) (xy 92.690451 -51.879453) (xy 92.670944 -51.953363) (xy 92.658438 -51.989482)
			(xy 92.655852 -51.997798) (xy 92.655852 -52.015202) (xy 92.658438 -52.023518) (xy 92.670929 -52.059641)
			(xy 92.690419 -52.133553) (xy 92.703503 -52.208864) (xy 92.710085 -52.285019) (xy 92.710508 -52.323238)
			(xy 92.710508 -52.324) (xy 96.392492 -52.324) (xy 96.392492 -52.323238) (xy 96.3929 -52.285018) (xy 96.399465 -52.208859)
			(xy 96.412549 -52.133547) (xy 96.432056 -52.059637) (xy 96.444562 -52.023518) (xy 96.447148 -52.015202)
			(xy 96.447148 -51.997798) (xy 96.444562 -51.989482) (xy 96.432071 -51.953359) (xy 96.412581 -51.879447)
			(xy 96.399497 -51.804136) (xy 96.392915 -51.727981) (xy 96.392492 -51.689762) (xy 96.392492 -51.689)
			(xy 96.392907 -51.648953) (xy 96.400102 -51.569184) (xy 96.414436 -51.490384) (xy 96.43579 -51.41319)
			(xy 96.463994 -51.338227) (xy 96.498818 -51.2661) (xy 96.539982 -51.197395) (xy 96.587151 -51.132665)
			(xy 96.613218 -51.10226) (xy 96.618983 -51.095171) (xy 96.625495 -51.078114) (xy 96.625918 -51.068986)
			(xy 96.625918 -51.039014) (xy 96.625484 -51.029891) (xy 96.618964 -51.012841) (xy 96.613218 -51.00574)
			(xy 96.58716 -50.975326) (xy 96.539974 -50.910608) (xy 96.498798 -50.841908) (xy 96.463967 -50.769784)
			(xy 96.435763 -50.69482) (xy 96.414414 -50.617623) (xy 96.400094 -50.538819) (xy 96.392919 -50.459047)
			(xy 96.392492 -50.419) (xy 96.392492 -50.418238) (xy 96.3929 -50.380018) (xy 96.399465 -50.303859)
			(xy 96.412549 -50.228547) (xy 96.432056 -50.154637) (xy 96.444562 -50.118518) (xy 96.447148 -50.110202)
			(xy 96.447148 -50.092798) (xy 96.444562 -50.084482) (xy 96.432071 -50.048359) (xy 96.412581 -49.974447)
			(xy 96.399497 -49.899136) (xy 96.392915 -49.822981) (xy 96.392492 -49.784762) (xy 96.392492 -49.784)
			(xy 96.392996 -49.741652) (xy 96.401047 -49.657338) (xy 96.417076 -49.574172) (xy 96.440937 -49.492905)
			(xy 96.472416 -49.414275) (xy 96.511227 -49.338994) (xy 96.557017 -49.267742) (xy 96.609373 -49.201166)
			(xy 96.667821 -49.139868) (xy 96.731831 -49.084403) (xy 96.800823 -49.035274) (xy 96.874173 -48.992925)
			(xy 96.951216 -48.957741) (xy 97.031255 -48.930039) (xy 97.113564 -48.910071) (xy 97.197399 -48.898018)
			(xy 97.282 -48.893988) (xy 97.366601 -48.898018) (xy 97.450436 -48.910071) (xy 97.532745 -48.930039)
			(xy 97.612784 -48.957741) (xy 97.689827 -48.992925) (xy 97.763177 -49.035274) (xy 97.832169 -49.084403)
			(xy 97.896179 -49.139868) (xy 97.954627 -49.201166) (xy 98.006983 -49.267742) (xy 98.052773 -49.338994)
			(xy 98.091584 -49.414275) (xy 98.123063 -49.492905) (xy 98.146924 -49.574172) (xy 98.162953 -49.657338)
			(xy 98.171004 -49.741652) (xy 98.171508 -49.784) (xy 98.171508 -49.784762) (xy 98.1711 -49.822982)
			(xy 98.164535 -49.899141) (xy 98.151451 -49.974453) (xy 98.131944 -50.048363) (xy 98.119438 -50.084482)
			(xy 98.116852 -50.092798) (xy 98.116852 -50.110202) (xy 98.119438 -50.118518) (xy 98.131929 -50.154641)
			(xy 98.151419 -50.228553) (xy 98.164503 -50.303864) (xy 98.171085 -50.380019) (xy 98.171508 -50.418238)
			(xy 98.171508 -50.419) (xy 98.171093 -50.459047) (xy 98.163898 -50.538816) (xy 98.149564 -50.617616)
			(xy 98.12821 -50.69481) (xy 98.100006 -50.769773) (xy 98.065182 -50.8419) (xy 98.024018 -50.910605)
			(xy 97.976849 -50.975335) (xy 97.950782 -51.00574) (xy 97.945017 -51.012829) (xy 97.938505 -51.029886)
			(xy 97.938082 -51.039014) (xy 97.938082 -51.068986) (xy 97.938516 -51.078109) (xy 97.945036 -51.095159)
			(xy 97.950782 -51.10226) (xy 97.97684 -51.132674) (xy 98.024026 -51.197392) (xy 98.065202 -51.266092)
			(xy 98.100033 -51.338216) (xy 98.128237 -51.41318) (xy 98.149586 -51.490377) (xy 98.163906 -51.569181)
			(xy 98.171081 -51.648953) (xy 98.171508 -51.689) (xy 98.171508 -51.689762) (xy 98.1711 -51.727982)
			(xy 98.164535 -51.804141) (xy 98.151451 -51.879453) (xy 98.131944 -51.953363) (xy 98.119438 -51.989482)
			(xy 98.116852 -51.997798) (xy 98.116852 -52.015202) (xy 98.119438 -52.023518) (xy 98.131929 -52.059641)
			(xy 98.151419 -52.133553) (xy 98.164503 -52.208864) (xy 98.171085 -52.285019) (xy 98.171508 -52.323238)
			(xy 98.171508 -52.324) (xy 101.853492 -52.324) (xy 101.853492 -52.323238) (xy 101.8539 -52.285018)
			(xy 101.860465 -52.208859) (xy 101.873549 -52.133547) (xy 101.893056 -52.059637) (xy 101.905562 -52.023518)
			(xy 101.908148 -52.015202) (xy 101.908148 -51.997798) (xy 101.905562 -51.989482) (xy 101.893071 -51.953359)
			(xy 101.873581 -51.879447) (xy 101.860497 -51.804136) (xy 101.853915 -51.727981) (xy 101.853492 -51.689762)
			(xy 101.853492 -51.689) (xy 101.853907 -51.648953) (xy 101.861102 -51.569184) (xy 101.875436 -51.490384)
			(xy 101.89679 -51.41319) (xy 101.924994 -51.338227) (xy 101.959818 -51.2661) (xy 102.000982 -51.197395)
			(xy 102.048151 -51.132665) (xy 102.074218 -51.10226) (xy 102.079983 -51.095171) (xy 102.086495 -51.078114)
			(xy 102.086918 -51.068986) (xy 102.086918 -51.039014) (xy 102.086484 -51.029891) (xy 102.079964 -51.012841)
			(xy 102.074218 -51.00574) (xy 102.04816 -50.975326) (xy 102.000974 -50.910608) (xy 101.959798 -50.841908)
			(xy 101.924967 -50.769784) (xy 101.896763 -50.69482) (xy 101.875414 -50.617623) (xy 101.861094 -50.538819)
			(xy 101.853919 -50.459047) (xy 101.853492 -50.419) (xy 101.853492 -50.418238) (xy 101.8539 -50.380018)
			(xy 101.860465 -50.303859) (xy 101.873549 -50.228547) (xy 101.893056 -50.154637) (xy 101.905562 -50.118518)
			(xy 101.908148 -50.110202) (xy 101.908148 -50.092798) (xy 101.905562 -50.084482) (xy 101.893071 -50.048359)
			(xy 101.873581 -49.974447) (xy 101.860497 -49.899136) (xy 101.853915 -49.822981) (xy 101.853492 -49.784762)
			(xy 101.853492 -49.784) (xy 101.853996 -49.741652) (xy 101.862047 -49.657338) (xy 101.878076 -49.574172)
			(xy 101.901937 -49.492905) (xy 101.933416 -49.414275) (xy 101.972227 -49.338994) (xy 102.018017 -49.267742)
			(xy 102.070373 -49.201166) (xy 102.128821 -49.139868) (xy 102.192831 -49.084403) (xy 102.261823 -49.035274)
			(xy 102.335173 -48.992925) (xy 102.412216 -48.957741) (xy 102.492255 -48.930039) (xy 102.574564 -48.910071)
			(xy 102.658399 -48.898018) (xy 102.743 -48.893988) (xy 102.827601 -48.898018) (xy 102.911436 -48.910071)
			(xy 102.993745 -48.930039) (xy 103.073784 -48.957741) (xy 103.150827 -48.992925) (xy 103.224177 -49.035274)
			(xy 103.293169 -49.084403) (xy 103.357179 -49.139868) (xy 103.415627 -49.201166) (xy 103.467983 -49.267742)
			(xy 103.513773 -49.338994) (xy 103.552584 -49.414275) (xy 103.584063 -49.492905) (xy 103.607924 -49.574172)
			(xy 103.623953 -49.657338) (xy 103.632004 -49.741652) (xy 103.632508 -49.784) (xy 103.632508 -49.784762)
			(xy 103.6321 -49.822982) (xy 103.625535 -49.899141) (xy 103.612451 -49.974453) (xy 103.592944 -50.048363)
			(xy 103.580438 -50.084482) (xy 103.577852 -50.092798) (xy 103.577852 -50.110202) (xy 103.580438 -50.118518)
			(xy 103.592929 -50.154641) (xy 103.612419 -50.228553) (xy 103.625503 -50.303864) (xy 103.632085 -50.380019)
			(xy 103.632508 -50.418238) (xy 103.632508 -50.419) (xy 103.632093 -50.459047) (xy 103.624898 -50.538816)
			(xy 103.610564 -50.617616) (xy 103.58921 -50.69481) (xy 103.561006 -50.769773) (xy 103.526182 -50.8419)
			(xy 103.485018 -50.910605) (xy 103.437849 -50.975335) (xy 103.411782 -51.00574) (xy 103.406017 -51.012829)
			(xy 103.399505 -51.029886) (xy 103.399082 -51.039014) (xy 103.399082 -51.068986) (xy 103.399516 -51.078109)
			(xy 103.406036 -51.095159) (xy 103.411782 -51.10226) (xy 103.43784 -51.132674) (xy 103.485026 -51.197392)
			(xy 103.526202 -51.266092) (xy 103.561033 -51.338216) (xy 103.589237 -51.41318) (xy 103.610586 -51.490377)
			(xy 103.624906 -51.569181) (xy 103.632081 -51.648953) (xy 103.632508 -51.689) (xy 103.632508 -51.689762)
			(xy 103.6321 -51.727982) (xy 103.625535 -51.804141) (xy 103.612451 -51.879453) (xy 103.592944 -51.953363)
			(xy 103.580438 -51.989482) (xy 103.577852 -51.997798) (xy 103.577852 -52.015202) (xy 103.580438 -52.023518)
			(xy 103.592929 -52.059641) (xy 103.612419 -52.133553) (xy 103.625503 -52.208864) (xy 103.632085 -52.285019)
			(xy 103.632508 -52.323238) (xy 103.632508 -52.324) (xy 107.314492 -52.324) (xy 107.314492 -52.323238)
			(xy 107.3149 -52.285018) (xy 107.321465 -52.208859) (xy 107.334549 -52.133547) (xy 107.354056 -52.059637)
			(xy 107.366562 -52.023518) (xy 107.369148 -52.015202) (xy 107.369148 -51.997798) (xy 107.366562 -51.989482)
			(xy 107.354071 -51.953359) (xy 107.334581 -51.879447) (xy 107.321497 -51.804136) (xy 107.314915 -51.727981)
			(xy 107.314492 -51.689762) (xy 107.314492 -51.689) (xy 107.314907 -51.648953) (xy 107.322102 -51.569184)
			(xy 107.336436 -51.490384) (xy 107.35779 -51.41319) (xy 107.385994 -51.338227) (xy 107.420818 -51.2661)
			(xy 107.461982 -51.197395) (xy 107.509151 -51.132665) (xy 107.535218 -51.10226) (xy 107.540983 -51.095171)
			(xy 107.547495 -51.078114) (xy 107.547918 -51.068986) (xy 107.547918 -51.039014) (xy 107.547484 -51.029891)
			(xy 107.540964 -51.012841) (xy 107.535218 -51.00574) (xy 107.50916 -50.975326) (xy 107.461974 -50.910608)
			(xy 107.420798 -50.841908) (xy 107.385967 -50.769784) (xy 107.357763 -50.69482) (xy 107.336414 -50.617623)
			(xy 107.322094 -50.538819) (xy 107.314919 -50.459047) (xy 107.314492 -50.419) (xy 107.314492 -50.418238)
			(xy 107.3149 -50.380018) (xy 107.321465 -50.303859) (xy 107.334549 -50.228547) (xy 107.354056 -50.154637)
			(xy 107.366562 -50.118518) (xy 107.369148 -50.110202) (xy 107.369148 -50.092798) (xy 107.366562 -50.084482)
			(xy 107.354071 -50.048359) (xy 107.334581 -49.974447) (xy 107.321497 -49.899136) (xy 107.314915 -49.822981)
			(xy 107.314492 -49.784762) (xy 107.314492 -49.784) (xy 107.314996 -49.741652) (xy 107.323047 -49.657338)
			(xy 107.339076 -49.574172) (xy 107.362937 -49.492905) (xy 107.394416 -49.414275) (xy 107.433227 -49.338994)
			(xy 107.479017 -49.267742) (xy 107.531373 -49.201166) (xy 107.589821 -49.139868) (xy 107.653831 -49.084403)
			(xy 107.722823 -49.035274) (xy 107.796173 -48.992925) (xy 107.873216 -48.957741) (xy 107.953255 -48.930039)
			(xy 108.035564 -48.910071) (xy 108.119399 -48.898018) (xy 108.204 -48.893988) (xy 108.288601 -48.898018)
			(xy 108.372436 -48.910071) (xy 108.454745 -48.930039) (xy 108.534784 -48.957741) (xy 108.611827 -48.992925)
			(xy 108.685177 -49.035274) (xy 108.754169 -49.084403) (xy 108.818179 -49.139868) (xy 108.876627 -49.201166)
			(xy 108.928983 -49.267742) (xy 108.974773 -49.338994) (xy 109.013584 -49.414275) (xy 109.045063 -49.492905)
			(xy 109.068924 -49.574172) (xy 109.084953 -49.657338) (xy 109.093004 -49.741652) (xy 109.093508 -49.784)
			(xy 109.093508 -49.784762) (xy 109.0931 -49.822982) (xy 109.086535 -49.899141) (xy 109.073451 -49.974453)
			(xy 109.053944 -50.048363) (xy 109.041438 -50.084482) (xy 109.038852 -50.092798) (xy 109.038852 -50.110202)
			(xy 109.041438 -50.118518) (xy 109.053929 -50.154641) (xy 109.073419 -50.228553) (xy 109.086503 -50.303864)
			(xy 109.093085 -50.380019) (xy 109.093508 -50.418238) (xy 109.093508 -50.419) (xy 109.093093 -50.459047)
			(xy 109.085898 -50.538816) (xy 109.071564 -50.617616) (xy 109.05021 -50.69481) (xy 109.022006 -50.769773)
			(xy 108.987182 -50.8419) (xy 108.946018 -50.910605) (xy 108.898849 -50.975335) (xy 108.872782 -51.00574)
			(xy 108.867017 -51.012829) (xy 108.860505 -51.029886) (xy 108.860082 -51.039014) (xy 108.860082 -51.068986)
			(xy 108.860516 -51.078109) (xy 108.867036 -51.095159) (xy 108.872782 -51.10226) (xy 108.89884 -51.132674)
			(xy 108.946026 -51.197392) (xy 108.987202 -51.266092) (xy 109.022033 -51.338216) (xy 109.050237 -51.41318)
			(xy 109.071586 -51.490377) (xy 109.085906 -51.569181) (xy 109.093081 -51.648953) (xy 109.093508 -51.689)
			(xy 109.093508 -51.689762) (xy 109.0931 -51.727982) (xy 109.086535 -51.804141) (xy 109.073451 -51.879453)
			(xy 109.053944 -51.953363) (xy 109.041438 -51.989482) (xy 109.038852 -51.997798) (xy 109.038852 -52.015202)
			(xy 109.041438 -52.023518) (xy 109.053929 -52.059641) (xy 109.073419 -52.133553) (xy 109.084442 -52.197)
			(xy 152.653492 -52.197) (xy 152.653492 -52.196238) (xy 152.6539 -52.158018) (xy 152.660465 -52.081859)
			(xy 152.673549 -52.006547) (xy 152.693056 -51.932637) (xy 152.705562 -51.896518) (xy 152.708148 -51.888202)
			(xy 152.708148 -51.870798) (xy 152.705562 -51.862482) (xy 152.693071 -51.826359) (xy 152.673581 -51.752447)
			(xy 152.660497 -51.677136) (xy 152.653915 -51.600981) (xy 152.653492 -51.562762) (xy 152.653492 -51.562)
			(xy 152.653907 -51.521953) (xy 152.661102 -51.442184) (xy 152.675436 -51.363384) (xy 152.69679 -51.28619)
			(xy 152.724994 -51.211227) (xy 152.759818 -51.1391) (xy 152.800982 -51.070395) (xy 152.848151 -51.005665)
			(xy 152.874218 -50.97526) (xy 152.879983 -50.968171) (xy 152.886495 -50.951114) (xy 152.886918 -50.941986)
			(xy 152.886918 -50.912014) (xy 152.886484 -50.902891) (xy 152.879964 -50.885841) (xy 152.874218 -50.87874)
			(xy 152.84816 -50.848326) (xy 152.800974 -50.783608) (xy 152.759798 -50.714908) (xy 152.724967 -50.642784)
			(xy 152.696763 -50.56782) (xy 152.675414 -50.490623) (xy 152.661094 -50.411819) (xy 152.653919 -50.332047)
			(xy 152.653492 -50.292) (xy 152.653492 -50.291238) (xy 152.6539 -50.253018) (xy 152.660465 -50.176859)
			(xy 152.673549 -50.101547) (xy 152.693056 -50.027637) (xy 152.705562 -49.991518) (xy 152.708148 -49.983202)
			(xy 152.708148 -49.965798) (xy 152.705562 -49.957482) (xy 152.693071 -49.921359) (xy 152.673581 -49.847447)
			(xy 152.660497 -49.772136) (xy 152.653915 -49.695981) (xy 152.653492 -49.657762) (xy 152.653492 -49.657)
			(xy 152.653996 -49.614652) (xy 152.662047 -49.530338) (xy 152.678076 -49.447172) (xy 152.701937 -49.365905)
			(xy 152.733416 -49.287275) (xy 152.772227 -49.211994) (xy 152.818017 -49.140742) (xy 152.870373 -49.074166)
			(xy 152.928821 -49.012868) (xy 152.992831 -48.957403) (xy 153.061823 -48.908274) (xy 153.135173 -48.865925)
			(xy 153.212216 -48.830741) (xy 153.292255 -48.803039) (xy 153.374564 -48.783071) (xy 153.458399 -48.771018)
			(xy 153.543 -48.766988) (xy 153.627601 -48.771018) (xy 153.711436 -48.783071) (xy 153.793745 -48.803039)
			(xy 153.873784 -48.830741) (xy 153.950827 -48.865925) (xy 154.024177 -48.908274) (xy 154.093169 -48.957403)
			(xy 154.157179 -49.012868) (xy 154.215627 -49.074166) (xy 154.267983 -49.140742) (xy 154.313773 -49.211994)
			(xy 154.352584 -49.287275) (xy 154.384063 -49.365905) (xy 154.407924 -49.447172) (xy 154.423953 -49.530338)
			(xy 154.432004 -49.614652) (xy 154.432508 -49.657) (xy 154.432508 -49.657762) (xy 154.4321 -49.695982)
			(xy 154.425535 -49.772141) (xy 154.412451 -49.847453) (xy 154.392944 -49.921363) (xy 154.380438 -49.957482)
			(xy 154.377852 -49.965798) (xy 154.377852 -49.983202) (xy 154.380438 -49.991518) (xy 154.392929 -50.027641)
			(xy 154.412419 -50.101553) (xy 154.425503 -50.176864) (xy 154.432085 -50.253019) (xy 154.432508 -50.291238)
			(xy 154.432508 -50.292) (xy 154.432093 -50.332047) (xy 154.424898 -50.411816) (xy 154.410564 -50.490616)
			(xy 154.38921 -50.56781) (xy 154.361006 -50.642773) (xy 154.326182 -50.7149) (xy 154.285018 -50.783605)
			(xy 154.237849 -50.848335) (xy 154.211782 -50.87874) (xy 154.206017 -50.885829) (xy 154.199505 -50.902886)
			(xy 154.199082 -50.912014) (xy 154.199082 -50.941986) (xy 154.199516 -50.951109) (xy 154.206036 -50.968159)
			(xy 154.211782 -50.97526) (xy 154.23784 -51.005674) (xy 154.285026 -51.070392) (xy 154.326202 -51.139092)
			(xy 154.361033 -51.211216) (xy 154.389237 -51.28618) (xy 154.410586 -51.363377) (xy 154.424906 -51.442181)
			(xy 154.432081 -51.521953) (xy 154.432508 -51.562) (xy 154.432508 -51.562762) (xy 154.4321 -51.600982)
			(xy 154.425535 -51.677141) (xy 154.412451 -51.752453) (xy 154.392944 -51.826363) (xy 154.380438 -51.862482)
			(xy 154.377852 -51.870798) (xy 154.377852 -51.888202) (xy 154.380438 -51.896518) (xy 154.392929 -51.932641)
			(xy 154.412419 -52.006553) (xy 154.425503 -52.081864) (xy 154.432085 -52.158019) (xy 154.432508 -52.196238)
			(xy 154.432508 -52.197) (xy 158.114492 -52.197) (xy 158.114492 -52.196238) (xy 158.1149 -52.158018)
			(xy 158.121465 -52.081859) (xy 158.134549 -52.006547) (xy 158.154056 -51.932637) (xy 158.166562 -51.896518)
			(xy 158.169148 -51.888202) (xy 158.169148 -51.870798) (xy 158.166562 -51.862482) (xy 158.154071 -51.826359)
			(xy 158.134581 -51.752447) (xy 158.121497 -51.677136) (xy 158.114915 -51.600981) (xy 158.114492 -51.562762)
			(xy 158.114492 -51.562) (xy 158.114907 -51.521953) (xy 158.122102 -51.442184) (xy 158.136436 -51.363384)
			(xy 158.15779 -51.28619) (xy 158.185994 -51.211227) (xy 158.220818 -51.1391) (xy 158.261982 -51.070395)
			(xy 158.309151 -51.005665) (xy 158.335218 -50.97526) (xy 158.340983 -50.968171) (xy 158.347495 -50.951114)
			(xy 158.347918 -50.941986) (xy 158.347918 -50.912014) (xy 158.347484 -50.902891) (xy 158.340964 -50.885841)
			(xy 158.335218 -50.87874) (xy 158.30916 -50.848326) (xy 158.261974 -50.783608) (xy 158.220798 -50.714908)
			(xy 158.185967 -50.642784) (xy 158.157763 -50.56782) (xy 158.136414 -50.490623) (xy 158.122094 -50.411819)
			(xy 158.114919 -50.332047) (xy 158.114492 -50.292) (xy 158.114492 -50.291238) (xy 158.1149 -50.253018)
			(xy 158.121465 -50.176859) (xy 158.134549 -50.101547) (xy 158.154056 -50.027637) (xy 158.166562 -49.991518)
			(xy 158.169148 -49.983202) (xy 158.169148 -49.965798) (xy 158.166562 -49.957482) (xy 158.154071 -49.921359)
			(xy 158.134581 -49.847447) (xy 158.121497 -49.772136) (xy 158.114915 -49.695981) (xy 158.114492 -49.657762)
			(xy 158.114492 -49.657) (xy 158.114996 -49.614652) (xy 158.123047 -49.530338) (xy 158.139076 -49.447172)
			(xy 158.162937 -49.365905) (xy 158.194416 -49.287275) (xy 158.233227 -49.211994) (xy 158.279017 -49.140742)
			(xy 158.331373 -49.074166) (xy 158.389821 -49.012868) (xy 158.453831 -48.957403) (xy 158.522823 -48.908274)
			(xy 158.596173 -48.865925) (xy 158.673216 -48.830741) (xy 158.753255 -48.803039) (xy 158.835564 -48.783071)
			(xy 158.919399 -48.771018) (xy 159.004 -48.766988) (xy 159.088601 -48.771018) (xy 159.172436 -48.783071)
			(xy 159.254745 -48.803039) (xy 159.334784 -48.830741) (xy 159.411827 -48.865925) (xy 159.485177 -48.908274)
			(xy 159.554169 -48.957403) (xy 159.618179 -49.012868) (xy 159.676627 -49.074166) (xy 159.728983 -49.140742)
			(xy 159.774773 -49.211994) (xy 159.813584 -49.287275) (xy 159.845063 -49.365905) (xy 159.868924 -49.447172)
			(xy 159.884953 -49.530338) (xy 159.893004 -49.614652) (xy 159.893508 -49.657) (xy 159.893508 -49.657762)
			(xy 159.8931 -49.695982) (xy 159.886535 -49.772141) (xy 159.873451 -49.847453) (xy 159.853944 -49.921363)
			(xy 159.841438 -49.957482) (xy 159.838852 -49.965798) (xy 159.838852 -49.983202) (xy 159.841438 -49.991518)
			(xy 159.853929 -50.027641) (xy 159.873419 -50.101553) (xy 159.886503 -50.176864) (xy 159.893085 -50.253019)
			(xy 159.893508 -50.291238) (xy 159.893508 -50.292) (xy 159.893093 -50.332047) (xy 159.885898 -50.411816)
			(xy 159.871564 -50.490616) (xy 159.85021 -50.56781) (xy 159.822006 -50.642773) (xy 159.787182 -50.7149)
			(xy 159.746018 -50.783605) (xy 159.698849 -50.848335) (xy 159.672782 -50.87874) (xy 159.667017 -50.885829)
			(xy 159.660505 -50.902886) (xy 159.660082 -50.912014) (xy 159.660082 -50.941986) (xy 159.660516 -50.951109)
			(xy 159.667036 -50.968159) (xy 159.672782 -50.97526) (xy 159.69884 -51.005674) (xy 159.746026 -51.070392)
			(xy 159.787202 -51.139092) (xy 159.822033 -51.211216) (xy 159.850237 -51.28618) (xy 159.871586 -51.363377)
			(xy 159.885906 -51.442181) (xy 159.893081 -51.521953) (xy 159.893508 -51.562) (xy 159.893508 -51.562762)
			(xy 159.8931 -51.600982) (xy 159.886535 -51.677141) (xy 159.873451 -51.752453) (xy 159.853944 -51.826363)
			(xy 159.841438 -51.862482) (xy 159.838852 -51.870798) (xy 159.838852 -51.888202) (xy 159.841438 -51.896518)
			(xy 159.853929 -51.932641) (xy 159.873419 -52.006553) (xy 159.886503 -52.081864) (xy 159.893085 -52.158019)
			(xy 159.893508 -52.196238) (xy 159.893508 -52.197) (xy 163.575492 -52.197) (xy 163.575492 -52.196238)
			(xy 163.5759 -52.158018) (xy 163.582465 -52.081859) (xy 163.595549 -52.006547) (xy 163.615056 -51.932637)
			(xy 163.627562 -51.896518) (xy 163.630148 -51.888202) (xy 163.630148 -51.870798) (xy 163.627562 -51.862482)
			(xy 163.615071 -51.826359) (xy 163.595581 -51.752447) (xy 163.582497 -51.677136) (xy 163.575915 -51.600981)
			(xy 163.575492 -51.562762) (xy 163.575492 -51.562) (xy 163.575907 -51.521953) (xy 163.583102 -51.442184)
			(xy 163.597436 -51.363384) (xy 163.61879 -51.28619) (xy 163.646994 -51.211227) (xy 163.681818 -51.1391)
			(xy 163.722982 -51.070395) (xy 163.770151 -51.005665) (xy 163.796218 -50.97526) (xy 163.801983 -50.968171)
			(xy 163.808495 -50.951114) (xy 163.808918 -50.941986) (xy 163.808918 -50.912014) (xy 163.808484 -50.902891)
			(xy 163.801964 -50.885841) (xy 163.796218 -50.87874) (xy 163.77016 -50.848326) (xy 163.722974 -50.783608)
			(xy 163.681798 -50.714908) (xy 163.646967 -50.642784) (xy 163.618763 -50.56782) (xy 163.597414 -50.490623)
			(xy 163.583094 -50.411819) (xy 163.575919 -50.332047) (xy 163.575492 -50.292) (xy 163.575492 -50.291238)
			(xy 163.5759 -50.253018) (xy 163.582465 -50.176859) (xy 163.595549 -50.101547) (xy 163.615056 -50.027637)
			(xy 163.627562 -49.991518) (xy 163.630148 -49.983202) (xy 163.630148 -49.965798) (xy 163.627562 -49.957482)
			(xy 163.615071 -49.921359) (xy 163.595581 -49.847447) (xy 163.582497 -49.772136) (xy 163.575915 -49.695981)
			(xy 163.575492 -49.657762) (xy 163.575492 -49.657) (xy 163.575996 -49.614652) (xy 163.584047 -49.530338)
			(xy 163.600076 -49.447172) (xy 163.623937 -49.365905) (xy 163.655416 -49.287275) (xy 163.694227 -49.211994)
			(xy 163.740017 -49.140742) (xy 163.792373 -49.074166) (xy 163.850821 -49.012868) (xy 163.914831 -48.957403)
			(xy 163.983823 -48.908274) (xy 164.057173 -48.865925) (xy 164.134216 -48.830741) (xy 164.214255 -48.803039)
			(xy 164.296564 -48.783071) (xy 164.380399 -48.771018) (xy 164.465 -48.766988) (xy 164.549601 -48.771018)
			(xy 164.633436 -48.783071) (xy 164.715745 -48.803039) (xy 164.795784 -48.830741) (xy 164.872827 -48.865925)
			(xy 164.946177 -48.908274) (xy 165.015169 -48.957403) (xy 165.079179 -49.012868) (xy 165.137627 -49.074166)
			(xy 165.189983 -49.140742) (xy 165.235773 -49.211994) (xy 165.274584 -49.287275) (xy 165.306063 -49.365905)
			(xy 165.329924 -49.447172) (xy 165.345953 -49.530338) (xy 165.354004 -49.614652) (xy 165.354508 -49.657)
			(xy 165.354508 -49.657762) (xy 165.3541 -49.695982) (xy 165.347535 -49.772141) (xy 165.334451 -49.847453)
			(xy 165.314944 -49.921363) (xy 165.302438 -49.957482) (xy 165.299852 -49.965798) (xy 165.299852 -49.983202)
			(xy 165.302438 -49.991518) (xy 165.314929 -50.027641) (xy 165.334419 -50.101553) (xy 165.347503 -50.176864)
			(xy 165.354085 -50.253019) (xy 165.354508 -50.291238) (xy 165.354508 -50.292) (xy 165.354093 -50.332047)
			(xy 165.346898 -50.411816) (xy 165.332564 -50.490616) (xy 165.31121 -50.56781) (xy 165.283006 -50.642773)
			(xy 165.248182 -50.7149) (xy 165.207018 -50.783605) (xy 165.159849 -50.848335) (xy 165.133782 -50.87874)
			(xy 165.128017 -50.885829) (xy 165.121505 -50.902886) (xy 165.121082 -50.912014) (xy 165.121082 -50.941986)
			(xy 165.121516 -50.951109) (xy 165.128036 -50.968159) (xy 165.133782 -50.97526) (xy 165.15984 -51.005674)
			(xy 165.207026 -51.070392) (xy 165.248202 -51.139092) (xy 165.283033 -51.211216) (xy 165.311237 -51.28618)
			(xy 165.332586 -51.363377) (xy 165.346906 -51.442181) (xy 165.354081 -51.521953) (xy 165.354508 -51.562)
			(xy 165.354508 -51.562762) (xy 165.3541 -51.600982) (xy 165.347535 -51.677141) (xy 165.334451 -51.752453)
			(xy 165.314944 -51.826363) (xy 165.302438 -51.862482) (xy 165.299852 -51.870798) (xy 165.299852 -51.888202)
			(xy 165.302438 -51.896518) (xy 165.314929 -51.932641) (xy 165.334419 -52.006553) (xy 165.347503 -52.081864)
			(xy 165.354085 -52.158019) (xy 165.354508 -52.196238) (xy 165.354508 -52.197) (xy 169.036492 -52.197)
			(xy 169.036492 -52.196238) (xy 169.0369 -52.158018) (xy 169.043465 -52.081859) (xy 169.056549 -52.006547)
			(xy 169.076056 -51.932637) (xy 169.088562 -51.896518) (xy 169.091148 -51.888202) (xy 169.091148 -51.870798)
			(xy 169.088562 -51.862482) (xy 169.076071 -51.826359) (xy 169.056581 -51.752447) (xy 169.043497 -51.677136)
			(xy 169.036915 -51.600981) (xy 169.036492 -51.562762) (xy 169.036492 -51.562) (xy 169.036907 -51.521953)
			(xy 169.044102 -51.442184) (xy 169.058436 -51.363384) (xy 169.07979 -51.28619) (xy 169.107994 -51.211227)
			(xy 169.142818 -51.1391) (xy 169.183982 -51.070395) (xy 169.231151 -51.005665) (xy 169.257218 -50.97526)
			(xy 169.262983 -50.968171) (xy 169.269495 -50.951114) (xy 169.269918 -50.941986) (xy 169.269918 -50.912014)
			(xy 169.269484 -50.902891) (xy 169.262964 -50.885841) (xy 169.257218 -50.87874) (xy 169.23116 -50.848326)
			(xy 169.183974 -50.783608) (xy 169.142798 -50.714908) (xy 169.107967 -50.642784) (xy 169.079763 -50.56782)
			(xy 169.058414 -50.490623) (xy 169.044094 -50.411819) (xy 169.036919 -50.332047) (xy 169.036492 -50.292)
			(xy 169.036492 -50.291238) (xy 169.0369 -50.253018) (xy 169.043465 -50.176859) (xy 169.056549 -50.101547)
			(xy 169.076056 -50.027637) (xy 169.088562 -49.991518) (xy 169.091148 -49.983202) (xy 169.091148 -49.965798)
			(xy 169.088562 -49.957482) (xy 169.076071 -49.921359) (xy 169.056581 -49.847447) (xy 169.043497 -49.772136)
			(xy 169.036915 -49.695981) (xy 169.036492 -49.657762) (xy 169.036492 -49.657) (xy 169.036996 -49.614652)
			(xy 169.045047 -49.530338) (xy 169.061076 -49.447172) (xy 169.084937 -49.365905) (xy 169.116416 -49.287275)
			(xy 169.155227 -49.211994) (xy 169.201017 -49.140742) (xy 169.253373 -49.074166) (xy 169.311821 -49.012868)
			(xy 169.375831 -48.957403) (xy 169.444823 -48.908274) (xy 169.518173 -48.865925) (xy 169.595216 -48.830741)
			(xy 169.675255 -48.803039) (xy 169.757564 -48.783071) (xy 169.841399 -48.771018) (xy 169.926 -48.766988)
			(xy 170.010601 -48.771018) (xy 170.094436 -48.783071) (xy 170.176745 -48.803039) (xy 170.256784 -48.830741)
			(xy 170.333827 -48.865925) (xy 170.407177 -48.908274) (xy 170.476169 -48.957403) (xy 170.540179 -49.012868)
			(xy 170.598627 -49.074166) (xy 170.650983 -49.140742) (xy 170.696773 -49.211994) (xy 170.735584 -49.287275)
			(xy 170.767063 -49.365905) (xy 170.790924 -49.447172) (xy 170.806953 -49.530338) (xy 170.815004 -49.614652)
			(xy 170.815508 -49.657) (xy 170.815508 -49.657762) (xy 170.8151 -49.695982) (xy 170.808535 -49.772141)
			(xy 170.795451 -49.847453) (xy 170.775944 -49.921363) (xy 170.763438 -49.957482) (xy 170.760852 -49.965798)
			(xy 170.760852 -49.983202) (xy 170.763438 -49.991518) (xy 170.775929 -50.027641) (xy 170.795419 -50.101553)
			(xy 170.808503 -50.176864) (xy 170.815085 -50.253019) (xy 170.815508 -50.291238) (xy 170.815508 -50.292)
			(xy 170.815093 -50.332047) (xy 170.807898 -50.411816) (xy 170.793564 -50.490616) (xy 170.77221 -50.56781)
			(xy 170.744006 -50.642773) (xy 170.709182 -50.7149) (xy 170.668018 -50.783605) (xy 170.620849 -50.848335)
			(xy 170.594782 -50.87874) (xy 170.589017 -50.885829) (xy 170.582505 -50.902886) (xy 170.582082 -50.912014)
			(xy 170.582082 -50.941986) (xy 170.582516 -50.951109) (xy 170.589036 -50.968159) (xy 170.594782 -50.97526)
			(xy 170.62084 -51.005674) (xy 170.668026 -51.070392) (xy 170.709202 -51.139092) (xy 170.744033 -51.211216)
			(xy 170.772237 -51.28618) (xy 170.793586 -51.363377) (xy 170.807906 -51.442181) (xy 170.815081 -51.521953)
			(xy 170.815508 -51.562) (xy 170.815508 -51.562762) (xy 170.8151 -51.600982) (xy 170.808535 -51.677141)
			(xy 170.795451 -51.752453) (xy 170.775944 -51.826363) (xy 170.763438 -51.862482) (xy 170.760852 -51.870798)
			(xy 170.760852 -51.888202) (xy 170.763438 -51.896518) (xy 170.775929 -51.932641) (xy 170.795419 -52.006553)
			(xy 170.808503 -52.081864) (xy 170.815085 -52.158019) (xy 170.815508 -52.196238) (xy 170.815508 -52.197)
			(xy 174.497492 -52.197) (xy 174.497492 -52.196238) (xy 174.4979 -52.158018) (xy 174.504465 -52.081859)
			(xy 174.517549 -52.006547) (xy 174.537056 -51.932637) (xy 174.549562 -51.896518) (xy 174.552148 -51.888202)
			(xy 174.552148 -51.870798) (xy 174.549562 -51.862482) (xy 174.537071 -51.826359) (xy 174.517581 -51.752447)
			(xy 174.504497 -51.677136) (xy 174.497915 -51.600981) (xy 174.497492 -51.562762) (xy 174.497492 -51.562)
			(xy 174.497907 -51.521953) (xy 174.505102 -51.442184) (xy 174.519436 -51.363384) (xy 174.54079 -51.28619)
			(xy 174.568994 -51.211227) (xy 174.603818 -51.1391) (xy 174.644982 -51.070395) (xy 174.692151 -51.005665)
			(xy 174.718218 -50.97526) (xy 174.723983 -50.968171) (xy 174.730495 -50.951114) (xy 174.730918 -50.941986)
			(xy 174.730918 -50.912014) (xy 174.730484 -50.902891) (xy 174.723964 -50.885841) (xy 174.718218 -50.87874)
			(xy 174.69216 -50.848326) (xy 174.644974 -50.783608) (xy 174.603798 -50.714908) (xy 174.568967 -50.642784)
			(xy 174.540763 -50.56782) (xy 174.519414 -50.490623) (xy 174.505094 -50.411819) (xy 174.497919 -50.332047)
			(xy 174.497492 -50.292) (xy 174.497492 -50.291238) (xy 174.4979 -50.253018) (xy 174.504465 -50.176859)
			(xy 174.517549 -50.101547) (xy 174.537056 -50.027637) (xy 174.549562 -49.991518) (xy 174.552148 -49.983202)
			(xy 174.552148 -49.965798) (xy 174.549562 -49.957482) (xy 174.537071 -49.921359) (xy 174.517581 -49.847447)
			(xy 174.504497 -49.772136) (xy 174.497915 -49.695981) (xy 174.497492 -49.657762) (xy 174.497492 -49.657)
			(xy 174.497996 -49.614652) (xy 174.506047 -49.530338) (xy 174.522076 -49.447172) (xy 174.545937 -49.365905)
			(xy 174.577416 -49.287275) (xy 174.616227 -49.211994) (xy 174.662017 -49.140742) (xy 174.714373 -49.074166)
			(xy 174.772821 -49.012868) (xy 174.836831 -48.957403) (xy 174.905823 -48.908274) (xy 174.979173 -48.865925)
			(xy 175.056216 -48.830741) (xy 175.136255 -48.803039) (xy 175.218564 -48.783071) (xy 175.302399 -48.771018)
			(xy 175.387 -48.766988) (xy 175.471601 -48.771018) (xy 175.555436 -48.783071) (xy 175.637745 -48.803039)
			(xy 175.717784 -48.830741) (xy 175.794827 -48.865925) (xy 175.868177 -48.908274) (xy 175.937169 -48.957403)
			(xy 176.001179 -49.012868) (xy 176.059627 -49.074166) (xy 176.111983 -49.140742) (xy 176.157773 -49.211994)
			(xy 176.196584 -49.287275) (xy 176.228063 -49.365905) (xy 176.251924 -49.447172) (xy 176.267953 -49.530338)
			(xy 176.276004 -49.614652) (xy 176.276508 -49.657) (xy 176.276508 -49.657762) (xy 176.2761 -49.695982)
			(xy 176.269535 -49.772141) (xy 176.256451 -49.847453) (xy 176.236944 -49.921363) (xy 176.224438 -49.957482)
			(xy 176.221852 -49.965798) (xy 176.221852 -49.983202) (xy 176.224438 -49.991518) (xy 176.236929 -50.027641)
			(xy 176.256419 -50.101553) (xy 176.269503 -50.176864) (xy 176.276085 -50.253019) (xy 176.276508 -50.291238)
			(xy 176.276508 -50.292) (xy 176.276093 -50.332047) (xy 176.268898 -50.411816) (xy 176.254564 -50.490616)
			(xy 176.23321 -50.56781) (xy 176.205006 -50.642773) (xy 176.170182 -50.7149) (xy 176.129018 -50.783605)
			(xy 176.081849 -50.848335) (xy 176.055782 -50.87874) (xy 176.050017 -50.885829) (xy 176.043505 -50.902886)
			(xy 176.043082 -50.912014) (xy 176.043082 -50.941986) (xy 176.043516 -50.951109) (xy 176.050036 -50.968159)
			(xy 176.055782 -50.97526) (xy 176.08184 -51.005674) (xy 176.129026 -51.070392) (xy 176.170202 -51.139092)
			(xy 176.205033 -51.211216) (xy 176.233237 -51.28618) (xy 176.254586 -51.363377) (xy 176.268906 -51.442181)
			(xy 176.276081 -51.521953) (xy 176.276508 -51.562) (xy 176.276508 -51.562762) (xy 176.2761 -51.600982)
			(xy 176.269535 -51.677141) (xy 176.256451 -51.752453) (xy 176.236944 -51.826363) (xy 176.224438 -51.862482)
			(xy 176.221852 -51.870798) (xy 176.221852 -51.888202) (xy 176.224438 -51.896518) (xy 176.236929 -51.932641)
			(xy 176.256419 -52.006553) (xy 176.269503 -52.081864) (xy 176.276085 -52.158019) (xy 176.276508 -52.196238)
			(xy 176.276508 -52.197) (xy 179.955952 -52.197) (xy 179.955952 -52.196238) (xy 179.956357 -52.158018)
			(xy 179.962922 -52.081859) (xy 179.976007 -52.006546) (xy 179.995515 -51.932637) (xy 180.008022 -51.896518)
			(xy 180.01061 -51.888202) (xy 180.01061 -51.870798) (xy 180.008022 -51.862482) (xy 179.995533 -51.826358)
			(xy 179.976042 -51.752446) (xy 179.962957 -51.677136) (xy 179.956375 -51.600981) (xy 179.955952 -51.562762)
			(xy 179.955952 -51.562) (xy 179.956377 -51.521954) (xy 179.963572 -51.442185) (xy 179.977904 -51.363385)
			(xy 179.999258 -51.286192) (xy 180.02746 -51.211228) (xy 180.062283 -51.139102) (xy 180.103445 -51.070396)
			(xy 180.150612 -51.005665) (xy 180.176678 -50.97526) (xy 180.182439 -50.968167) (xy 180.188954 -50.951113)
			(xy 180.189378 -50.941986) (xy 180.189378 -50.912014) (xy 180.188931 -50.902892) (xy 180.182419 -50.885843)
			(xy 180.176678 -50.87874) (xy 180.150614 -50.848332) (xy 180.103428 -50.783612) (xy 180.062254 -50.714911)
			(xy 180.027424 -50.642786) (xy 179.999221 -50.567821) (xy 179.977874 -50.490624) (xy 179.963554 -50.41182)
			(xy 179.956379 -50.332047) (xy 179.955952 -50.292) (xy 179.955952 -50.291238) (xy 179.956357 -50.253018)
			(xy 179.962922 -50.176859) (xy 179.976007 -50.101546) (xy 179.995515 -50.027637) (xy 180.008022 -49.991518)
			(xy 180.01061 -49.983202) (xy 180.01061 -49.965798) (xy 180.008022 -49.957482) (xy 179.995533 -49.921358)
			(xy 179.976042 -49.847446) (xy 179.962957 -49.772136) (xy 179.956375 -49.695981) (xy 179.955952 -49.657762)
			(xy 179.955952 -49.657) (xy 179.956456 -49.614652) (xy 179.964507 -49.530338) (xy 179.980536 -49.447172)
			(xy 180.004397 -49.365905) (xy 180.035876 -49.287275) (xy 180.074687 -49.211994) (xy 180.120477 -49.140742)
			(xy 180.172833 -49.074166) (xy 180.231281 -49.012868) (xy 180.295291 -48.957403) (xy 180.364283 -48.908274)
			(xy 180.437633 -48.865925) (xy 180.514676 -48.830741) (xy 180.594715 -48.803039) (xy 180.677024 -48.783071)
			(xy 180.760859 -48.771018) (xy 180.84546 -48.766988) (xy 180.930061 -48.771018) (xy 181.013896 -48.783071)
			(xy 181.096205 -48.803039) (xy 181.176244 -48.830741) (xy 181.253287 -48.865925) (xy 181.326637 -48.908274)
			(xy 181.395629 -48.957403) (xy 181.459639 -49.012868) (xy 181.518087 -49.074166) (xy 181.570443 -49.140742)
			(xy 181.616233 -49.211994) (xy 181.655044 -49.287275) (xy 181.686523 -49.365905) (xy 181.710384 -49.447172)
			(xy 181.726413 -49.530338) (xy 181.734464 -49.614652) (xy 181.734968 -49.657) (xy 181.734968 -49.657762)
			(xy 181.734562 -49.695982) (xy 181.727997 -49.772141) (xy 181.714912 -49.847454) (xy 181.695405 -49.921363)
			(xy 181.682898 -49.957482) (xy 181.68031 -49.965798) (xy 181.68031 -49.983202) (xy 181.682898 -49.991518)
			(xy 181.695388 -50.027641) (xy 181.714878 -50.101553) (xy 181.727963 -50.176864) (xy 181.734545 -50.253019)
			(xy 181.734968 -50.291238) (xy 181.734968 -50.292) (xy 181.734538 -50.332046) (xy 181.727343 -50.411815)
			(xy 181.713011 -50.490614) (xy 181.691658 -50.567808) (xy 181.663456 -50.642771) (xy 181.628634 -50.714897)
			(xy 181.587474 -50.783604) (xy 181.540307 -50.848334) (xy 181.514242 -50.87874) (xy 181.508472 -50.885825)
			(xy 181.501964 -50.902886) (xy 181.501542 -50.912014) (xy 181.501542 -50.941986) (xy 181.501985 -50.951108)
			(xy 181.5085 -50.968158) (xy 181.514242 -50.97526) (xy 181.54031 -51.005665) (xy 181.587494 -51.070386)
			(xy 181.628668 -51.139087) (xy 181.663497 -51.211213) (xy 181.691699 -51.286178) (xy 181.713047 -51.363376)
			(xy 181.727366 -51.44218) (xy 181.734541 -51.521953) (xy 181.734968 -51.562) (xy 181.734968 -51.562762)
			(xy 181.734562 -51.600982) (xy 181.727997 -51.677141) (xy 181.714912 -51.752454) (xy 181.695405 -51.826363)
			(xy 181.682898 -51.862482) (xy 181.68031 -51.870798) (xy 181.68031 -51.888202) (xy 181.682898 -51.896518)
			(xy 181.695388 -51.932641) (xy 181.714878 -52.006553) (xy 181.727963 -52.081864) (xy 181.734545 -52.158019)
			(xy 181.734968 -52.196238) (xy 181.734968 -52.197) (xy 185.416952 -52.197) (xy 185.416952 -52.196238)
			(xy 185.417357 -52.158018) (xy 185.423922 -52.081859) (xy 185.437007 -52.006546) (xy 185.456515 -51.932637)
			(xy 185.469022 -51.896518) (xy 185.47161 -51.888202) (xy 185.47161 -51.870798) (xy 185.469022 -51.862482)
			(xy 185.456533 -51.826358) (xy 185.437042 -51.752446) (xy 185.423957 -51.677136) (xy 185.417375 -51.600981)
			(xy 185.416952 -51.562762) (xy 185.416952 -51.562) (xy 185.417377 -51.521954) (xy 185.424572 -51.442185)
			(xy 185.438904 -51.363385) (xy 185.460258 -51.286192) (xy 185.48846 -51.211228) (xy 185.523283 -51.139102)
			(xy 185.564445 -51.070396) (xy 185.611612 -51.005665) (xy 185.637678 -50.97526) (xy 185.643439 -50.968167)
			(xy 185.649954 -50.951113) (xy 185.650378 -50.941986) (xy 185.650378 -50.912014) (xy 185.649931 -50.902892)
			(xy 185.643419 -50.885843) (xy 185.637678 -50.87874) (xy 185.611614 -50.848332) (xy 185.564428 -50.783612)
			(xy 185.523254 -50.714911) (xy 185.488424 -50.642786) (xy 185.460221 -50.567821) (xy 185.438874 -50.490624)
			(xy 185.424554 -50.41182) (xy 185.417379 -50.332047) (xy 185.416952 -50.292) (xy 185.416952 -50.291238)
			(xy 185.417357 -50.253018) (xy 185.423922 -50.176859) (xy 185.437007 -50.101546) (xy 185.456515 -50.027637)
			(xy 185.469022 -49.991518) (xy 185.47161 -49.983202) (xy 185.47161 -49.965798) (xy 185.469022 -49.957482)
			(xy 185.456533 -49.921358) (xy 185.437042 -49.847446) (xy 185.423957 -49.772136) (xy 185.417375 -49.695981)
			(xy 185.416952 -49.657762) (xy 185.416952 -49.657) (xy 185.417456 -49.614652) (xy 185.425507 -49.530338)
			(xy 185.441536 -49.447172) (xy 185.465397 -49.365905) (xy 185.496876 -49.287275) (xy 185.535687 -49.211994)
			(xy 185.581477 -49.140742) (xy 185.633833 -49.074166) (xy 185.692281 -49.012868) (xy 185.756291 -48.957403)
			(xy 185.825283 -48.908274) (xy 185.898633 -48.865925) (xy 185.975676 -48.830741) (xy 186.055715 -48.803039)
			(xy 186.138024 -48.783071) (xy 186.221859 -48.771018) (xy 186.30646 -48.766988) (xy 186.391061 -48.771018)
			(xy 186.474896 -48.783071) (xy 186.557205 -48.803039) (xy 186.637244 -48.830741) (xy 186.714287 -48.865925)
			(xy 186.787637 -48.908274) (xy 186.856629 -48.957403) (xy 186.920639 -49.012868) (xy 186.979087 -49.074166)
			(xy 187.031443 -49.140742) (xy 187.077233 -49.211994) (xy 187.116044 -49.287275) (xy 187.147523 -49.365905)
			(xy 187.171384 -49.447172) (xy 187.187413 -49.530338) (xy 187.195464 -49.614652) (xy 187.195968 -49.657)
			(xy 187.195968 -49.657762) (xy 187.195562 -49.695982) (xy 187.188997 -49.772141) (xy 187.175912 -49.847454)
			(xy 187.156405 -49.921363) (xy 187.143898 -49.957482) (xy 187.14131 -49.965798) (xy 187.14131 -49.983202)
			(xy 187.143898 -49.991518) (xy 187.156388 -50.027641) (xy 187.175878 -50.101553) (xy 187.188963 -50.176864)
			(xy 187.195545 -50.253019) (xy 187.195968 -50.291238) (xy 187.195968 -50.292) (xy 187.195538 -50.332046)
			(xy 187.188343 -50.411815) (xy 187.174011 -50.490614) (xy 187.152658 -50.567808) (xy 187.124456 -50.642771)
			(xy 187.089634 -50.714897) (xy 187.048474 -50.783604) (xy 187.001307 -50.848334) (xy 186.975242 -50.87874)
			(xy 186.969472 -50.885825) (xy 186.962964 -50.902886) (xy 186.962542 -50.912014) (xy 186.962542 -50.941986)
			(xy 186.962985 -50.951108) (xy 186.9695 -50.968158) (xy 186.975242 -50.97526) (xy 187.00131 -51.005665)
			(xy 187.048494 -51.070386) (xy 187.089668 -51.139087) (xy 187.124497 -51.211213) (xy 187.152699 -51.286178)
			(xy 187.174047 -51.363376) (xy 187.188366 -51.44218) (xy 187.195541 -51.521953) (xy 187.195968 -51.562)
			(xy 187.195968 -51.562762) (xy 187.195562 -51.600982) (xy 187.188997 -51.677141) (xy 187.175912 -51.752454)
			(xy 187.156405 -51.826363) (xy 187.143898 -51.862482) (xy 187.14131 -51.870798) (xy 187.14131 -51.888202)
			(xy 187.143898 -51.896518) (xy 187.156388 -51.932641) (xy 187.175878 -52.006553) (xy 187.188963 -52.081864)
			(xy 187.195545 -52.158019) (xy 187.195968 -52.196238) (xy 187.195968 -52.197) (xy 187.195464 -52.239348)
			(xy 187.187413 -52.323662) (xy 187.171384 -52.406828) (xy 187.147523 -52.488095) (xy 187.116044 -52.566725)
			(xy 187.077233 -52.642006) (xy 187.031443 -52.713258) (xy 186.979087 -52.779834) (xy 186.920639 -52.841132)
			(xy 186.856629 -52.896597) (xy 186.787637 -52.945726) (xy 186.714287 -52.988075) (xy 186.637244 -53.023259)
			(xy 186.557205 -53.050961) (xy 186.474896 -53.070929) (xy 186.391061 -53.082982) (xy 186.30646 -53.087013)
			(xy 186.221859 -53.082982) (xy 186.138024 -53.070929) (xy 186.055715 -53.050961) (xy 185.975676 -53.023259)
			(xy 185.898633 -52.988075) (xy 185.825283 -52.945726) (xy 185.756291 -52.896597) (xy 185.692281 -52.841132)
			(xy 185.633833 -52.779834) (xy 185.581477 -52.713258) (xy 185.535687 -52.642006) (xy 185.496876 -52.566725)
			(xy 185.465397 -52.488095) (xy 185.441536 -52.406828) (xy 185.425507 -52.323662) (xy 185.417456 -52.239348)
			(xy 185.416952 -52.197) (xy 181.734968 -52.197) (xy 181.734464 -52.239348) (xy 181.726413 -52.323662)
			(xy 181.710384 -52.406828) (xy 181.686523 -52.488095) (xy 181.655044 -52.566725) (xy 181.616233 -52.642006)
			(xy 181.570443 -52.713258) (xy 181.518087 -52.779834) (xy 181.459639 -52.841132) (xy 181.395629 -52.896597)
			(xy 181.326637 -52.945726) (xy 181.253287 -52.988075) (xy 181.176244 -53.023259) (xy 181.096205 -53.050961)
			(xy 181.013896 -53.070929) (xy 180.930061 -53.082982) (xy 180.84546 -53.087013) (xy 180.760859 -53.082982)
			(xy 180.677024 -53.070929) (xy 180.594715 -53.050961) (xy 180.514676 -53.023259) (xy 180.437633 -52.988075)
			(xy 180.364283 -52.945726) (xy 180.295291 -52.896597) (xy 180.231281 -52.841132) (xy 180.172833 -52.779834)
			(xy 180.120477 -52.713258) (xy 180.074687 -52.642006) (xy 180.035876 -52.566725) (xy 180.004397 -52.488095)
			(xy 179.980536 -52.406828) (xy 179.964507 -52.323662) (xy 179.956456 -52.239348) (xy 179.955952 -52.197)
			(xy 176.276508 -52.197) (xy 176.276004 -52.239348) (xy 176.267953 -52.323662) (xy 176.251924 -52.406828)
			(xy 176.228063 -52.488095) (xy 176.196584 -52.566725) (xy 176.157773 -52.642006) (xy 176.111983 -52.713258)
			(xy 176.059627 -52.779834) (xy 176.001179 -52.841132) (xy 175.937169 -52.896597) (xy 175.868177 -52.945726)
			(xy 175.794827 -52.988075) (xy 175.717784 -53.023259) (xy 175.637745 -53.050961) (xy 175.555436 -53.070929)
			(xy 175.471601 -53.082982) (xy 175.387 -53.087013) (xy 175.302399 -53.082982) (xy 175.218564 -53.070929)
			(xy 175.136255 -53.050961) (xy 175.056216 -53.023259) (xy 174.979173 -52.988075) (xy 174.905823 -52.945726)
			(xy 174.836831 -52.896597) (xy 174.772821 -52.841132) (xy 174.714373 -52.779834) (xy 174.662017 -52.713258)
			(xy 174.616227 -52.642006) (xy 174.577416 -52.566725) (xy 174.545937 -52.488095) (xy 174.522076 -52.406828)
			(xy 174.506047 -52.323662) (xy 174.497996 -52.239348) (xy 174.497492 -52.197) (xy 170.815508 -52.197)
			(xy 170.815004 -52.239348) (xy 170.806953 -52.323662) (xy 170.790924 -52.406828) (xy 170.767063 -52.488095)
			(xy 170.735584 -52.566725) (xy 170.696773 -52.642006) (xy 170.650983 -52.713258) (xy 170.598627 -52.779834)
			(xy 170.540179 -52.841132) (xy 170.476169 -52.896597) (xy 170.407177 -52.945726) (xy 170.333827 -52.988075)
			(xy 170.256784 -53.023259) (xy 170.176745 -53.050961) (xy 170.094436 -53.070929) (xy 170.010601 -53.082982)
			(xy 169.926 -53.087013) (xy 169.841399 -53.082982) (xy 169.757564 -53.070929) (xy 169.675255 -53.050961)
			(xy 169.595216 -53.023259) (xy 169.518173 -52.988075) (xy 169.444823 -52.945726) (xy 169.375831 -52.896597)
			(xy 169.311821 -52.841132) (xy 169.253373 -52.779834) (xy 169.201017 -52.713258) (xy 169.155227 -52.642006)
			(xy 169.116416 -52.566725) (xy 169.084937 -52.488095) (xy 169.061076 -52.406828) (xy 169.045047 -52.323662)
			(xy 169.036996 -52.239348) (xy 169.036492 -52.197) (xy 165.354508 -52.197) (xy 165.354004 -52.239348)
			(xy 165.345953 -52.323662) (xy 165.329924 -52.406828) (xy 165.306063 -52.488095) (xy 165.274584 -52.566725)
			(xy 165.235773 -52.642006) (xy 165.189983 -52.713258) (xy 165.137627 -52.779834) (xy 165.079179 -52.841132)
			(xy 165.015169 -52.896597) (xy 164.946177 -52.945726) (xy 164.872827 -52.988075) (xy 164.795784 -53.023259)
			(xy 164.715745 -53.050961) (xy 164.633436 -53.070929) (xy 164.549601 -53.082982) (xy 164.465 -53.087013)
			(xy 164.380399 -53.082982) (xy 164.296564 -53.070929) (xy 164.214255 -53.050961) (xy 164.134216 -53.023259)
			(xy 164.057173 -52.988075) (xy 163.983823 -52.945726) (xy 163.914831 -52.896597) (xy 163.850821 -52.841132)
			(xy 163.792373 -52.779834) (xy 163.740017 -52.713258) (xy 163.694227 -52.642006) (xy 163.655416 -52.566725)
			(xy 163.623937 -52.488095) (xy 163.600076 -52.406828) (xy 163.584047 -52.323662) (xy 163.575996 -52.239348)
			(xy 163.575492 -52.197) (xy 159.893508 -52.197) (xy 159.893004 -52.239348) (xy 159.884953 -52.323662)
			(xy 159.868924 -52.406828) (xy 159.845063 -52.488095) (xy 159.813584 -52.566725) (xy 159.774773 -52.642006)
			(xy 159.728983 -52.713258) (xy 159.676627 -52.779834) (xy 159.618179 -52.841132) (xy 159.554169 -52.896597)
			(xy 159.485177 -52.945726) (xy 159.411827 -52.988075) (xy 159.334784 -53.023259) (xy 159.254745 -53.050961)
			(xy 159.172436 -53.070929) (xy 159.088601 -53.082982) (xy 159.004 -53.087013) (xy 158.919399 -53.082982)
			(xy 158.835564 -53.070929) (xy 158.753255 -53.050961) (xy 158.673216 -53.023259) (xy 158.596173 -52.988075)
			(xy 158.522823 -52.945726) (xy 158.453831 -52.896597) (xy 158.389821 -52.841132) (xy 158.331373 -52.779834)
			(xy 158.279017 -52.713258) (xy 158.233227 -52.642006) (xy 158.194416 -52.566725) (xy 158.162937 -52.488095)
			(xy 158.139076 -52.406828) (xy 158.123047 -52.323662) (xy 158.114996 -52.239348) (xy 158.114492 -52.197)
			(xy 154.432508 -52.197) (xy 154.432004 -52.239348) (xy 154.423953 -52.323662) (xy 154.407924 -52.406828)
			(xy 154.384063 -52.488095) (xy 154.352584 -52.566725) (xy 154.313773 -52.642006) (xy 154.267983 -52.713258)
			(xy 154.215627 -52.779834) (xy 154.157179 -52.841132) (xy 154.093169 -52.896597) (xy 154.024177 -52.945726)
			(xy 153.950827 -52.988075) (xy 153.873784 -53.023259) (xy 153.793745 -53.050961) (xy 153.711436 -53.070929)
			(xy 153.627601 -53.082982) (xy 153.543 -53.087013) (xy 153.458399 -53.082982) (xy 153.374564 -53.070929)
			(xy 153.292255 -53.050961) (xy 153.212216 -53.023259) (xy 153.135173 -52.988075) (xy 153.061823 -52.945726)
			(xy 152.992831 -52.896597) (xy 152.928821 -52.841132) (xy 152.870373 -52.779834) (xy 152.818017 -52.713258)
			(xy 152.772227 -52.642006) (xy 152.733416 -52.566725) (xy 152.701937 -52.488095) (xy 152.678076 -52.406828)
			(xy 152.662047 -52.323662) (xy 152.653996 -52.239348) (xy 152.653492 -52.197) (xy 109.084442 -52.197)
			(xy 109.086503 -52.208864) (xy 109.093085 -52.285019) (xy 109.093508 -52.323238) (xy 109.093508 -52.324)
			(xy 109.093004 -52.366348) (xy 109.084953 -52.450662) (xy 109.068924 -52.533828) (xy 109.045063 -52.615095)
			(xy 109.013584 -52.693725) (xy 108.974773 -52.769006) (xy 108.928983 -52.840258) (xy 108.876627 -52.906834)
			(xy 108.818179 -52.968132) (xy 108.754169 -53.023597) (xy 108.685177 -53.072726) (xy 108.611827 -53.115075)
			(xy 108.534784 -53.150259) (xy 108.454745 -53.177961) (xy 108.372436 -53.197929) (xy 108.288601 -53.209982)
			(xy 108.204 -53.214013) (xy 108.119399 -53.209982) (xy 108.035564 -53.197929) (xy 107.953255 -53.177961)
			(xy 107.873216 -53.150259) (xy 107.796173 -53.115075) (xy 107.722823 -53.072726) (xy 107.653831 -53.023597)
			(xy 107.589821 -52.968132) (xy 107.531373 -52.906834) (xy 107.479017 -52.840258) (xy 107.433227 -52.769006)
			(xy 107.394416 -52.693725) (xy 107.362937 -52.615095) (xy 107.339076 -52.533828) (xy 107.323047 -52.450662)
			(xy 107.314996 -52.366348) (xy 107.314492 -52.324) (xy 103.632508 -52.324) (xy 103.632004 -52.366348)
			(xy 103.623953 -52.450662) (xy 103.607924 -52.533828) (xy 103.584063 -52.615095) (xy 103.552584 -52.693725)
			(xy 103.513773 -52.769006) (xy 103.467983 -52.840258) (xy 103.415627 -52.906834) (xy 103.357179 -52.968132)
			(xy 103.293169 -53.023597) (xy 103.224177 -53.072726) (xy 103.150827 -53.115075) (xy 103.073784 -53.150259)
			(xy 102.993745 -53.177961) (xy 102.911436 -53.197929) (xy 102.827601 -53.209982) (xy 102.743 -53.214013)
			(xy 102.658399 -53.209982) (xy 102.574564 -53.197929) (xy 102.492255 -53.177961) (xy 102.412216 -53.150259)
			(xy 102.335173 -53.115075) (xy 102.261823 -53.072726) (xy 102.192831 -53.023597) (xy 102.128821 -52.968132)
			(xy 102.070373 -52.906834) (xy 102.018017 -52.840258) (xy 101.972227 -52.769006) (xy 101.933416 -52.693725)
			(xy 101.901937 -52.615095) (xy 101.878076 -52.533828) (xy 101.862047 -52.450662) (xy 101.853996 -52.366348)
			(xy 101.853492 -52.324) (xy 98.171508 -52.324) (xy 98.171004 -52.366348) (xy 98.162953 -52.450662)
			(xy 98.146924 -52.533828) (xy 98.123063 -52.615095) (xy 98.091584 -52.693725) (xy 98.052773 -52.769006)
			(xy 98.006983 -52.840258) (xy 97.954627 -52.906834) (xy 97.896179 -52.968132) (xy 97.832169 -53.023597)
			(xy 97.763177 -53.072726) (xy 97.689827 -53.115075) (xy 97.612784 -53.150259) (xy 97.532745 -53.177961)
			(xy 97.450436 -53.197929) (xy 97.366601 -53.209982) (xy 97.282 -53.214013) (xy 97.197399 -53.209982)
			(xy 97.113564 -53.197929) (xy 97.031255 -53.177961) (xy 96.951216 -53.150259) (xy 96.874173 -53.115075)
			(xy 96.800823 -53.072726) (xy 96.731831 -53.023597) (xy 96.667821 -52.968132) (xy 96.609373 -52.906834)
			(xy 96.557017 -52.840258) (xy 96.511227 -52.769006) (xy 96.472416 -52.693725) (xy 96.440937 -52.615095)
			(xy 96.417076 -52.533828) (xy 96.401047 -52.450662) (xy 96.392996 -52.366348) (xy 96.392492 -52.324)
			(xy 92.710508 -52.324) (xy 92.710004 -52.366348) (xy 92.701953 -52.450662) (xy 92.685924 -52.533828)
			(xy 92.662063 -52.615095) (xy 92.630584 -52.693725) (xy 92.591773 -52.769006) (xy 92.545983 -52.840258)
			(xy 92.493627 -52.906834) (xy 92.435179 -52.968132) (xy 92.371169 -53.023597) (xy 92.302177 -53.072726)
			(xy 92.228827 -53.115075) (xy 92.151784 -53.150259) (xy 92.071745 -53.177961) (xy 91.989436 -53.197929)
			(xy 91.905601 -53.209982) (xy 91.821 -53.214013) (xy 91.736399 -53.209982) (xy 91.652564 -53.197929)
			(xy 91.570255 -53.177961) (xy 91.490216 -53.150259) (xy 91.413173 -53.115075) (xy 91.339823 -53.072726)
			(xy 91.270831 -53.023597) (xy 91.206821 -52.968132) (xy 91.148373 -52.906834) (xy 91.096017 -52.840258)
			(xy 91.050227 -52.769006) (xy 91.011416 -52.693725) (xy 90.979937 -52.615095) (xy 90.956076 -52.533828)
			(xy 90.940047 -52.450662) (xy 90.931996 -52.366348) (xy 90.931492 -52.324) (xy 87.249508 -52.324)
			(xy 87.249004 -52.366348) (xy 87.240953 -52.450662) (xy 87.224924 -52.533828) (xy 87.201063 -52.615095)
			(xy 87.169584 -52.693725) (xy 87.130773 -52.769006) (xy 87.084983 -52.840258) (xy 87.032627 -52.906834)
			(xy 86.974179 -52.968132) (xy 86.910169 -53.023597) (xy 86.841177 -53.072726) (xy 86.767827 -53.115075)
			(xy 86.690784 -53.150259) (xy 86.610745 -53.177961) (xy 86.528436 -53.197929) (xy 86.444601 -53.209982)
			(xy 86.36 -53.214013) (xy 86.275399 -53.209982) (xy 86.191564 -53.197929) (xy 86.109255 -53.177961)
			(xy 86.029216 -53.150259) (xy 85.952173 -53.115075) (xy 85.878823 -53.072726) (xy 85.809831 -53.023597)
			(xy 85.745821 -52.968132) (xy 85.687373 -52.906834) (xy 85.635017 -52.840258) (xy 85.589227 -52.769006)
			(xy 85.550416 -52.693725) (xy 85.518937 -52.615095) (xy 85.495076 -52.533828) (xy 85.479047 -52.450662)
			(xy 85.470996 -52.366348) (xy 85.470492 -52.324) (xy 81.788508 -52.324) (xy 81.788004 -52.366348)
			(xy 81.779953 -52.450662) (xy 81.763924 -52.533828) (xy 81.740063 -52.615095) (xy 81.708584 -52.693725)
			(xy 81.669773 -52.769006) (xy 81.623983 -52.840258) (xy 81.571627 -52.906834) (xy 81.513179 -52.968132)
			(xy 81.449169 -53.023597) (xy 81.380177 -53.072726) (xy 81.306827 -53.115075) (xy 81.229784 -53.150259)
			(xy 81.149745 -53.177961) (xy 81.067436 -53.197929) (xy 80.983601 -53.209982) (xy 80.899 -53.214013)
			(xy 80.814399 -53.209982) (xy 80.730564 -53.197929) (xy 80.648255 -53.177961) (xy 80.568216 -53.150259)
			(xy 80.491173 -53.115075) (xy 80.417823 -53.072726) (xy 80.348831 -53.023597) (xy 80.284821 -52.968132)
			(xy 80.226373 -52.906834) (xy 80.174017 -52.840258) (xy 80.128227 -52.769006) (xy 80.089416 -52.693725)
			(xy 80.057937 -52.615095) (xy 80.034076 -52.533828) (xy 80.018047 -52.450662) (xy 80.009996 -52.366348)
			(xy 80.009492 -52.324) (xy 76.327508 -52.324) (xy 76.327004 -52.366348) (xy 76.318953 -52.450662)
			(xy 76.302924 -52.533828) (xy 76.279063 -52.615095) (xy 76.247584 -52.693725) (xy 76.208773 -52.769006)
			(xy 76.162983 -52.840258) (xy 76.110627 -52.906834) (xy 76.052179 -52.968132) (xy 75.988169 -53.023597)
			(xy 75.919177 -53.072726) (xy 75.845827 -53.115075) (xy 75.768784 -53.150259) (xy 75.688745 -53.177961)
			(xy 75.606436 -53.197929) (xy 75.522601 -53.209982) (xy 75.438 -53.214013) (xy 75.353399 -53.209982)
			(xy 75.269564 -53.197929) (xy 75.187255 -53.177961) (xy 75.107216 -53.150259) (xy 75.030173 -53.115075)
			(xy 74.956823 -53.072726) (xy 74.887831 -53.023597) (xy 74.823821 -52.968132) (xy 74.765373 -52.906834)
			(xy 74.713017 -52.840258) (xy 74.667227 -52.769006) (xy 74.628416 -52.693725) (xy 74.596937 -52.615095)
			(xy 74.573076 -52.533828) (xy 74.557047 -52.450662) (xy 74.548996 -52.366348) (xy 74.548492 -52.324)
			(xy 35.433 -52.324) (xy 35.433 -55.642002) (xy 37.371528 -55.642002) (xy 37.372025 -55.599894) (xy 37.379983 -55.516053)
			(xy 37.395827 -55.43334) (xy 37.419416 -55.352494) (xy 37.450538 -55.274239) (xy 37.488916 -55.199275)
			(xy 37.534205 -55.128272) (xy 37.586001 -55.061867) (xy 37.64384 -55.000653) (xy 37.707204 -54.945178)
			(xy 37.775527 -54.895939) (xy 37.848196 -54.853376) (xy 37.924563 -54.81787) (xy 38.003942 -54.789738)
			(xy 38.085625 -54.769234) (xy 38.127178 -54.7624) (xy 38.13937 -54.760622) (xy 38.159436 -54.746144)
			(xy 38.207442 -54.64937) (xy 38.207188 -54.624732) (xy 38.201092 -54.61381) (xy 38.180677 -54.57486)
			(xy 38.146762 -54.493717) (xy 38.121019 -54.409623) (xy 38.103699 -54.3234) (xy 38.094971 -54.235888)
			(xy 38.094412 -54.191916) (xy 38.094412 -54.1909) (xy 38.094916 -54.148552) (xy 38.102967 -54.064238)
			(xy 38.118996 -53.981072) (xy 38.142857 -53.899805) (xy 38.174336 -53.821175) (xy 38.213147 -53.745894)
			(xy 38.258937 -53.674642) (xy 38.311293 -53.608066) (xy 38.369741 -53.546768) (xy 38.433751 -53.491303)
			(xy 38.502743 -53.442174) (xy 38.576093 -53.399825) (xy 38.653136 -53.364641) (xy 38.733175 -53.336939)
			(xy 38.815484 -53.316971) (xy 38.899319 -53.304918) (xy 38.98392 -53.300888) (xy 39.068521 -53.304918)
			(xy 39.152356 -53.316971) (xy 39.234665 -53.336939) (xy 39.314704 -53.364641) (xy 39.391747 -53.399825)
			(xy 39.465097 -53.442174) (xy 39.534089 -53.491303) (xy 39.598099 -53.546768) (xy 39.656547 -53.608066)
			(xy 39.708903 -53.674642) (xy 39.754693 -53.745894) (xy 39.793504 -53.821175) (xy 39.824983 -53.899805)
			(xy 39.848844 -53.981072) (xy 39.86323 -54.055715) (xy 45.935388 -54.055715) (xy 45.935388 -53.970993)
			(xy 45.943441 -53.886656) (xy 45.959475 -53.803466) (xy 45.983343 -53.722176) (xy 46.014831 -53.643524)
			(xy 46.053653 -53.568221) (xy 46.099456 -53.496949) (xy 46.151827 -53.430353) (xy 46.210292 -53.369038)
			(xy 46.27432 -53.313557) (xy 46.343332 -53.264414) (xy 46.416702 -53.222054) (xy 46.493767 -53.186859)
			(xy 46.573829 -53.15915) (xy 46.656162 -53.139176) (xy 46.740021 -53.127119) (xy 46.824646 -53.123088)
			(xy 46.909271 -53.127119) (xy 46.99313 -53.139176) (xy 47.075463 -53.15915) (xy 47.155525 -53.186859)
			(xy 47.23259 -53.222054) (xy 47.30596 -53.264414) (xy 47.374972 -53.313557) (xy 47.439 -53.369038)
			(xy 47.497465 -53.430353) (xy 47.549836 -53.496949) (xy 47.595639 -53.568221) (xy 47.634461 -53.643524)
			(xy 47.665949 -53.722176) (xy 47.689817 -53.803466) (xy 47.705851 -53.886656) (xy 47.713904 -53.970993)
			(xy 47.714408 -54.013354) (xy 47.713904 -54.055715) (xy 47.705851 -54.140052) (xy 47.689817 -54.223242)
			(xy 47.665949 -54.304532) (xy 47.634461 -54.383184) (xy 47.595639 -54.458487) (xy 47.549836 -54.529759)
			(xy 47.497465 -54.596355) (xy 47.439 -54.65767) (xy 47.374972 -54.713151) (xy 47.30596 -54.762294)
			(xy 47.23259 -54.804654) (xy 47.155525 -54.839849) (xy 47.075463 -54.867558) (xy 46.99313 -54.887532)
			(xy 46.909271 -54.899589) (xy 46.824646 -54.903621) (xy 46.740021 -54.899589) (xy 46.656162 -54.887532)
			(xy 46.573829 -54.867558) (xy 46.493767 -54.839849) (xy 46.416702 -54.804654) (xy 46.343332 -54.762294)
			(xy 46.27432 -54.713151) (xy 46.210292 -54.65767) (xy 46.151827 -54.596355) (xy 46.099456 -54.529759)
			(xy 46.053653 -54.458487) (xy 46.014831 -54.383184) (xy 45.983343 -54.304532) (xy 45.959475 -54.223242)
			(xy 45.943441 -54.140052) (xy 45.935388 -54.055715) (xy 39.86323 -54.055715) (xy 39.864873 -54.064238)
			(xy 39.872924 -54.148552) (xy 39.873428 -54.1909) (xy 39.87297 -54.23301) (xy 39.865012 -54.316852)
			(xy 39.849167 -54.399567) (xy 39.825576 -54.480415) (xy 39.794452 -54.558672) (xy 39.756072 -54.633638)
			(xy 39.710779 -54.704641) (xy 39.65898 -54.771047) (xy 39.601138 -54.832261) (xy 39.537771 -54.887736)
			(xy 39.469444 -54.936974) (xy 39.396771 -54.979536) (xy 39.320401 -55.01504) (xy 39.241018 -55.043169)
			(xy 39.159333 -55.06367) (xy 39.117778 -55.070502) (xy 39.105586 -55.07228) (xy 39.08552 -55.086758)
			(xy 39.037514 -55.183532) (xy 39.037768 -55.20817) (xy 39.043864 -55.219092) (xy 39.06432 -55.258135)
			(xy 39.098296 -55.339473) (xy 39.124061 -55.423772) (xy 39.141362 -55.510206) (xy 39.150031 -55.597927)
			(xy 39.150544 -55.642002) (xy 39.149888 -55.692156) (xy 39.13869 -55.791837) (xy 39.128192 -55.840884)
			(xy 39.126403 -55.851401) (xy 39.130519 -55.872305) (xy 39.142729 -55.889765) (xy 39.15156 -55.895748)
			(xy 39.188993 -55.918893) (xy 39.259542 -55.971521) (xy 39.324556 -56.030851) (xy 39.383399 -56.096306)
			(xy 39.409878 -56.13146) (xy 39.416788 -56.140033) (xy 39.436031 -56.150694) (xy 39.446962 -56.152034)
			(xy 39.488331 -56.155768) (xy 39.570195 -56.169853) (xy 39.65039 -56.191507) (xy 39.728218 -56.220543)
			(xy 39.802999 -56.256707) (xy 39.874084 -56.299685) (xy 39.940853 -56.349102) (xy 40.002725 -56.404528)
			(xy 40.049273 -56.454802) (xy 42.97934 -56.454802) (xy 42.97934 -56.454294) (xy 42.979916 -56.408849)
			(xy 42.989185 -56.318433) (xy 43.007626 -56.229433) (xy 43.035046 -56.142777) (xy 43.07116 -56.05937)
			(xy 43.092878 -56.019446) (xy 43.097838 -56.009355) (xy 43.09942 -55.986953) (xy 43.095926 -55.976266)
			(xy 43.081477 -55.937748) (xy 43.058925 -55.858627) (xy 43.043785 -55.777759) (xy 43.036187 -55.695838)
			(xy 43.035728 -55.654702) (xy 43.035728 -55.65394) (xy 43.03619 -55.612836) (xy 43.043772 -55.53098)
			(xy 43.058875 -55.450172) (xy 43.08137 -55.371102) (xy 43.111064 -55.294446) (xy 43.147706 -55.220856)
			(xy 43.190981 -55.150962) (xy 43.240521 -55.085358) (xy 43.295904 -55.024606) (xy 43.356655 -54.969224)
			(xy 43.422258 -54.919683) (xy 43.492153 -54.876408) (xy 43.565742 -54.839766) (xy 43.642398 -54.810071)
			(xy 43.721468 -54.787576) (xy 43.802276 -54.772473) (xy 43.884132 -54.764891) (xy 43.925236 -54.764432)
			(xy 43.925744 -54.764432) (xy 43.972721 -54.765036) (xy 44.066153 -54.774917) (xy 44.158025 -54.794587)
			(xy 44.202858 -54.808628) (xy 44.213338 -54.811501) (xy 44.234917 -54.80915) (xy 44.244514 -54.804056)
			(xy 44.278856 -54.784226) (xy 44.350406 -54.750021) (xy 44.42472 -54.722329) (xy 44.501207 -54.701372)
			(xy 44.579258 -54.687316) (xy 44.658251 -54.680274) (xy 44.697904 -54.67985) (xy 44.738985 -54.680256)
			(xy 44.820797 -54.687838) (xy 44.90156 -54.702936) (xy 44.980586 -54.725422) (xy 45.0572 -54.755104)
			(xy 45.130748 -54.791728) (xy 45.200603 -54.834983) (xy 45.266168 -54.884498) (xy 45.326886 -54.939853)
			(xy 45.382236 -55.000573) (xy 45.431748 -55.066142) (xy 45.474998 -55.135999) (xy 45.511618 -55.20955)
			(xy 45.541295 -55.286165) (xy 45.563776 -55.365192) (xy 45.578869 -55.445956) (xy 45.586446 -55.527769)
			(xy 45.586904 -55.56885) (xy 45.58637 -55.611928) (xy 45.57804 -55.69768) (xy 45.561453 -55.782224)
			(xy 45.536764 -55.864767) (xy 45.504206 -55.944534) (xy 45.464083 -56.020778) (xy 45.416773 -56.092782)
			(xy 45.369284 -56.151723) (xy 45.799752 -56.151723) (xy 45.799752 -56.067001) (xy 45.807805 -55.982664)
			(xy 45.823839 -55.899474) (xy 45.847707 -55.818184) (xy 45.879195 -55.739532) (xy 45.918017 -55.664229)
			(xy 45.96382 -55.592957) (xy 46.016191 -55.526361) (xy 46.074656 -55.465046) (xy 46.138684 -55.409565)
			(xy 46.207696 -55.360422) (xy 46.281066 -55.318062) (xy 46.358131 -55.282867) (xy 46.438193 -55.255158)
			(xy 46.520526 -55.235184) (xy 46.604385 -55.223127) (xy 46.68901 -55.219096) (xy 46.773635 -55.223127)
			(xy 46.857494 -55.235184) (xy 46.939827 -55.255158) (xy 47.019889 -55.282867) (xy 47.096954 -55.318062)
			(xy 47.170324 -55.360422) (xy 47.239336 -55.409565) (xy 47.303364 -55.465046) (xy 47.361829 -55.526361)
			(xy 47.4142 -55.592957) (xy 47.460003 -55.664229) (xy 47.498825 -55.739532) (xy 47.530313 -55.818184)
			(xy 47.554181 -55.899474) (xy 47.565849 -55.96001) (xy 66.673737 -55.96001) (xy 66.677742 -55.854261)
			(xy 66.689732 -55.749118) (xy 66.709641 -55.645183) (xy 66.737352 -55.543051) (xy 66.772709 -55.443307)
			(xy 66.815507 -55.346523) (xy 66.865503 -55.253253) (xy 66.92241 -55.164032) (xy 66.985901 -55.079369)
			(xy 67.055613 -54.999751) (xy 67.131147 -54.925633) (xy 67.21207 -54.85744) (xy 67.297919 -54.795562)
			(xy 67.388202 -54.740355) (xy 67.482401 -54.692133) (xy 67.579978 -54.651173) (xy 67.680373 -54.617711)
			(xy 67.783011 -54.591937) (xy 67.887304 -54.573999) (xy 67.992655 -54.564) (xy 68.098461 -54.561997)
			(xy 68.204115 -54.568002) (xy 68.309012 -54.581981) (xy 68.412552 -54.603852) (xy 68.514141 -54.633492)
			(xy 68.613198 -54.67073) (xy 68.709155 -54.715352) (xy 68.801462 -54.767104) (xy 68.889591 -54.825689)
			(xy 68.973037 -54.890771) (xy 69.051321 -54.961977) (xy 69.123996 -55.0389) (xy 69.190646 -55.1211)
			(xy 69.250888 -55.208104) (xy 69.304377 -55.299415) (xy 69.350808 -55.39451) (xy 69.389913 -55.492844)
			(xy 69.42147 -55.593855) (xy 69.445297 -55.696962) (xy 69.461258 -55.801576) (xy 69.469262 -55.907098)
			(xy 69.469762 -55.96001) (xy 77.976737 -55.96001) (xy 77.980742 -55.854261) (xy 77.992732 -55.749118)
			(xy 78.012641 -55.645183) (xy 78.040352 -55.543051) (xy 78.075709 -55.443307) (xy 78.118507 -55.346523)
			(xy 78.168503 -55.253253) (xy 78.22541 -55.164032) (xy 78.288901 -55.079369) (xy 78.358613 -54.999751)
			(xy 78.434147 -54.925633) (xy 78.51507 -54.85744) (xy 78.600919 -54.795562) (xy 78.691202 -54.740355)
			(xy 78.785401 -54.692133) (xy 78.882978 -54.651173) (xy 78.983373 -54.617711) (xy 79.086011 -54.591937)
			(xy 79.190304 -54.573999) (xy 79.295655 -54.564) (xy 79.401461 -54.561997) (xy 79.507115 -54.568002)
			(xy 79.612012 -54.581981) (xy 79.715552 -54.603852) (xy 79.817141 -54.633492) (xy 79.916198 -54.67073)
			(xy 80.012155 -54.715352) (xy 80.104462 -54.767104) (xy 80.192591 -54.825689) (xy 80.276037 -54.890771)
			(xy 80.354321 -54.961977) (xy 80.426996 -55.0389) (xy 80.493646 -55.1211) (xy 80.553888 -55.208104)
			(xy 80.607377 -55.299415) (xy 80.653808 -55.39451) (xy 80.692913 -55.492844) (xy 80.72447 -55.593855)
			(xy 80.748297 -55.696962) (xy 80.764258 -55.801576) (xy 80.772262 -55.907098) (xy 80.772762 -55.96001)
			(xy 89.279737 -55.96001) (xy 89.283742 -55.854261) (xy 89.295732 -55.749118) (xy 89.315641 -55.645183)
			(xy 89.343352 -55.543051) (xy 89.378709 -55.443307) (xy 89.421507 -55.346523) (xy 89.471503 -55.253253)
			(xy 89.52841 -55.164032) (xy 89.591901 -55.079369) (xy 89.661613 -54.999751) (xy 89.737147 -54.925633)
			(xy 89.81807 -54.85744) (xy 89.903919 -54.795562) (xy 89.994202 -54.740355) (xy 90.088401 -54.692133)
			(xy 90.185978 -54.651173) (xy 90.286373 -54.617711) (xy 90.389011 -54.591937) (xy 90.493304 -54.573999)
			(xy 90.598655 -54.564) (xy 90.704461 -54.561997) (xy 90.810115 -54.568002) (xy 90.915012 -54.581981)
			(xy 91.018552 -54.603852) (xy 91.120141 -54.633492) (xy 91.219198 -54.67073) (xy 91.315155 -54.715352)
			(xy 91.407462 -54.767104) (xy 91.495591 -54.825689) (xy 91.579037 -54.890771) (xy 91.657321 -54.961977)
			(xy 91.729996 -55.0389) (xy 91.796646 -55.1211) (xy 91.856888 -55.208104) (xy 91.910377 -55.299415)
			(xy 91.956808 -55.39451) (xy 91.995913 -55.492844) (xy 92.02747 -55.593855) (xy 92.051297 -55.696962)
			(xy 92.067258 -55.801576) (xy 92.075262 -55.907098) (xy 92.075762 -55.96001) (xy 107.440737 -55.96001)
			(xy 107.444742 -55.854261) (xy 107.456732 -55.749118) (xy 107.476641 -55.645183) (xy 107.504352 -55.543051)
			(xy 107.539709 -55.443307) (xy 107.582507 -55.346523) (xy 107.632503 -55.253253) (xy 107.68941 -55.164032)
			(xy 107.752901 -55.079369) (xy 107.822613 -54.999751) (xy 107.898147 -54.925633) (xy 107.97907 -54.85744)
			(xy 108.064919 -54.795562) (xy 108.155202 -54.740355) (xy 108.249401 -54.692133) (xy 108.346978 -54.651173)
			(xy 108.447373 -54.617711) (xy 108.550011 -54.591937) (xy 108.654304 -54.573999) (xy 108.759655 -54.564)
			(xy 108.865461 -54.561997) (xy 108.971115 -54.568002) (xy 109.076012 -54.581981) (xy 109.179552 -54.603852)
			(xy 109.281141 -54.633492) (xy 109.380198 -54.67073) (xy 109.476155 -54.715352) (xy 109.568462 -54.767104)
			(xy 109.656591 -54.825689) (xy 109.740037 -54.890771) (xy 109.818321 -54.961977) (xy 109.890996 -55.0389)
			(xy 109.957646 -55.1211) (xy 110.017888 -55.208104) (xy 110.071377 -55.299415) (xy 110.117808 -55.39451)
			(xy 110.156913 -55.492844) (xy 110.18847 -55.593855) (xy 110.212297 -55.696962) (xy 110.228258 -55.801576)
			(xy 110.236262 -55.907098) (xy 110.236762 -55.96001) (xy 118.616737 -55.96001) (xy 118.620742 -55.854261)
			(xy 118.632732 -55.749118) (xy 118.652641 -55.645183) (xy 118.680352 -55.543051) (xy 118.715709 -55.443307)
			(xy 118.758507 -55.346523) (xy 118.808503 -55.253253) (xy 118.86541 -55.164032) (xy 118.928901 -55.079369)
			(xy 118.998613 -54.999751) (xy 119.074147 -54.925633) (xy 119.15507 -54.85744) (xy 119.240919 -54.795562)
			(xy 119.331202 -54.740355) (xy 119.425401 -54.692133) (xy 119.522978 -54.651173) (xy 119.623373 -54.617711)
			(xy 119.726011 -54.591937) (xy 119.830304 -54.573999) (xy 119.935655 -54.564) (xy 120.041461 -54.561997)
			(xy 120.147115 -54.568002) (xy 120.252012 -54.581981) (xy 120.355552 -54.603852) (xy 120.457141 -54.633492)
			(xy 120.556198 -54.67073) (xy 120.652155 -54.715352) (xy 120.744462 -54.767104) (xy 120.832591 -54.825689)
			(xy 120.916037 -54.890771) (xy 120.994321 -54.961977) (xy 121.066996 -55.0389) (xy 121.133646 -55.1211)
			(xy 121.193888 -55.208104) (xy 121.247377 -55.299415) (xy 121.293808 -55.39451) (xy 121.332913 -55.492844)
			(xy 121.36447 -55.593855) (xy 121.388297 -55.696962) (xy 121.404258 -55.801576) (xy 121.412262 -55.907098)
			(xy 121.412762 -55.96001) (xy 129.792737 -55.96001) (xy 129.796742 -55.854261) (xy 129.808732 -55.749118)
			(xy 129.828641 -55.645183) (xy 129.856352 -55.543051) (xy 129.891709 -55.443307) (xy 129.934507 -55.346523)
			(xy 129.984503 -55.253253) (xy 130.04141 -55.164032) (xy 130.104901 -55.079369) (xy 130.174613 -54.999751)
			(xy 130.250147 -54.925633) (xy 130.33107 -54.85744) (xy 130.416919 -54.795562) (xy 130.507202 -54.740355)
			(xy 130.601401 -54.692133) (xy 130.698978 -54.651173) (xy 130.799373 -54.617711) (xy 130.902011 -54.591937)
			(xy 131.006304 -54.573999) (xy 131.111655 -54.564) (xy 131.217461 -54.561997) (xy 131.323115 -54.568002)
			(xy 131.428012 -54.581981) (xy 131.531552 -54.603852) (xy 131.633141 -54.633492) (xy 131.732198 -54.67073)
			(xy 131.828155 -54.715352) (xy 131.920462 -54.767104) (xy 132.008591 -54.825689) (xy 132.092037 -54.890771)
			(xy 132.170321 -54.961977) (xy 132.242996 -55.0389) (xy 132.309646 -55.1211) (xy 132.369888 -55.208104)
			(xy 132.423377 -55.299415) (xy 132.469808 -55.39451) (xy 132.508913 -55.492844) (xy 132.54047 -55.593855)
			(xy 132.564297 -55.696962) (xy 132.580258 -55.801576) (xy 132.588262 -55.907098) (xy 132.588762 -55.96001)
			(xy 145.540737 -55.96001) (xy 145.544742 -55.854261) (xy 145.556732 -55.749118) (xy 145.576641 -55.645183)
			(xy 145.604352 -55.543051) (xy 145.639709 -55.443307) (xy 145.682507 -55.346523) (xy 145.732503 -55.253253)
			(xy 145.78941 -55.164032) (xy 145.852901 -55.079369) (xy 145.922613 -54.999751) (xy 145.998147 -54.925633)
			(xy 146.07907 -54.85744) (xy 146.164919 -54.795562) (xy 146.255202 -54.740355) (xy 146.349401 -54.692133)
			(xy 146.446978 -54.651173) (xy 146.547373 -54.617711) (xy 146.650011 -54.591937) (xy 146.754304 -54.573999)
			(xy 146.859655 -54.564) (xy 146.965461 -54.561997) (xy 147.071115 -54.568002) (xy 147.176012 -54.581981)
			(xy 147.279552 -54.603852) (xy 147.381141 -54.633492) (xy 147.480198 -54.67073) (xy 147.576155 -54.715352)
			(xy 147.668462 -54.767104) (xy 147.756591 -54.825689) (xy 147.840037 -54.890771) (xy 147.918321 -54.961977)
			(xy 147.990996 -55.0389) (xy 148.057646 -55.1211) (xy 148.117888 -55.208104) (xy 148.171377 -55.299415)
			(xy 148.217808 -55.39451) (xy 148.256913 -55.492844) (xy 148.28847 -55.593855) (xy 148.312297 -55.696962)
			(xy 148.328258 -55.801576) (xy 148.336262 -55.907098) (xy 148.336762 -55.96001) (xy 156.716737 -55.96001)
			(xy 156.720742 -55.854261) (xy 156.732732 -55.749118) (xy 156.752641 -55.645183) (xy 156.780352 -55.543051)
			(xy 156.815709 -55.443307) (xy 156.858507 -55.346523) (xy 156.908503 -55.253253) (xy 156.96541 -55.164032)
			(xy 157.028901 -55.079369) (xy 157.098613 -54.999751) (xy 157.174147 -54.925633) (xy 157.25507 -54.85744)
			(xy 157.340919 -54.795562) (xy 157.431202 -54.740355) (xy 157.525401 -54.692133) (xy 157.622978 -54.651173)
			(xy 157.723373 -54.617711) (xy 157.826011 -54.591937) (xy 157.930304 -54.573999) (xy 158.035655 -54.564)
			(xy 158.141461 -54.561997) (xy 158.247115 -54.568002) (xy 158.352012 -54.581981) (xy 158.455552 -54.603852)
			(xy 158.557141 -54.633492) (xy 158.656198 -54.67073) (xy 158.752155 -54.715352) (xy 158.844462 -54.767104)
			(xy 158.932591 -54.825689) (xy 159.016037 -54.890771) (xy 159.094321 -54.961977) (xy 159.166996 -55.0389)
			(xy 159.233646 -55.1211) (xy 159.293888 -55.208104) (xy 159.347377 -55.299415) (xy 159.393808 -55.39451)
			(xy 159.432913 -55.492844) (xy 159.46447 -55.593855) (xy 159.488297 -55.696962) (xy 159.504258 -55.801576)
			(xy 159.512262 -55.907098) (xy 159.512762 -55.96001) (xy 167.892737 -55.96001) (xy 167.896742 -55.854261)
			(xy 167.908732 -55.749118) (xy 167.928641 -55.645183) (xy 167.956352 -55.543051) (xy 167.991709 -55.443307)
			(xy 168.034507 -55.346523) (xy 168.084503 -55.253253) (xy 168.14141 -55.164032) (xy 168.204901 -55.079369)
			(xy 168.274613 -54.999751) (xy 168.350147 -54.925633) (xy 168.43107 -54.85744) (xy 168.516919 -54.795562)
			(xy 168.607202 -54.740355) (xy 168.701401 -54.692133) (xy 168.798978 -54.651173) (xy 168.899373 -54.617711)
			(xy 169.002011 -54.591937) (xy 169.106304 -54.573999) (xy 169.211655 -54.564) (xy 169.317461 -54.561997)
			(xy 169.423115 -54.568002) (xy 169.528012 -54.581981) (xy 169.631552 -54.603852) (xy 169.733141 -54.633492)
			(xy 169.832198 -54.67073) (xy 169.928155 -54.715352) (xy 170.020462 -54.767104) (xy 170.108591 -54.825689)
			(xy 170.192037 -54.890771) (xy 170.270321 -54.961977) (xy 170.342996 -55.0389) (xy 170.409646 -55.1211)
			(xy 170.469888 -55.208104) (xy 170.523377 -55.299415) (xy 170.569808 -55.39451) (xy 170.608913 -55.492844)
			(xy 170.64047 -55.593855) (xy 170.664297 -55.696962) (xy 170.680258 -55.801576) (xy 170.688262 -55.907098)
			(xy 170.688762 -55.96001) (xy 185.540911 -55.96001) (xy 185.544916 -55.854261) (xy 185.556906 -55.749118)
			(xy 185.576815 -55.645183) (xy 185.604526 -55.543051) (xy 185.639883 -55.443307) (xy 185.682681 -55.346523)
			(xy 185.732677 -55.253253) (xy 185.789584 -55.164032) (xy 185.853075 -55.079369) (xy 185.922787 -54.999751)
			(xy 185.998321 -54.925633) (xy 186.079244 -54.85744) (xy 186.165093 -54.795562) (xy 186.255376 -54.740355)
			(xy 186.349575 -54.692133) (xy 186.447152 -54.651173) (xy 186.547547 -54.617711) (xy 186.650185 -54.591937)
			(xy 186.754478 -54.573999) (xy 186.859829 -54.564) (xy 186.965635 -54.561997) (xy 187.071289 -54.568002)
			(xy 187.176186 -54.581981) (xy 187.279726 -54.603852) (xy 187.381315 -54.633492) (xy 187.480372 -54.67073)
			(xy 187.576329 -54.715352) (xy 187.668636 -54.767104) (xy 187.756765 -54.825689) (xy 187.840211 -54.890771)
			(xy 187.918495 -54.961977) (xy 187.99117 -55.0389) (xy 188.05782 -55.1211) (xy 188.118062 -55.208104)
			(xy 188.171551 -55.299415) (xy 188.217982 -55.39451) (xy 188.257087 -55.492844) (xy 188.288644 -55.593855)
			(xy 188.312471 -55.696962) (xy 188.328432 -55.801576) (xy 188.336436 -55.907098) (xy 188.336936 -55.96001)
			(xy 196.716911 -55.96001) (xy 196.720916 -55.854261) (xy 196.732906 -55.749118) (xy 196.752815 -55.645183)
			(xy 196.780526 -55.543051) (xy 196.815883 -55.443307) (xy 196.858681 -55.346523) (xy 196.908677 -55.253253)
			(xy 196.965584 -55.164032) (xy 197.029075 -55.079369) (xy 197.098787 -54.999751) (xy 197.174321 -54.925633)
			(xy 197.255244 -54.85744) (xy 197.341093 -54.795562) (xy 197.431376 -54.740355) (xy 197.525575 -54.692133)
			(xy 197.623152 -54.651173) (xy 197.723547 -54.617711) (xy 197.826185 -54.591937) (xy 197.930478 -54.573999)
			(xy 198.035829 -54.564) (xy 198.141635 -54.561997) (xy 198.247289 -54.568002) (xy 198.352186 -54.581981)
			(xy 198.455726 -54.603852) (xy 198.557315 -54.633492) (xy 198.656372 -54.67073) (xy 198.752329 -54.715352)
			(xy 198.844636 -54.767104) (xy 198.932765 -54.825689) (xy 199.016211 -54.890771) (xy 199.094495 -54.961977)
			(xy 199.16717 -55.0389) (xy 199.23382 -55.1211) (xy 199.294062 -55.208104) (xy 199.347551 -55.299415)
			(xy 199.393982 -55.39451) (xy 199.433087 -55.492844) (xy 199.464644 -55.593855) (xy 199.488471 -55.696962)
			(xy 199.504432 -55.801576) (xy 199.512436 -55.907098) (xy 199.512936 -55.96001) (xy 207.892911 -55.96001)
			(xy 207.896916 -55.854261) (xy 207.908906 -55.749118) (xy 207.928815 -55.645183) (xy 207.956526 -55.543051)
			(xy 207.991883 -55.443307) (xy 208.034681 -55.346523) (xy 208.084677 -55.253253) (xy 208.141584 -55.164032)
			(xy 208.205075 -55.079369) (xy 208.274787 -54.999751) (xy 208.350321 -54.925633) (xy 208.431244 -54.85744)
			(xy 208.517093 -54.795562) (xy 208.607376 -54.740355) (xy 208.701575 -54.692133) (xy 208.799152 -54.651173)
			(xy 208.899547 -54.617711) (xy 209.002185 -54.591937) (xy 209.106478 -54.573999) (xy 209.211829 -54.564)
			(xy 209.317635 -54.561997) (xy 209.423289 -54.568002) (xy 209.528186 -54.581981) (xy 209.631726 -54.603852)
			(xy 209.733315 -54.633492) (xy 209.832372 -54.67073) (xy 209.928329 -54.715352) (xy 210.020636 -54.767104)
			(xy 210.108765 -54.825689) (xy 210.192211 -54.890771) (xy 210.270495 -54.961977) (xy 210.34317 -55.0389)
			(xy 210.40982 -55.1211) (xy 210.470062 -55.208104) (xy 210.523551 -55.299415) (xy 210.569982 -55.39451)
			(xy 210.609087 -55.492844) (xy 210.640644 -55.593855) (xy 210.664471 -55.696962) (xy 210.680432 -55.801576)
			(xy 210.688436 -55.907098) (xy 210.688936 -55.96001) (xy 210.688436 -56.012922) (xy 210.680432 -56.118444)
			(xy 210.664471 -56.223058) (xy 210.640644 -56.326165) (xy 210.609087 -56.427176) (xy 210.569982 -56.52551)
			(xy 210.523551 -56.620605) (xy 210.470062 -56.711916) (xy 210.40982 -56.79892) (xy 210.34317 -56.88112)
			(xy 210.270495 -56.958043) (xy 210.192211 -57.029249) (xy 210.108765 -57.094331) (xy 210.020636 -57.152916)
			(xy 209.928329 -57.204668) (xy 209.832372 -57.24929) (xy 209.733315 -57.286528) (xy 209.631726 -57.316168)
			(xy 209.528186 -57.338039) (xy 209.423289 -57.352018) (xy 209.317635 -57.358023) (xy 209.211829 -57.35602)
			(xy 209.106478 -57.346021) (xy 209.002185 -57.328083) (xy 208.899547 -57.302309) (xy 208.799152 -57.268847)
			(xy 208.701575 -57.227887) (xy 208.607376 -57.179665) (xy 208.517093 -57.124458) (xy 208.431244 -57.06258)
			(xy 208.350321 -56.994387) (xy 208.274787 -56.920269) (xy 208.205075 -56.840651) (xy 208.141584 -56.755988)
			(xy 208.084677 -56.666767) (xy 208.034681 -56.573497) (xy 207.991883 -56.476713) (xy 207.956526 -56.376969)
			(xy 207.928815 -56.274837) (xy 207.908906 -56.170902) (xy 207.896916 -56.065759) (xy 207.892911 -55.96001)
			(xy 199.512936 -55.96001) (xy 199.512436 -56.012922) (xy 199.504432 -56.118444) (xy 199.488471 -56.223058)
			(xy 199.464644 -56.326165) (xy 199.433087 -56.427176) (xy 199.393982 -56.52551) (xy 199.347551 -56.620605)
			(xy 199.294062 -56.711916) (xy 199.23382 -56.79892) (xy 199.16717 -56.88112) (xy 199.094495 -56.958043)
			(xy 199.016211 -57.029249) (xy 198.932765 -57.094331) (xy 198.844636 -57.152916) (xy 198.752329 -57.204668)
			(xy 198.656372 -57.24929) (xy 198.557315 -57.286528) (xy 198.455726 -57.316168) (xy 198.352186 -57.338039)
			(xy 198.247289 -57.352018) (xy 198.141635 -57.358023) (xy 198.035829 -57.35602) (xy 197.930478 -57.346021)
			(xy 197.826185 -57.328083) (xy 197.723547 -57.302309) (xy 197.623152 -57.268847) (xy 197.525575 -57.227887)
			(xy 197.431376 -57.179665) (xy 197.341093 -57.124458) (xy 197.255244 -57.06258) (xy 197.174321 -56.994387)
			(xy 197.098787 -56.920269) (xy 197.029075 -56.840651) (xy 196.965584 -56.755988) (xy 196.908677 -56.666767)
			(xy 196.858681 -56.573497) (xy 196.815883 -56.476713) (xy 196.780526 -56.376969) (xy 196.752815 -56.274837)
			(xy 196.732906 -56.170902) (xy 196.720916 -56.065759) (xy 196.716911 -55.96001) (xy 188.336936 -55.96001)
			(xy 188.336436 -56.012922) (xy 188.328432 -56.118444) (xy 188.312471 -56.223058) (xy 188.288644 -56.326165)
			(xy 188.257087 -56.427176) (xy 188.217982 -56.52551) (xy 188.171551 -56.620605) (xy 188.118062 -56.711916)
			(xy 188.05782 -56.79892) (xy 187.99117 -56.88112) (xy 187.918495 -56.958043) (xy 187.840211 -57.029249)
			(xy 187.756765 -57.094331) (xy 187.668636 -57.152916) (xy 187.576329 -57.204668) (xy 187.480372 -57.24929)
			(xy 187.381315 -57.286528) (xy 187.279726 -57.316168) (xy 187.176186 -57.338039) (xy 187.071289 -57.352018)
			(xy 186.965635 -57.358023) (xy 186.859829 -57.35602) (xy 186.754478 -57.346021) (xy 186.650185 -57.328083)
			(xy 186.547547 -57.302309) (xy 186.447152 -57.268847) (xy 186.349575 -57.227887) (xy 186.255376 -57.179665)
			(xy 186.165093 -57.124458) (xy 186.079244 -57.06258) (xy 185.998321 -56.994387) (xy 185.922787 -56.920269)
			(xy 185.853075 -56.840651) (xy 185.789584 -56.755988) (xy 185.732677 -56.666767) (xy 185.682681 -56.573497)
			(xy 185.639883 -56.476713) (xy 185.604526 -56.376969) (xy 185.576815 -56.274837) (xy 185.556906 -56.170902)
			(xy 185.544916 -56.065759) (xy 185.540911 -55.96001) (xy 170.688762 -55.96001) (xy 170.688262 -56.012922)
			(xy 170.680258 -56.118444) (xy 170.664297 -56.223058) (xy 170.64047 -56.326165) (xy 170.608913 -56.427176)
			(xy 170.569808 -56.52551) (xy 170.523377 -56.620605) (xy 170.469888 -56.711916) (xy 170.409646 -56.79892)
			(xy 170.342996 -56.88112) (xy 170.270321 -56.958043) (xy 170.192037 -57.029249) (xy 170.108591 -57.094331)
			(xy 170.020462 -57.152916) (xy 169.928155 -57.204668) (xy 169.832198 -57.24929) (xy 169.733141 -57.286528)
			(xy 169.631552 -57.316168) (xy 169.528012 -57.338039) (xy 169.423115 -57.352018) (xy 169.317461 -57.358023)
			(xy 169.211655 -57.35602) (xy 169.106304 -57.346021) (xy 169.002011 -57.328083) (xy 168.899373 -57.302309)
			(xy 168.798978 -57.268847) (xy 168.701401 -57.227887) (xy 168.607202 -57.179665) (xy 168.516919 -57.124458)
			(xy 168.43107 -57.06258) (xy 168.350147 -56.994387) (xy 168.274613 -56.920269) (xy 168.204901 -56.840651)
			(xy 168.14141 -56.755988) (xy 168.084503 -56.666767) (xy 168.034507 -56.573497) (xy 167.991709 -56.476713)
			(xy 167.956352 -56.376969) (xy 167.928641 -56.274837) (xy 167.908732 -56.170902) (xy 167.896742 -56.065759)
			(xy 167.892737 -55.96001) (xy 159.512762 -55.96001) (xy 159.512262 -56.012922) (xy 159.504258 -56.118444)
			(xy 159.488297 -56.223058) (xy 159.46447 -56.326165) (xy 159.432913 -56.427176) (xy 159.393808 -56.52551)
			(xy 159.347377 -56.620605) (xy 159.293888 -56.711916) (xy 159.233646 -56.79892) (xy 159.166996 -56.88112)
			(xy 159.094321 -56.958043) (xy 159.016037 -57.029249) (xy 158.932591 -57.094331) (xy 158.844462 -57.152916)
			(xy 158.752155 -57.204668) (xy 158.656198 -57.24929) (xy 158.557141 -57.286528) (xy 158.455552 -57.316168)
			(xy 158.352012 -57.338039) (xy 158.247115 -57.352018) (xy 158.141461 -57.358023) (xy 158.035655 -57.35602)
			(xy 157.930304 -57.346021) (xy 157.826011 -57.328083) (xy 157.723373 -57.302309) (xy 157.622978 -57.268847)
			(xy 157.525401 -57.227887) (xy 157.431202 -57.179665) (xy 157.340919 -57.124458) (xy 157.25507 -57.06258)
			(xy 157.174147 -56.994387) (xy 157.098613 -56.920269) (xy 157.028901 -56.840651) (xy 156.96541 -56.755988)
			(xy 156.908503 -56.666767) (xy 156.858507 -56.573497) (xy 156.815709 -56.476713) (xy 156.780352 -56.376969)
			(xy 156.752641 -56.274837) (xy 156.732732 -56.170902) (xy 156.720742 -56.065759) (xy 156.716737 -55.96001)
			(xy 148.336762 -55.96001) (xy 148.336262 -56.012922) (xy 148.328258 -56.118444) (xy 148.312297 -56.223058)
			(xy 148.28847 -56.326165) (xy 148.256913 -56.427176) (xy 148.217808 -56.52551) (xy 148.171377 -56.620605)
			(xy 148.117888 -56.711916) (xy 148.057646 -56.79892) (xy 147.990996 -56.88112) (xy 147.918321 -56.958043)
			(xy 147.840037 -57.029249) (xy 147.756591 -57.094331) (xy 147.668462 -57.152916) (xy 147.576155 -57.204668)
			(xy 147.480198 -57.24929) (xy 147.381141 -57.286528) (xy 147.279552 -57.316168) (xy 147.176012 -57.338039)
			(xy 147.071115 -57.352018) (xy 146.965461 -57.358023) (xy 146.859655 -57.35602) (xy 146.754304 -57.346021)
			(xy 146.650011 -57.328083) (xy 146.547373 -57.302309) (xy 146.446978 -57.268847) (xy 146.349401 -57.227887)
			(xy 146.255202 -57.179665) (xy 146.164919 -57.124458) (xy 146.07907 -57.06258) (xy 145.998147 -56.994387)
			(xy 145.922613 -56.920269) (xy 145.852901 -56.840651) (xy 145.78941 -56.755988) (xy 145.732503 -56.666767)
			(xy 145.682507 -56.573497) (xy 145.639709 -56.476713) (xy 145.604352 -56.376969) (xy 145.576641 -56.274837)
			(xy 145.556732 -56.170902) (xy 145.544742 -56.065759) (xy 145.540737 -55.96001) (xy 132.588762 -55.96001)
			(xy 132.588262 -56.012922) (xy 132.580258 -56.118444) (xy 132.564297 -56.223058) (xy 132.54047 -56.326165)
			(xy 132.508913 -56.427176) (xy 132.469808 -56.52551) (xy 132.423377 -56.620605) (xy 132.369888 -56.711916)
			(xy 132.309646 -56.79892) (xy 132.242996 -56.88112) (xy 132.170321 -56.958043) (xy 132.092037 -57.029249)
			(xy 132.008591 -57.094331) (xy 131.920462 -57.152916) (xy 131.828155 -57.204668) (xy 131.732198 -57.24929)
			(xy 131.633141 -57.286528) (xy 131.531552 -57.316168) (xy 131.428012 -57.338039) (xy 131.323115 -57.352018)
			(xy 131.217461 -57.358023) (xy 131.111655 -57.35602) (xy 131.006304 -57.346021) (xy 130.902011 -57.328083)
			(xy 130.799373 -57.302309) (xy 130.698978 -57.268847) (xy 130.601401 -57.227887) (xy 130.507202 -57.179665)
			(xy 130.416919 -57.124458) (xy 130.33107 -57.06258) (xy 130.250147 -56.994387) (xy 130.174613 -56.920269)
			(xy 130.104901 -56.840651) (xy 130.04141 -56.755988) (xy 129.984503 -56.666767) (xy 129.934507 -56.573497)
			(xy 129.891709 -56.476713) (xy 129.856352 -56.376969) (xy 129.828641 -56.274837) (xy 129.808732 -56.170902)
			(xy 129.796742 -56.065759) (xy 129.792737 -55.96001) (xy 121.412762 -55.96001) (xy 121.412262 -56.012922)
			(xy 121.404258 -56.118444) (xy 121.388297 -56.223058) (xy 121.36447 -56.326165) (xy 121.332913 -56.427176)
			(xy 121.293808 -56.52551) (xy 121.247377 -56.620605) (xy 121.193888 -56.711916) (xy 121.133646 -56.79892)
			(xy 121.066996 -56.88112) (xy 120.994321 -56.958043) (xy 120.916037 -57.029249) (xy 120.832591 -57.094331)
			(xy 120.744462 -57.152916) (xy 120.652155 -57.204668) (xy 120.556198 -57.24929) (xy 120.457141 -57.286528)
			(xy 120.355552 -57.316168) (xy 120.252012 -57.338039) (xy 120.147115 -57.352018) (xy 120.041461 -57.358023)
			(xy 119.935655 -57.35602) (xy 119.830304 -57.346021) (xy 119.726011 -57.328083) (xy 119.623373 -57.302309)
			(xy 119.522978 -57.268847) (xy 119.425401 -57.227887) (xy 119.331202 -57.179665) (xy 119.240919 -57.124458)
			(xy 119.15507 -57.06258) (xy 119.074147 -56.994387) (xy 118.998613 -56.920269) (xy 118.928901 -56.840651)
			(xy 118.86541 -56.755988) (xy 118.808503 -56.666767) (xy 118.758507 -56.573497) (xy 118.715709 -56.476713)
			(xy 118.680352 -56.376969) (xy 118.652641 -56.274837) (xy 118.632732 -56.170902) (xy 118.620742 -56.065759)
			(xy 118.616737 -55.96001) (xy 110.236762 -55.96001) (xy 110.236262 -56.012922) (xy 110.228258 -56.118444)
			(xy 110.212297 -56.223058) (xy 110.18847 -56.326165) (xy 110.156913 -56.427176) (xy 110.117808 -56.52551)
			(xy 110.071377 -56.620605) (xy 110.017888 -56.711916) (xy 109.957646 -56.79892) (xy 109.890996 -56.88112)
			(xy 109.818321 -56.958043) (xy 109.740037 -57.029249) (xy 109.656591 -57.094331) (xy 109.568462 -57.152916)
			(xy 109.476155 -57.204668) (xy 109.380198 -57.24929) (xy 109.281141 -57.286528) (xy 109.179552 -57.316168)
			(xy 109.076012 -57.338039) (xy 108.971115 -57.352018) (xy 108.865461 -57.358023) (xy 108.759655 -57.35602)
			(xy 108.654304 -57.346021) (xy 108.550011 -57.328083) (xy 108.447373 -57.302309) (xy 108.346978 -57.268847)
			(xy 108.249401 -57.227887) (xy 108.155202 -57.179665) (xy 108.064919 -57.124458) (xy 107.97907 -57.06258)
			(xy 107.898147 -56.994387) (xy 107.822613 -56.920269) (xy 107.752901 -56.840651) (xy 107.68941 -56.755988)
			(xy 107.632503 -56.666767) (xy 107.582507 -56.573497) (xy 107.539709 -56.476713) (xy 107.504352 -56.376969)
			(xy 107.476641 -56.274837) (xy 107.456732 -56.170902) (xy 107.444742 -56.065759) (xy 107.440737 -55.96001)
			(xy 92.075762 -55.96001) (xy 92.075262 -56.012922) (xy 92.067258 -56.118444) (xy 92.051297 -56.223058)
			(xy 92.02747 -56.326165) (xy 91.995913 -56.427176) (xy 91.956808 -56.52551) (xy 91.910377 -56.620605)
			(xy 91.856888 -56.711916) (xy 91.796646 -56.79892) (xy 91.729996 -56.88112) (xy 91.657321 -56.958043)
			(xy 91.579037 -57.029249) (xy 91.495591 -57.094331) (xy 91.407462 -57.152916) (xy 91.315155 -57.204668)
			(xy 91.219198 -57.24929) (xy 91.120141 -57.286528) (xy 91.018552 -57.316168) (xy 90.915012 -57.338039)
			(xy 90.810115 -57.352018) (xy 90.704461 -57.358023) (xy 90.598655 -57.35602) (xy 90.493304 -57.346021)
			(xy 90.389011 -57.328083) (xy 90.286373 -57.302309) (xy 90.185978 -57.268847) (xy 90.088401 -57.227887)
			(xy 89.994202 -57.179665) (xy 89.903919 -57.124458) (xy 89.81807 -57.06258) (xy 89.737147 -56.994387)
			(xy 89.661613 -56.920269) (xy 89.591901 -56.840651) (xy 89.52841 -56.755988) (xy 89.471503 -56.666767)
			(xy 89.421507 -56.573497) (xy 89.378709 -56.476713) (xy 89.343352 -56.376969) (xy 89.315641 -56.274837)
			(xy 89.295732 -56.170902) (xy 89.283742 -56.065759) (xy 89.279737 -55.96001) (xy 80.772762 -55.96001)
			(xy 80.772262 -56.012922) (xy 80.764258 -56.118444) (xy 80.748297 -56.223058) (xy 80.72447 -56.326165)
			(xy 80.692913 -56.427176) (xy 80.653808 -56.52551) (xy 80.607377 -56.620605) (xy 80.553888 -56.711916)
			(xy 80.493646 -56.79892) (xy 80.426996 -56.88112) (xy 80.354321 -56.958043) (xy 80.276037 -57.029249)
			(xy 80.192591 -57.094331) (xy 80.104462 -57.152916) (xy 80.012155 -57.204668) (xy 79.916198 -57.24929)
			(xy 79.817141 -57.286528) (xy 79.715552 -57.316168) (xy 79.612012 -57.338039) (xy 79.507115 -57.352018)
			(xy 79.401461 -57.358023) (xy 79.295655 -57.35602) (xy 79.190304 -57.346021) (xy 79.086011 -57.328083)
			(xy 78.983373 -57.302309) (xy 78.882978 -57.268847) (xy 78.785401 -57.227887) (xy 78.691202 -57.179665)
			(xy 78.600919 -57.124458) (xy 78.51507 -57.06258) (xy 78.434147 -56.994387) (xy 78.358613 -56.920269)
			(xy 78.288901 -56.840651) (xy 78.22541 -56.755988) (xy 78.168503 -56.666767) (xy 78.118507 -56.573497)
			(xy 78.075709 -56.476713) (xy 78.040352 -56.376969) (xy 78.012641 -56.274837) (xy 77.992732 -56.170902)
			(xy 77.980742 -56.065759) (xy 77.976737 -55.96001) (xy 69.469762 -55.96001) (xy 69.469262 -56.012922)
			(xy 69.461258 -56.118444) (xy 69.445297 -56.223058) (xy 69.42147 -56.326165) (xy 69.389913 -56.427176)
			(xy 69.350808 -56.52551) (xy 69.304377 -56.620605) (xy 69.250888 -56.711916) (xy 69.190646 -56.79892)
			(xy 69.123996 -56.88112) (xy 69.051321 -56.958043) (xy 68.973037 -57.029249) (xy 68.889591 -57.094331)
			(xy 68.801462 -57.152916) (xy 68.709155 -57.204668) (xy 68.613198 -57.24929) (xy 68.514141 -57.286528)
			(xy 68.412552 -57.316168) (xy 68.309012 -57.338039) (xy 68.204115 -57.352018) (xy 68.098461 -57.358023)
			(xy 67.992655 -57.35602) (xy 67.887304 -57.346021) (xy 67.783011 -57.328083) (xy 67.680373 -57.302309)
			(xy 67.579978 -57.268847) (xy 67.482401 -57.227887) (xy 67.388202 -57.179665) (xy 67.297919 -57.124458)
			(xy 67.21207 -57.06258) (xy 67.131147 -56.994387) (xy 67.055613 -56.920269) (xy 66.985901 -56.840651)
			(xy 66.92241 -56.755988) (xy 66.865503 -56.666767) (xy 66.815507 -56.573497) (xy 66.772709 -56.476713)
			(xy 66.737352 -56.376969) (xy 66.709641 -56.274837) (xy 66.689732 -56.170902) (xy 66.677742 -56.065759)
			(xy 66.673737 -55.96001) (xy 47.565849 -55.96001) (xy 47.570215 -55.982664) (xy 47.578268 -56.067001)
			(xy 47.578772 -56.109362) (xy 47.578268 -56.151723) (xy 47.570215 -56.23606) (xy 47.554181 -56.31925)
			(xy 47.530313 -56.40054) (xy 47.498825 -56.479192) (xy 47.460003 -56.554495) (xy 47.4142 -56.625767)
			(xy 47.361829 -56.692363) (xy 47.303364 -56.753678) (xy 47.239336 -56.809159) (xy 47.170324 -56.858302)
			(xy 47.096954 -56.900662) (xy 47.019889 -56.935857) (xy 46.939827 -56.963566) (xy 46.857494 -56.98354)
			(xy 46.773635 -56.995597) (xy 46.68901 -56.999629) (xy 46.604385 -56.995597) (xy 46.520526 -56.98354)
			(xy 46.438193 -56.963566) (xy 46.358131 -56.935857) (xy 46.281066 -56.900662) (xy 46.207696 -56.858302)
			(xy 46.138684 -56.809159) (xy 46.074656 -56.753678) (xy 46.016191 -56.692363) (xy 45.96382 -56.625767)
			(xy 45.918017 -56.554495) (xy 45.879195 -56.479192) (xy 45.847707 -56.40054) (xy 45.823839 -56.31925)
			(xy 45.807805 -56.23606) (xy 45.799752 -56.151723) (xy 45.369284 -56.151723) (xy 45.362719 -56.159871)
			(xy 45.302427 -56.221416) (xy 45.236465 -56.27684) (xy 45.16545 -56.325622) (xy 45.090048 -56.367305)
			(xy 45.010968 -56.401498) (xy 44.928951 -56.42788) (xy 44.844766 -56.446203) (xy 44.802044 -56.451754)
			(xy 44.793195 -56.453171) (xy 44.777202 -56.461221) (xy 44.764992 -56.474316) (xy 44.758078 -56.490831)
			(xy 44.75734 -56.49976) (xy 44.754638 -56.541945) (xy 44.742374 -56.625587) (xy 44.722231 -56.707688)
			(xy 44.694389 -56.787507) (xy 44.6591 -56.864325) (xy 44.616681 -56.937448) (xy 44.567517 -57.006217)
			(xy 44.51205 -57.070011) (xy 44.45078 -57.128255) (xy 44.384261 -57.180423) (xy 44.313092 -57.226045)
			(xy 44.237917 -57.264709) (xy 44.159412 -57.296066) (xy 44.078286 -57.319834) (xy 43.995271 -57.335797)
			(xy 43.911116 -57.343813) (xy 43.868848 -57.34431) (xy 43.827746 -57.343802) (xy 43.745891 -57.336221)
			(xy 43.665086 -57.32112) (xy 43.586018 -57.298627) (xy 43.509363 -57.268935) (xy 43.435776 -57.232296)
			(xy 43.365882 -57.189023) (xy 43.30028 -57.139486) (xy 43.239528 -57.084107) (xy 43.184146 -57.023359)
			(xy 43.134605 -56.957759) (xy 43.091328 -56.887868) (xy 43.054685 -56.814282) (xy 43.024989 -56.737629)
			(xy 43.002491 -56.658563) (xy 42.987386 -56.577758) (xy 42.9798 -56.495904) (xy 42.97934 -56.454802)
			(xy 40.049273 -56.454802) (xy 40.05916 -56.465481) (xy 40.109668 -56.531428) (xy 40.153809 -56.601797)
			(xy 40.191198 -56.675974) (xy 40.221509 -56.753314) (xy 40.244479 -56.833142) (xy 40.259907 -56.914764)
			(xy 40.267659 -56.997468) (xy 40.268144 -57.039002) (xy 40.268144 -57.03951) (xy 40.267634 -57.083274)
			(xy 40.259058 -57.170381) (xy 40.241961 -57.256222) (xy 40.216507 -57.339968) (xy 40.182945 -57.420805)
			(xy 40.162734 -57.459626) (xy 40.157403 -57.470978) (xy 40.157404 -57.496026) (xy 40.162734 -57.507378)
			(xy 40.182945 -57.546255) (xy 40.216517 -57.627194) (xy 40.241974 -57.711041) (xy 40.25907 -57.796983)
			(xy 40.26764 -57.884189) (xy 40.268144 -57.928002) (xy 40.267644 -57.971817) (xy 40.259099 -58.059028)
			(xy 40.242014 -58.144974) (xy 40.216553 -58.228823) (xy 40.182965 -58.309758) (xy 40.162734 -58.348626)
			(xy 40.157403 -58.359978) (xy 40.157404 -58.385026) (xy 40.162734 -58.396378) (xy 40.182923 -58.435209)
			(xy 40.216465 -58.516051) (xy 40.241912 -58.599794) (xy 40.259018 -58.685631) (xy 40.267617 -58.772732)
			(xy 40.268144 -58.816494) (xy 40.268144 -58.817002) (xy 40.267689 -58.858109) (xy 40.260105 -58.939973)
			(xy 40.245 -59.020789) (xy 40.222505 -59.099866) (xy 40.19281 -59.17653) (xy 40.156169 -59.250129)
			(xy 40.112895 -59.320033) (xy 40.063357 -59.385647) (xy 40.007977 -59.446411) (xy 39.947227 -59.501807)
			(xy 39.881626 -59.551363) (xy 39.811733 -59.594655) (xy 39.738145 -59.631315) (xy 39.661488 -59.66103)
			(xy 39.582416 -59.683546) (xy 39.501605 -59.698672) (xy 39.419743 -59.706279) (xy 39.378636 -59.706764)
			(xy 39.336925 -59.706314) (xy 39.25387 -59.698512) (xy 39.17191 -59.682965) (xy 39.091767 -59.659809)
			(xy 39.014146 -59.629247) (xy 38.939728 -59.591549) (xy 38.869169 -59.547045) (xy 38.803089 -59.496128)
			(xy 38.742069 -59.439245) (xy 38.686646 -59.376897) (xy 38.661594 -59.343544) (xy 38.654652 -59.335001)
			(xy 38.635433 -59.324324) (xy 38.62451 -59.32297) (xy 38.583139 -59.319256) (xy 38.501275 -59.305169)
			(xy 38.42108 -59.283512) (xy 38.343252 -59.254474) (xy 38.268471 -59.218308) (xy 38.197386 -59.175329)
			(xy 38.130618 -59.12591) (xy 38.068746 -59.070482) (xy 38.012311 -59.009529) (xy 37.961804 -58.94358)
			(xy 37.917663 -58.873211) (xy 37.880275 -58.799033) (xy 37.849964 -58.721692) (xy 37.826994 -58.641864)
			(xy 37.811565 -58.560241) (xy 37.803813 -58.477536) (xy 37.803328 -58.436002) (xy 37.803328 -58.435494)
			(xy 37.803843 -58.39173) (xy 37.812418 -58.304624) (xy 37.829515 -58.218782) (xy 37.854967 -58.135037)
			(xy 37.888528 -58.054199) (xy 37.908738 -58.015378) (xy 37.914061 -58.004024) (xy 37.914062 -57.978979)
			(xy 37.908738 -57.967626) (xy 37.888526 -57.92875) (xy 37.854955 -57.84781) (xy 37.829498 -57.763963)
			(xy 37.812402 -57.678021) (xy 37.803832 -57.590815) (xy 37.803328 -57.547002) (xy 37.803821 -57.503187)
			(xy 37.812366 -57.415976) (xy 37.829453 -57.330029) (xy 37.854915 -57.24618) (xy 37.888506 -57.165245)
			(xy 37.908738 -57.126378) (xy 37.914061 -57.115024) (xy 37.914062 -57.089979) (xy 37.908738 -57.078626)
			(xy 37.888526 -57.03975) (xy 37.854955 -56.95881) (xy 37.829498 -56.874963) (xy 37.812402 -56.789021)
			(xy 37.803832 -56.701815) (xy 37.803328 -56.658002) (xy 37.803969 -56.607847) (xy 37.815177 -56.508167)
			(xy 37.82568 -56.45912) (xy 37.827479 -56.448604) (xy 37.823362 -56.427696) (xy 37.811147 -56.410236)
			(xy 37.802312 -56.404256) (xy 37.766912 -56.382369) (xy 37.699929 -56.332962) (xy 37.637853 -56.277515)
			(xy 37.581226 -56.216513) (xy 37.530544 -56.15049) (xy 37.48625 -56.080021) (xy 37.44873 -56.005724)
			(xy 37.418313 -55.928248) (xy 37.395264 -55.84827) (xy 37.379785 -55.766488) (xy 37.372012 -55.683619)
			(xy 37.371528 -55.642002) (xy 35.433 -55.642002) (xy 35.433 -56.918606) (xy 35.433424 -56.928676)
			(xy 35.44114 -56.947279) (xy 35.447986 -56.954674) (xy 38.79977 -60.306458) (xy 38.806503 -60.312705)
			(xy 38.823187 -60.320351) (xy 38.841496 -60.321612) (xy 38.859071 -60.316328) (xy 38.866572 -60.31103)
			(xy 38.899761 -60.286326) (xy 38.969941 -60.242494) (xy 39.043887 -60.205367) (xy 39.12096 -60.175267)
			(xy 39.200496 -60.152453) (xy 39.281806 -60.137123) (xy 39.364189 -60.129409) (xy 39.40556 -60.128912)
			(xy 39.446664 -60.12937) (xy 39.528522 -60.136952) (xy 39.60933 -60.152055) (xy 39.688401 -60.17455)
			(xy 39.765059 -60.204244) (xy 39.838649 -60.240886) (xy 39.908545 -60.284161) (xy 39.974149 -60.333701)
			(xy 40.034902 -60.389084) (xy 40.090286 -60.449836) (xy 40.139828 -60.515439) (xy 40.183105 -60.585333)
			(xy 40.219748 -60.658923) (xy 40.249444 -60.73558) (xy 40.271941 -60.81465) (xy 40.287045 -60.895459)
			(xy 40.294629 -60.977316) (xy 40.295068 -61.01842) (xy 40.294542 -61.061908) (xy 40.286057 -61.148469)
			(xy 40.26917 -61.233789) (xy 40.244042 -61.317056) (xy 40.210913 -61.397476) (xy 40.170098 -61.47428)
			(xy 40.121988 -61.546738) (xy 40.094916 -61.580776) (xy 40.089106 -61.588513) (xy 40.083222 -61.606928)
			(xy 40.08455 -61.626216) (xy 40.088312 -61.635132) (xy 40.103623 -61.668151) (xy 40.125676 -61.737511)
			(xy 40.132254 -61.773308) (xy 40.136318 -61.786516) (xy 40.152191 -61.821756) (xy 40.178489 -61.89444)
			(xy 40.198392 -61.969129) (xy 40.21175 -62.045261) (xy 40.218462 -62.122264) (xy 40.218868 -62.160912)
			(xy 40.218868 -62.161674) (xy 40.218275 -62.207897) (xy 40.213323 -62.2554) (xy 47.309532 -62.2554)
			(xy 47.309532 -62.254892) (xy 47.310135 -62.20856) (xy 47.319807 -62.116402) (xy 47.339003 -62.025748)
			(xy 47.367516 -61.937579) (xy 47.385732 -61.894974) (xy 47.389541 -61.885032) (xy 47.389541 -61.863768)
			(xy 47.385732 -61.853826) (xy 47.367506 -61.811225) (xy 47.33899 -61.723056) (xy 47.319799 -61.632401)
			(xy 47.31014 -61.54024) (xy 47.309532 -61.493908) (xy 47.309532 -61.4934) (xy 47.309952 -61.452296)
			(xy 47.317538 -61.370438) (xy 47.332644 -61.289629) (xy 47.355142 -61.210559) (xy 47.38484 -61.133902)
			(xy 47.421485 -61.060312) (xy 47.464763 -60.990417) (xy 47.514306 -60.924814) (xy 47.569691 -60.864063)
			(xy 47.630445 -60.80868) (xy 47.69605 -60.75914) (xy 47.765947 -60.715865) (xy 47.839538 -60.679224)
			(xy 47.916197 -60.649529) (xy 47.995268 -60.627035) (xy 48.076077 -60.611932) (xy 48.157936 -60.60435)
			(xy 48.19904 -60.603892) (xy 48.199548 -60.603892) (xy 48.245879 -60.604519) (xy 48.338037 -60.614184)
			(xy 48.428691 -60.633374) (xy 48.51686 -60.66188) (xy 48.559466 -60.680092) (xy 48.569408 -60.683898)
			(xy 48.590672 -60.683898) (xy 48.600614 -60.680092) (xy 48.643271 -60.661834) (xy 48.731565 -60.633293)
			(xy 48.822352 -60.614104) (xy 48.914643 -60.604475) (xy 48.96104 -60.603892) (xy 49.007435 -60.604496)
			(xy 49.099723 -60.614135) (xy 49.190507 -60.633325) (xy 49.278801 -60.661857) (xy 49.321466 -60.680092)
			(xy 49.331408 -60.683898) (xy 49.352672 -60.683898) (xy 49.362614 -60.680092) (xy 49.405271 -60.661834)
			(xy 49.493565 -60.633293) (xy 49.584352 -60.614104) (xy 49.676643 -60.604475) (xy 49.72304 -60.603892)
			(xy 49.769435 -60.604496) (xy 49.861723 -60.614135) (xy 49.952507 -60.633325) (xy 50.040801 -60.661857)
			(xy 50.083466 -60.680092) (xy 50.093408 -60.683898) (xy 50.114672 -60.683898) (xy 50.124614 -60.680092)
			(xy 50.167271 -60.661834) (xy 50.255565 -60.633293) (xy 50.346352 -60.614104) (xy 50.438643 -60.604475)
			(xy 50.48504 -60.603892) (xy 50.531435 -60.604496) (xy 50.623723 -60.614135) (xy 50.714507 -60.633325)
			(xy 50.802801 -60.661857) (xy 50.845466 -60.680092) (xy 50.855408 -60.683898) (xy 50.876672 -60.683898)
			(xy 50.886614 -60.680092) (xy 50.929211 -60.661857) (xy 51.017381 -60.633343) (xy 51.108038 -60.614154)
			(xy 51.200199 -60.604498) (xy 51.246532 -60.603892) (xy 51.24704 -60.603892) (xy 51.288143 -60.604328)
			(xy 51.369998 -60.611917) (xy 51.450804 -60.627026) (xy 51.529872 -60.649525) (xy 51.606526 -60.679224)
			(xy 51.680113 -60.715869) (xy 51.750005 -60.759147) (xy 51.815606 -60.808689) (xy 51.876355 -60.864073)
			(xy 51.931736 -60.924825) (xy 51.981275 -60.990428) (xy 52.02455 -61.060322) (xy 52.061192 -61.133911)
			(xy 52.090887 -61.210566) (xy 52.113384 -61.289634) (xy 52.128489 -61.370441) (xy 52.136073 -61.452297)
			(xy 52.136548 -61.4934) (xy 52.136548 -61.493908) (xy 52.135939 -61.54024) (xy 52.126268 -61.632397)
			(xy 52.107073 -61.723052) (xy 52.078562 -61.81122) (xy 52.060348 -61.853826) (xy 52.05654 -61.863768)
			(xy 52.05654 -61.885032) (xy 52.060348 -61.894974) (xy 52.078573 -61.937576) (xy 52.107089 -62.025744)
			(xy 52.126281 -62.1164) (xy 52.13594 -62.20856) (xy 52.136548 -62.254892) (xy 52.136548 -62.2554)
			(xy 52.136033 -62.296501) (xy 52.128449 -62.378353) (xy 52.113345 -62.459156) (xy 52.090849 -62.538221)
			(xy 52.061155 -62.614873) (xy 52.024515 -62.688458) (xy 51.981242 -62.758349) (xy 51.931705 -62.823949)
			(xy 51.894284 -62.865) (xy 60.705492 -62.865) (xy 60.705492 -62.864746) (xy 60.705976 -62.82326)
			(xy 60.71375 -62.740651) (xy 60.729179 -62.659125) (xy 60.752129 -62.579388) (xy 60.782401 -62.502134)
			(xy 60.819731 -62.428033) (xy 60.863796 -62.357727) (xy 60.888626 -62.324488) (xy 60.894965 -62.315288)
			(xy 60.899791 -62.2935) (xy 60.894965 -62.271712) (xy 60.888626 -62.262512) (xy 60.863786 -62.229279)
			(xy 60.8197 -62.158983) (xy 60.782357 -62.084885) (xy 60.752082 -62.007629) (xy 60.729138 -61.927888)
			(xy 60.713726 -61.846356) (xy 60.705978 -61.763742) (xy 60.705492 -61.722254) (xy 60.705492 -61.722)
			(xy 60.706009 -61.680858) (xy 60.713624 -61.598926) (xy 60.72877 -61.518046) (xy 60.751319 -61.438911)
			(xy 60.781077 -61.362195) (xy 60.81779 -61.288554) (xy 60.861145 -61.218617) (xy 60.910772 -61.152982)
			(xy 60.966246 -61.092208) (xy 61.027093 -61.036815) (xy 61.092795 -60.987276) (xy 61.16279 -60.944014)
			(xy 61.236479 -60.907398) (xy 61.313235 -60.877743) (xy 61.3924 -60.855299) (xy 61.473299 -60.840261)
			(xy 61.514228 -60.836048) (xy 61.514482 -60.836048) (xy 61.524785 -60.834611) (xy 61.54302 -60.824644)
			(xy 61.549788 -60.816744) (xy 61.601858 -60.749688) (xy 61.607192 -60.729368) (xy 61.605414 -60.718954)
			(xy 61.600256 -60.684197) (xy 61.594792 -60.614137) (xy 61.594492 -60.579) (xy 61.595075 -60.532604)
			(xy 61.60472 -60.440316) (xy 61.623916 -60.349532) (xy 61.652454 -60.261239) (xy 61.670692 -60.218574)
			(xy 61.674498 -60.208632) (xy 61.674498 -60.187368) (xy 61.670692 -60.177426) (xy 61.65247 -60.134823)
			(xy 61.623952 -60.046656) (xy 61.60476 -59.956) (xy 61.5951 -59.86384) (xy 61.594492 -59.817508)
			(xy 61.594492 -59.817) (xy 61.594996 -59.774652) (xy 61.603047 -59.690338) (xy 61.619076 -59.607172)
			(xy 61.642937 -59.525905) (xy 61.674416 -59.447275) (xy 61.713227 -59.371994) (xy 61.759017 -59.300742)
			(xy 61.811373 -59.234166) (xy 61.869821 -59.172868) (xy 61.933831 -59.117403) (xy 62.002823 -59.068274)
			(xy 62.076173 -59.025925) (xy 62.153216 -58.990741) (xy 62.233255 -58.963039) (xy 62.315564 -58.943071)
			(xy 62.399399 -58.931018) (xy 62.484 -58.926988) (xy 62.568601 -58.931018) (xy 62.652436 -58.943071)
			(xy 62.734745 -58.963039) (xy 62.814784 -58.990741) (xy 62.891827 -59.025925) (xy 62.965177 -59.068274)
			(xy 63.034169 -59.117403) (xy 63.098179 -59.172868) (xy 63.156627 -59.234166) (xy 63.208983 -59.300742)
			(xy 63.254773 -59.371994) (xy 63.293584 -59.447275) (xy 63.325063 -59.525905) (xy 63.348924 -59.607172)
			(xy 63.364953 -59.690338) (xy 63.373004 -59.774652) (xy 63.373508 -59.817) (xy 63.373508 -59.817508)
			(xy 63.372902 -59.86384) (xy 63.363231 -59.955998) (xy 63.344035 -60.046652) (xy 63.315523 -60.134821)
			(xy 63.297308 -60.177426) (xy 63.293502 -60.187368) (xy 63.293502 -60.208632) (xy 63.297308 -60.218574)
			(xy 63.31553 -60.261177) (xy 63.344048 -60.349344) (xy 63.36324 -60.44) (xy 63.3729 -60.53216) (xy 63.373508 -60.578492)
			(xy 63.373508 -60.579) (xy 63.372991 -60.620142) (xy 63.365376 -60.702074) (xy 63.35023 -60.782954)
			(xy 63.327681 -60.862089) (xy 63.297923 -60.938805) (xy 63.26121 -61.012446) (xy 63.217855 -61.082383)
			(xy 63.168228 -61.148018) (xy 63.112754 -61.208792) (xy 63.051907 -61.264185) (xy 62.986205 -61.313724)
			(xy 62.91621 -61.356986) (xy 62.842521 -61.393602) (xy 62.765765 -61.423257) (xy 62.6866 -61.445701)
			(xy 62.605701 -61.460739) (xy 62.564772 -61.464952) (xy 62.564518 -61.464952) (xy 62.554215 -61.466389)
			(xy 62.53598 -61.476356) (xy 62.529212 -61.484256) (xy 62.477142 -61.551312) (xy 62.471808 -61.571632)
			(xy 62.473586 -61.582046) (xy 62.478744 -61.616803) (xy 62.484208 -61.686863) (xy 62.484508 -61.722)
			(xy 62.484035 -61.763505) (xy 62.476278 -61.846151) (xy 62.460859 -61.927716) (xy 62.437912 -62.007491)
			(xy 62.407636 -62.084783) (xy 62.370296 -62.15892) (xy 62.326214 -62.229258) (xy 62.301374 -62.262512)
			(xy 62.295035 -62.271712) (xy 62.290209 -62.2935) (xy 62.295035 -62.315288) (xy 62.301374 -62.324488)
			(xy 62.326214 -62.357721) (xy 62.3703 -62.428017) (xy 62.407643 -62.502115) (xy 62.437918 -62.579371)
			(xy 62.460862 -62.659112) (xy 62.475774 -62.738) (xy 100.329492 -62.738) (xy 100.329492 -62.737746)
			(xy 100.329976 -62.69626) (xy 100.33775 -62.613651) (xy 100.353179 -62.532125) (xy 100.376129 -62.452388)
			(xy 100.406401 -62.375134) (xy 100.443731 -62.301033) (xy 100.487796 -62.230727) (xy 100.512626 -62.197488)
			(xy 100.518965 -62.188288) (xy 100.523791 -62.1665) (xy 100.518965 -62.144712) (xy 100.512626 -62.135512)
			(xy 100.487786 -62.102279) (xy 100.4437 -62.031983) (xy 100.406357 -61.957885) (xy 100.376082 -61.880629)
			(xy 100.353138 -61.800888) (xy 100.337726 -61.719356) (xy 100.329978 -61.636742) (xy 100.329492 -61.595254)
			(xy 100.329492 -61.595) (xy 100.330009 -61.553858) (xy 100.337624 -61.471926) (xy 100.35277 -61.391046)
			(xy 100.375319 -61.311911) (xy 100.405077 -61.235195) (xy 100.44179 -61.161554) (xy 100.485145 -61.091617)
			(xy 100.534772 -61.025982) (xy 100.590246 -60.965208) (xy 100.651093 -60.909815) (xy 100.716795 -60.860276)
			(xy 100.78679 -60.817014) (xy 100.860479 -60.780398) (xy 100.937235 -60.750743) (xy 101.0164 -60.728299)
			(xy 101.097299 -60.713261) (xy 101.138228 -60.709048) (xy 101.138482 -60.709048) (xy 101.148785 -60.707611)
			(xy 101.16702 -60.697644) (xy 101.173788 -60.689744) (xy 101.225858 -60.622688) (xy 101.231192 -60.602368)
			(xy 101.229414 -60.591954) (xy 101.224256 -60.557197) (xy 101.218792 -60.487137) (xy 101.218492 -60.452)
			(xy 101.219075 -60.405604) (xy 101.22872 -60.313316) (xy 101.247916 -60.222532) (xy 101.276454 -60.134239)
			(xy 101.294692 -60.091574) (xy 101.298498 -60.081632) (xy 101.298498 -60.060368) (xy 101.294692 -60.050426)
			(xy 101.27647 -60.007823) (xy 101.247952 -59.919656) (xy 101.22876 -59.829) (xy 101.2191 -59.73684)
			(xy 101.218492 -59.690508) (xy 101.218492 -59.69) (xy 101.218996 -59.647652) (xy 101.227047 -59.563338)
			(xy 101.243076 -59.480172) (xy 101.266937 -59.398905) (xy 101.298416 -59.320275) (xy 101.337227 -59.244994)
			(xy 101.383017 -59.173742) (xy 101.435373 -59.107166) (xy 101.493821 -59.045868) (xy 101.557831 -58.990403)
			(xy 101.626823 -58.941274) (xy 101.700173 -58.898925) (xy 101.777216 -58.863741) (xy 101.857255 -58.836039)
			(xy 101.939564 -58.816071) (xy 102.023399 -58.804018) (xy 102.108 -58.799988) (xy 102.192601 -58.804018)
			(xy 102.276436 -58.816071) (xy 102.358745 -58.836039) (xy 102.438784 -58.863741) (xy 102.515827 -58.898925)
			(xy 102.589177 -58.941274) (xy 102.658169 -58.990403) (xy 102.722179 -59.045868) (xy 102.780627 -59.107166)
			(xy 102.832983 -59.173742) (xy 102.878773 -59.244994) (xy 102.917584 -59.320275) (xy 102.949063 -59.398905)
			(xy 102.972924 -59.480172) (xy 102.988953 -59.563338) (xy 102.997004 -59.647652) (xy 102.997508 -59.69)
			(xy 102.997508 -59.690508) (xy 102.996902 -59.73684) (xy 102.987231 -59.828998) (xy 102.968035 -59.919652)
			(xy 102.939523 -60.007821) (xy 102.921308 -60.050426) (xy 102.917502 -60.060368) (xy 102.917502 -60.081632)
			(xy 102.921308 -60.091574) (xy 102.93953 -60.134177) (xy 102.968048 -60.222344) (xy 102.98724 -60.313)
			(xy 102.9969 -60.40516) (xy 102.997508 -60.451492) (xy 102.997508 -60.452) (xy 102.996991 -60.493142)
			(xy 102.989376 -60.575074) (xy 102.97423 -60.655954) (xy 102.951681 -60.735089) (xy 102.921923 -60.811805)
			(xy 102.88521 -60.885446) (xy 102.841855 -60.955383) (xy 102.792228 -61.021018) (xy 102.736754 -61.081792)
			(xy 102.675907 -61.137185) (xy 102.610205 -61.186724) (xy 102.54021 -61.229986) (xy 102.466521 -61.266602)
			(xy 102.389765 -61.296257) (xy 102.3106 -61.318701) (xy 102.229701 -61.333739) (xy 102.188772 -61.337952)
			(xy 102.188518 -61.337952) (xy 102.178215 -61.339389) (xy 102.15998 -61.349356) (xy 102.153212 -61.357256)
			(xy 102.101142 -61.424312) (xy 102.095808 -61.444632) (xy 102.097586 -61.455046) (xy 102.102744 -61.489803)
			(xy 102.108208 -61.559863) (xy 102.108508 -61.595) (xy 102.108035 -61.636505) (xy 102.100278 -61.719151)
			(xy 102.084859 -61.800716) (xy 102.061912 -61.880491) (xy 102.031636 -61.957783) (xy 101.994296 -62.03192)
			(xy 101.950214 -62.102258) (xy 101.925374 -62.135512) (xy 101.919035 -62.144712) (xy 101.914209 -62.1665)
			(xy 101.919035 -62.188288) (xy 101.925374 -62.197488) (xy 101.950214 -62.230721) (xy 101.9943 -62.301017)
			(xy 102.031643 -62.375115) (xy 102.061918 -62.452371) (xy 102.084862 -62.532112) (xy 102.100274 -62.613644)
			(xy 102.108022 -62.696258) (xy 102.108508 -62.737746) (xy 102.108508 -62.738) (xy 139.318492 -62.738)
			(xy 139.318492 -62.737492) (xy 139.319011 -62.693728) (xy 139.327586 -62.606622) (xy 139.344682 -62.520781)
			(xy 139.370133 -62.437035) (xy 139.403693 -62.356197) (xy 139.423902 -62.317376) (xy 139.429229 -62.306023)
			(xy 139.429229 -62.280977) (xy 139.423902 -62.269624) (xy 139.403708 -62.230796) (xy 139.370168 -62.149953)
			(xy 139.344723 -62.066208) (xy 139.327618 -61.980371) (xy 139.319019 -61.89327) (xy 139.318492 -61.849508)
			(xy 139.318492 -61.849) (xy 139.319009 -61.807858) (xy 139.326624 -61.725926) (xy 139.34177 -61.645046)
			(xy 139.364319 -61.565911) (xy 139.394077 -61.489195) (xy 139.43079 -61.415554) (xy 139.474145 -61.345617)
			(xy 139.523772 -61.279982) (xy 139.579246 -61.219208) (xy 139.640093 -61.163815) (xy 139.705795 -61.114276)
			(xy 139.77579 -61.071014) (xy 139.849479 -61.034398) (xy 139.926235 -61.004743) (xy 140.0054 -60.982299)
			(xy 140.086299 -60.967261) (xy 140.127228 -60.963048) (xy 140.127482 -60.963048) (xy 140.137785 -60.961611)
			(xy 140.15602 -60.951644) (xy 140.162788 -60.943744) (xy 140.214858 -60.876688) (xy 140.220192 -60.856368)
			(xy 140.218414 -60.845954) (xy 140.213256 -60.811197) (xy 140.207792 -60.741137) (xy 140.207492 -60.706)
			(xy 140.208075 -60.659604) (xy 140.21772 -60.567316) (xy 140.236916 -60.476532) (xy 140.265454 -60.388239)
			(xy 140.283692 -60.345574) (xy 140.287498 -60.335632) (xy 140.287498 -60.314368) (xy 140.283692 -60.304426)
			(xy 140.26547 -60.261823) (xy 140.236952 -60.173656) (xy 140.21776 -60.083) (xy 140.2081 -59.99084)
			(xy 140.207492 -59.944508) (xy 140.207492 -59.944) (xy 140.207996 -59.901652) (xy 140.216047 -59.817338)
			(xy 140.232076 -59.734172) (xy 140.255937 -59.652905) (xy 140.287416 -59.574275) (xy 140.326227 -59.498994)
			(xy 140.372017 -59.427742) (xy 140.424373 -59.361166) (xy 140.482821 -59.299868) (xy 140.546831 -59.244403)
			(xy 140.615823 -59.195274) (xy 140.689173 -59.152925) (xy 140.766216 -59.117741) (xy 140.846255 -59.090039)
			(xy 140.928564 -59.070071) (xy 141.012399 -59.058018) (xy 141.097 -59.053988) (xy 141.181601 -59.058018)
			(xy 141.265436 -59.070071) (xy 141.347745 -59.090039) (xy 141.427784 -59.117741) (xy 141.504827 -59.152925)
			(xy 141.578177 -59.195274) (xy 141.647169 -59.244403) (xy 141.711179 -59.299868) (xy 141.769627 -59.361166)
			(xy 141.821983 -59.427742) (xy 141.867773 -59.498994) (xy 141.906584 -59.574275) (xy 141.938063 -59.652905)
			(xy 141.961924 -59.734172) (xy 141.977953 -59.817338) (xy 141.986004 -59.901652) (xy 141.986508 -59.944)
			(xy 141.986508 -59.944508) (xy 141.985902 -59.99084) (xy 141.976231 -60.082998) (xy 141.957035 -60.173652)
			(xy 141.928523 -60.261821) (xy 141.910308 -60.304426) (xy 141.906502 -60.314368) (xy 141.906502 -60.335632)
			(xy 141.910308 -60.345574) (xy 141.92853 -60.388177) (xy 141.957048 -60.476344) (xy 141.97624 -60.567)
			(xy 141.9859 -60.65916) (xy 141.986508 -60.705492) (xy 141.986508 -60.706) (xy 141.985991 -60.747142)
			(xy 141.978376 -60.829074) (xy 141.96323 -60.909954) (xy 141.940681 -60.989089) (xy 141.910923 -61.065805)
			(xy 141.87421 -61.139446) (xy 141.830855 -61.209383) (xy 141.781228 -61.275018) (xy 141.725754 -61.335792)
			(xy 141.664907 -61.391185) (xy 141.599205 -61.440724) (xy 141.52921 -61.483986) (xy 141.455521 -61.520602)
			(xy 141.378765 -61.550257) (xy 141.2996 -61.572701) (xy 141.218701 -61.587739) (xy 141.177772 -61.591952)
			(xy 141.177518 -61.591952) (xy 141.167215 -61.593389) (xy 141.14898 -61.603356) (xy 141.142212 -61.611256)
			(xy 141.090142 -61.678312) (xy 141.084808 -61.698632) (xy 141.086586 -61.709046) (xy 141.091744 -61.743803)
			(xy 141.097208 -61.813863) (xy 141.097508 -61.849) (xy 179.318412 -61.849) (xy 179.31886 -61.807844)
			(xy 179.326447 -61.725881) (xy 179.341575 -61.644971) (xy 179.364115 -61.565804) (xy 179.393873 -61.489059)
			(xy 179.430594 -61.415391) (xy 179.473966 -61.345432) (xy 179.523616 -61.27978) (xy 179.57912 -61.218996)
			(xy 179.640003 -61.163601) (xy 179.705744 -61.114068) (xy 179.775781 -61.070821) (xy 179.849513 -61.034231)
			(xy 179.926312 -61.004611) (xy 180.005519 -60.982213) (xy 180.086456 -60.967229) (xy 180.127402 -60.963048)
			(xy 180.127656 -60.963048) (xy 180.137957 -60.961598) (xy 180.156192 -60.95164) (xy 180.162962 -60.943744)
			(xy 180.215032 -60.876688) (xy 180.220366 -60.856368) (xy 180.218588 -60.845954) (xy 180.213368 -60.811201)
			(xy 180.207773 -60.741141) (xy 180.207412 -60.706) (xy 180.208036 -60.659598) (xy 180.217726 -60.5673)
			(xy 180.236981 -60.476515) (xy 180.26559 -60.38823) (xy 180.283866 -60.345574) (xy 180.287673 -60.335632)
			(xy 180.287673 -60.314368) (xy 180.283866 -60.304426) (xy 180.2656 -60.261767) (xy 180.237009 -60.173478)
			(xy 180.217753 -60.082695) (xy 180.208041 -59.990401) (xy 180.207412 -59.944) (xy 180.207916 -59.901639)
			(xy 180.215969 -59.817302) (xy 180.232003 -59.734112) (xy 180.255871 -59.652822) (xy 180.287359 -59.57417)
			(xy 180.326181 -59.498867) (xy 180.371984 -59.427595) (xy 180.424355 -59.360999) (xy 180.48282 -59.299684)
			(xy 180.546848 -59.244203) (xy 180.61586 -59.19506) (xy 180.68923 -59.1527) (xy 180.766295 -59.117505)
			(xy 180.846357 -59.089796) (xy 180.92869 -59.069822) (xy 181.012549 -59.057765) (xy 181.097174 -59.053734)
			(xy 181.181799 -59.057765) (xy 181.265658 -59.069822) (xy 181.347991 -59.089796) (xy 181.428053 -59.117505)
			(xy 181.505118 -59.1527) (xy 181.578488 -59.19506) (xy 181.6475 -59.244203) (xy 181.711528 -59.299684)
			(xy 181.769993 -59.360999) (xy 181.822364 -59.427595) (xy 181.868167 -59.498867) (xy 181.906989 -59.57417)
			(xy 181.938477 -59.652822) (xy 181.962345 -59.734112) (xy 181.978379 -59.817302) (xy 181.986432 -59.901639)
			(xy 181.986936 -59.944) (xy 181.986308 -59.990402) (xy 181.976618 -60.082699) (xy 181.957365 -60.173485)
			(xy 181.928758 -60.26177) (xy 181.910482 -60.304426) (xy 181.906678 -60.314369) (xy 181.906678 -60.335631)
			(xy 181.910482 -60.345574) (xy 181.928745 -60.388234) (xy 181.957338 -60.476523) (xy 181.976595 -60.567306)
			(xy 181.986307 -60.659599) (xy 181.986936 -60.706) (xy 181.986444 -60.747155) (xy 181.978858 -60.829115)
			(xy 181.963731 -60.910023) (xy 181.941193 -60.989187) (xy 181.911437 -61.065931) (xy 181.874717 -61.139596)
			(xy 181.831349 -61.209554) (xy 181.781702 -61.275206) (xy 181.726201 -61.335989) (xy 181.665322 -61.391385)
			(xy 181.599584 -61.440918) (xy 181.529552 -61.484166) (xy 181.455822 -61.520758) (xy 181.379028 -61.550381)
			(xy 181.299825 -61.572782) (xy 181.21889 -61.587769) (xy 181.177946 -61.591952) (xy 181.177692 -61.591952)
			(xy 181.167386 -61.593376) (xy 181.149153 -61.603353) (xy 181.142386 -61.611256) (xy 181.090316 -61.678312)
			(xy 181.084982 -61.698632) (xy 181.08676 -61.709046) (xy 181.09198 -61.743799) (xy 181.097575 -61.813859)
			(xy 181.097936 -61.849) (xy 181.097398 -61.892337) (xy 181.088935 -61.978598) (xy 181.07212 -62.063626)
			(xy 181.047112 -62.146614) (xy 181.014148 -62.226775) (xy 180.994304 -62.265306) (xy 180.989053 -62.276759)
			(xy 180.989173 -62.301923) (xy 180.994558 -62.313312) (xy 181.015235 -62.352477) (xy 181.049579 -62.434116)
			(xy 181.075639 -62.518765) (xy 181.093157 -62.605585) (xy 181.101959 -62.693715) (xy 181.102508 -62.738)
			(xy 181.102004 -62.780348) (xy 181.093953 -62.864662) (xy 181.077924 -62.947828) (xy 181.054063 -63.029095)
			(xy 181.022584 -63.107725) (xy 180.983773 -63.183006) (xy 180.937983 -63.254258) (xy 180.885627 -63.320834)
			(xy 180.827179 -63.382132) (xy 180.763169 -63.437597) (xy 180.694177 -63.486726) (xy 180.620827 -63.529075)
			(xy 180.543784 -63.564259) (xy 180.463745 -63.591961) (xy 180.381436 -63.611929) (xy 180.297601 -63.623982)
			(xy 180.213 -63.628013) (xy 180.128399 -63.623982) (xy 180.044564 -63.611929) (xy 179.962255 -63.591961)
			(xy 179.882216 -63.564259) (xy 179.805173 -63.529075) (xy 179.731823 -63.486726) (xy 179.662831 -63.437597)
			(xy 179.598821 -63.382132) (xy 179.540373 -63.320834) (xy 179.488017 -63.254258) (xy 179.442227 -63.183006)
			(xy 179.403416 -63.107725) (xy 179.371937 -63.029095) (xy 179.348076 -62.947828) (xy 179.332047 -62.864662)
			(xy 179.323996 -62.780348) (xy 179.323492 -62.738) (xy 179.323492 -62.737746) (xy 179.324008 -62.69444)
			(xy 179.332429 -62.608238) (xy 179.349197 -62.523264) (xy 179.374152 -62.440324) (xy 179.407057 -62.360206)
			(xy 179.42687 -62.321694) (xy 179.432123 -62.310241) (xy 179.432003 -62.285077) (xy 179.426616 -62.273688)
			(xy 179.405927 -62.234523) (xy 179.371528 -62.152893) (xy 179.345413 -62.068249) (xy 179.327841 -61.981428)
			(xy 179.318986 -61.89329) (xy 179.318412 -61.849) (xy 141.097508 -61.849) (xy 141.097012 -61.892815)
			(xy 141.088467 -61.980026) (xy 141.07138 -62.065973) (xy 141.045919 -62.149821) (xy 141.012329 -62.230757)
			(xy 140.992098 -62.269624) (xy 140.986771 -62.280977) (xy 140.986771 -62.306023) (xy 140.992098 -62.317376)
			(xy 141.012292 -62.356204) (xy 141.045832 -62.437047) (xy 141.071277 -62.520792) (xy 141.088382 -62.606629)
			(xy 141.096981 -62.69373) (xy 141.097508 -62.737492) (xy 141.097508 -62.738) (xy 141.097004 -62.780348)
			(xy 141.088953 -62.864662) (xy 141.072924 -62.947828) (xy 141.049063 -63.029095) (xy 141.017584 -63.107725)
			(xy 140.978773 -63.183006) (xy 140.932983 -63.254258) (xy 140.880627 -63.320834) (xy 140.822179 -63.382132)
			(xy 140.758169 -63.437597) (xy 140.689177 -63.486726) (xy 140.615827 -63.529075) (xy 140.538784 -63.564259)
			(xy 140.458745 -63.591961) (xy 140.376436 -63.611929) (xy 140.292601 -63.623982) (xy 140.208 -63.628013)
			(xy 140.123399 -63.623982) (xy 140.039564 -63.611929) (xy 139.957255 -63.591961) (xy 139.877216 -63.564259)
			(xy 139.800173 -63.529075) (xy 139.726823 -63.486726) (xy 139.657831 -63.437597) (xy 139.593821 -63.382132)
			(xy 139.535373 -63.320834) (xy 139.483017 -63.254258) (xy 139.437227 -63.183006) (xy 139.398416 -63.107725)
			(xy 139.366937 -63.029095) (xy 139.343076 -62.947828) (xy 139.327047 -62.864662) (xy 139.318996 -62.780348)
			(xy 139.318492 -62.738) (xy 102.108508 -62.738) (xy 102.108004 -62.780348) (xy 102.099953 -62.864662)
			(xy 102.083924 -62.947828) (xy 102.060063 -63.029095) (xy 102.028584 -63.107725) (xy 101.989773 -63.183006)
			(xy 101.943983 -63.254258) (xy 101.891627 -63.320834) (xy 101.833179 -63.382132) (xy 101.769169 -63.437597)
			(xy 101.700177 -63.486726) (xy 101.626827 -63.529075) (xy 101.549784 -63.564259) (xy 101.469745 -63.591961)
			(xy 101.387436 -63.611929) (xy 101.303601 -63.623982) (xy 101.219 -63.628013) (xy 101.134399 -63.623982)
			(xy 101.050564 -63.611929) (xy 100.968255 -63.591961) (xy 100.888216 -63.564259) (xy 100.811173 -63.529075)
			(xy 100.737823 -63.486726) (xy 100.668831 -63.437597) (xy 100.604821 -63.382132) (xy 100.546373 -63.320834)
			(xy 100.494017 -63.254258) (xy 100.448227 -63.183006) (xy 100.409416 -63.107725) (xy 100.377937 -63.029095)
			(xy 100.354076 -62.947828) (xy 100.338047 -62.864662) (xy 100.329996 -62.780348) (xy 100.329492 -62.738)
			(xy 62.475774 -62.738) (xy 62.476274 -62.740644) (xy 62.484022 -62.823258) (xy 62.484508 -62.864746)
			(xy 62.484508 -62.865) (xy 62.484004 -62.907348) (xy 62.475953 -62.991662) (xy 62.459924 -63.074828)
			(xy 62.436063 -63.156095) (xy 62.404584 -63.234725) (xy 62.365773 -63.310006) (xy 62.319983 -63.381258)
			(xy 62.267627 -63.447834) (xy 62.209179 -63.509132) (xy 62.145169 -63.564597) (xy 62.076177 -63.613726)
			(xy 62.002827 -63.656075) (xy 61.925784 -63.691259) (xy 61.845745 -63.718961) (xy 61.763436 -63.738929)
			(xy 61.679601 -63.750982) (xy 61.595 -63.755013) (xy 61.510399 -63.750982) (xy 61.426564 -63.738929)
			(xy 61.344255 -63.718961) (xy 61.264216 -63.691259) (xy 61.187173 -63.656075) (xy 61.113823 -63.613726)
			(xy 61.044831 -63.564597) (xy 60.980821 -63.509132) (xy 60.922373 -63.447834) (xy 60.870017 -63.381258)
			(xy 60.824227 -63.310006) (xy 60.785416 -63.234725) (xy 60.753937 -63.156095) (xy 60.730076 -63.074828)
			(xy 60.714047 -62.991662) (xy 60.705996 -62.907348) (xy 60.705492 -62.865) (xy 51.894284 -62.865)
			(xy 51.876327 -62.884699) (xy 51.81558 -62.94008) (xy 51.749982 -62.98962) (xy 51.680093 -63.032896)
			(xy 51.60651 -63.069539) (xy 51.529859 -63.099237) (xy 51.450795 -63.121736) (xy 51.369993 -63.136843)
			(xy 51.288141 -63.144432) (xy 51.24704 -63.144908) (xy 51.246532 -63.144908) (xy 51.200201 -63.144288)
			(xy 51.108043 -63.134621) (xy 51.017389 -63.115429) (xy 50.92922 -63.086921) (xy 50.886614 -63.068708)
			(xy 50.876672 -63.064902) (xy 50.855408 -63.064902) (xy 50.845466 -63.068708) (xy 50.802798 -63.08694)
			(xy 50.714508 -63.115487) (xy 50.623725 -63.134684) (xy 50.531436 -63.144321) (xy 50.48504 -63.144908)
			(xy 50.438645 -63.144311) (xy 50.346357 -63.13467) (xy 50.255573 -63.115478) (xy 50.167279 -63.086944)
			(xy 50.124614 -63.068708) (xy 50.114672 -63.064902) (xy 50.093408 -63.064902) (xy 50.083466 -63.068708)
			(xy 50.040798 -63.08694) (xy 49.952508 -63.115487) (xy 49.861725 -63.134684) (xy 49.769436 -63.144321)
			(xy 49.72304 -63.144908) (xy 49.676645 -63.144311) (xy 49.584357 -63.13467) (xy 49.493573 -63.115478)
			(xy 49.405279 -63.086944) (xy 49.362614 -63.068708) (xy 49.352672 -63.064902) (xy 49.331408 -63.064902)
			(xy 49.321466 -63.068708) (xy 49.278798 -63.08694) (xy 49.190508 -63.115487) (xy 49.099725 -63.134684)
			(xy 49.007436 -63.144321) (xy 48.96104 -63.144908) (xy 48.914645 -63.144311) (xy 48.822357 -63.13467)
			(xy 48.731573 -63.115478) (xy 48.643279 -63.086944) (xy 48.600614 -63.068708) (xy 48.590672 -63.064902)
			(xy 48.569408 -63.064902) (xy 48.559466 -63.068708) (xy 48.516858 -63.086917) (xy 48.428692 -63.115438)
			(xy 48.338038 -63.134634) (xy 48.24588 -63.144298) (xy 48.199548 -63.144908) (xy 48.19904 -63.144908)
			(xy 48.157937 -63.14441) (xy 48.076083 -63.136828) (xy 47.995277 -63.121726) (xy 47.916209 -63.099233)
			(xy 47.839554 -63.06954) (xy 47.765966 -63.0329) (xy 47.696073 -62.989627) (xy 47.630471 -62.940089)
			(xy 47.569719 -62.884709) (xy 47.514337 -62.82396) (xy 47.464796 -62.75836) (xy 47.42152 -62.688469)
			(xy 47.384877 -62.614882) (xy 47.35518 -62.538229) (xy 47.332683 -62.459162) (xy 47.317577 -62.378357)
			(xy 47.309992 -62.296502) (xy 47.309532 -62.2554) (xy 40.213323 -62.2554) (xy 40.208689 -62.299845)
			(xy 40.189626 -62.390304) (xy 40.161293 -62.478301) (xy 40.143176 -62.52083) (xy 40.141144 -62.525728)
			(xy 40.138963 -62.536103) (xy 40.138858 -62.541404) (xy 40.138858 -65.965267) (xy 201.765658 -65.965267)
			(xy 201.765658 -65.880545) (xy 201.773711 -65.796208) (xy 201.789745 -65.713018) (xy 201.813613 -65.631728)
			(xy 201.845101 -65.553076) (xy 201.883923 -65.477773) (xy 201.929726 -65.406501) (xy 201.982097 -65.339905)
			(xy 202.040562 -65.27859) (xy 202.10459 -65.223109) (xy 202.173602 -65.173966) (xy 202.246972 -65.131606)
			(xy 202.324037 -65.096411) (xy 202.404099 -65.068702) (xy 202.486432 -65.048728) (xy 202.570291 -65.036671)
			(xy 202.654916 -65.03264) (xy 202.739541 -65.036671) (xy 202.8234 -65.048728) (xy 202.905733 -65.068702)
			(xy 202.985795 -65.096411) (xy 203.06286 -65.131606) (xy 203.13623 -65.173966) (xy 203.205242 -65.223109)
			(xy 203.26927 -65.27859) (xy 203.327735 -65.339905) (xy 203.380106 -65.406501) (xy 203.425909 -65.477773)
			(xy 203.464731 -65.553076) (xy 203.496219 -65.631728) (xy 203.520087 -65.713018) (xy 203.536121 -65.796208)
			(xy 203.544174 -65.880545) (xy 203.544678 -65.922906) (xy 203.544503 -65.937581) (xy 204.723742 -65.937581)
			(xy 204.723742 -65.852859) (xy 204.731795 -65.768522) (xy 204.747829 -65.685332) (xy 204.771697 -65.604042)
			(xy 204.803185 -65.52539) (xy 204.842007 -65.450087) (xy 204.88781 -65.378815) (xy 204.940181 -65.312219)
			(xy 204.998646 -65.250904) (xy 205.062674 -65.195423) (xy 205.131686 -65.14628) (xy 205.205056 -65.10392)
			(xy 205.282121 -65.068725) (xy 205.362183 -65.041016) (xy 205.444516 -65.021042) (xy 205.528375 -65.008985)
			(xy 205.613 -65.004954) (xy 205.697625 -65.008985) (xy 205.781484 -65.021042) (xy 205.863817 -65.041016)
			(xy 205.943879 -65.068725) (xy 206.020944 -65.10392) (xy 206.094314 -65.14628) (xy 206.163326 -65.195423)
			(xy 206.227354 -65.250904) (xy 206.285819 -65.312219) (xy 206.33819 -65.378815) (xy 206.383993 -65.450087)
			(xy 206.422815 -65.52539) (xy 206.454303 -65.604042) (xy 206.478171 -65.685332) (xy 206.494205 -65.768522)
			(xy 206.502258 -65.852859) (xy 206.502762 -65.89522) (xy 206.502258 -65.937581) (xy 206.494205 -66.021918)
			(xy 206.478171 -66.105108) (xy 206.454303 -66.186398) (xy 206.422815 -66.26505) (xy 206.383993 -66.340353)
			(xy 206.33819 -66.411625) (xy 206.285819 -66.478221) (xy 206.227354 -66.539536) (xy 206.163326 -66.595017)
			(xy 206.094314 -66.64416) (xy 206.020944 -66.68652) (xy 205.943879 -66.721715) (xy 205.863817 -66.749424)
			(xy 205.781484 -66.769398) (xy 205.697625 -66.781455) (xy 205.613 -66.785487) (xy 205.528375 -66.781455)
			(xy 205.444516 -66.769398) (xy 205.362183 -66.749424) (xy 205.282121 -66.721715) (xy 205.205056 -66.68652)
			(xy 205.131686 -66.64416) (xy 205.062674 -66.595017) (xy 204.998646 -66.539536) (xy 204.940181 -66.478221)
			(xy 204.88781 -66.411625) (xy 204.842007 -66.340353) (xy 204.803185 -66.26505) (xy 204.771697 -66.186398)
			(xy 204.747829 -66.105108) (xy 204.731795 -66.021918) (xy 204.723742 -65.937581) (xy 203.544503 -65.937581)
			(xy 203.544174 -65.965267) (xy 203.536121 -66.049604) (xy 203.520087 -66.132794) (xy 203.496219 -66.214084)
			(xy 203.464731 -66.292736) (xy 203.425909 -66.368039) (xy 203.380106 -66.439311) (xy 203.327735 -66.505907)
			(xy 203.26927 -66.567222) (xy 203.205242 -66.622703) (xy 203.13623 -66.671846) (xy 203.06286 -66.714206)
			(xy 202.985795 -66.749401) (xy 202.905733 -66.77711) (xy 202.8234 -66.797084) (xy 202.739541 -66.809141)
			(xy 202.654916 -66.813173) (xy 202.570291 -66.809141) (xy 202.486432 -66.797084) (xy 202.404099 -66.77711)
			(xy 202.324037 -66.749401) (xy 202.246972 -66.714206) (xy 202.173602 -66.671846) (xy 202.10459 -66.622703)
			(xy 202.040562 -66.567222) (xy 201.982097 -66.505907) (xy 201.929726 -66.439311) (xy 201.883923 -66.368039)
			(xy 201.845101 -66.292736) (xy 201.813613 -66.214084) (xy 201.789745 -66.132794) (xy 201.773711 -66.049604)
			(xy 201.765658 -65.965267) (xy 40.138858 -65.965267) (xy 40.138858 -67.8942) (xy 40.139345 -67.904211)
			(xy 40.147004 -67.92271) (xy 40.161155 -67.936873) (xy 40.179648 -67.944546) (xy 40.189658 -67.945)
			(xy 49.45253 -67.945) (xy 49.462406 -67.944538) (xy 49.480702 -67.937091) (xy 49.48809 -67.930522)
			(xy 49.53889 -67.880738) (xy 49.545594 -67.873535) (xy 49.553424 -67.855502) (xy 49.55413 -67.845686)
			(xy 49.55413 -67.845432) (xy 49.555563 -67.79516) (xy 49.565265 -67.695048) (xy 49.582698 -67.59599)
			(xy 49.607757 -67.498581) (xy 49.64029 -67.403407) (xy 49.680102 -67.311041) (xy 49.726953 -67.222038)
			(xy 49.780562 -67.136935) (xy 49.840605 -67.056243) (xy 49.906723 -66.980447) (xy 49.978516 -66.910004)
			(xy 50.055553 -66.845338) (xy 50.13737 -66.786837) (xy 50.223476 -66.734853) (xy 50.313352 -66.6897)
			(xy 50.406457 -66.651649) (xy 50.502231 -66.620928) (xy 50.600099 -66.597723) (xy 50.69947 -66.582174)
			(xy 50.799748 -66.574373) (xy 50.850038 -66.573908) (xy 50.850546 -66.573908) (xy 50.902195 -66.574421)
			(xy 51.005163 -66.582663) (xy 51.107149 -66.599076) (xy 51.207505 -66.623556) (xy 51.305593 -66.655946)
			(xy 51.400792 -66.696042) (xy 51.492496 -66.743589) (xy 51.580125 -66.798285) (xy 51.663122 -66.859783)
			(xy 51.74096 -66.927693) (xy 51.777392 -66.964306) (xy 51.784844 -66.971355) (xy 51.803719 -66.979338)
			(xy 51.813968 -66.9798) (xy 51.886104 -66.9798) (xy 51.896352 -66.97934) (xy 51.915229 -66.971355)
			(xy 51.92268 -66.964306) (xy 51.959136 -66.927696) (xy 52.036985 -66.859758) (xy 52.119998 -66.798236)
			(xy 52.207647 -66.74352) (xy 52.299376 -66.69596) (xy 52.394602 -66.655857) (xy 52.492719 -66.623466)
			(xy 52.593104 -66.598992) (xy 52.69512 -66.582591) (xy 52.798117 -66.574368) (xy 52.84978 -66.573908)
			(xy 52.850288 -66.573908) (xy 52.901948 -66.574415) (xy 53.00494 -66.582649) (xy 53.106949 -66.599056)
			(xy 53.207328 -66.623534) (xy 53.30544 -66.655926) (xy 53.400661 -66.696028) (xy 53.492386 -66.743583)
			(xy 53.580034 -66.798291) (xy 53.663048 -66.859804) (xy 53.7409 -66.927731) (xy 53.777388 -66.964306)
			(xy 53.78484 -66.971355) (xy 53.803715 -66.97934) (xy 53.813964 -66.9798) (xy 53.8861 -66.9798) (xy 53.896348 -66.979341)
			(xy 53.915226 -66.971357) (xy 53.922676 -66.964306) (xy 53.959132 -66.927696) (xy 54.036981 -66.859757)
			(xy 54.119994 -66.798235) (xy 54.207643 -66.74352) (xy 54.299372 -66.695959) (xy 54.394597 -66.655855)
			(xy 54.492715 -66.623464) (xy 54.5931 -66.59899) (xy 54.695115 -66.582589) (xy 54.798113 -66.574365)
			(xy 54.849776 -66.573908) (xy 54.850284 -66.573908) (xy 54.901944 -66.574415) (xy 55.004936 -66.582648)
			(xy 55.106946 -66.599056) (xy 55.207325 -66.623533) (xy 55.305437 -66.655925) (xy 55.400658 -66.696026)
			(xy 55.492383 -66.743581) (xy 55.580032 -66.798289) (xy 55.663046 -66.859802) (xy 55.740898 -66.927729)
			(xy 55.777384 -66.964306) (xy 55.784836 -66.971356) (xy 55.803711 -66.979342) (xy 55.81396 -66.9798)
			(xy 55.886096 -66.9798) (xy 55.896345 -66.979342) (xy 55.915223 -66.971359) (xy 55.922672 -66.964306)
			(xy 55.959128 -66.927696) (xy 56.036977 -66.859757) (xy 56.11999 -66.798234) (xy 56.207639 -66.743519)
			(xy 56.299368 -66.695958) (xy 56.394593 -66.655854) (xy 56.49271 -66.623462) (xy 56.593096 -66.598988)
			(xy 56.695111 -66.582586) (xy 56.798109 -66.574363) (xy 56.849772 -66.573908) (xy 56.85028 -66.573908)
			(xy 56.90194 -66.574415) (xy 57.004932 -66.582648) (xy 57.106942 -66.599055) (xy 57.207322 -66.623532)
			(xy 57.305433 -66.655924) (xy 57.400655 -66.696025) (xy 57.492381 -66.74358) (xy 57.580029 -66.798287)
			(xy 57.663043 -66.8598) (xy 57.740896 -66.927727) (xy 57.77738 -66.964306) (xy 57.784832 -66.971357)
			(xy 57.803707 -66.979344) (xy 57.813956 -66.9798) (xy 57.886092 -66.9798) (xy 57.896333 -66.979324)
			(xy 57.915185 -66.971316) (xy 57.922668 -66.964306) (xy 57.959125 -66.927699) (xy 58.036976 -66.859766)
			(xy 58.11999 -66.798249) (xy 58.20764 -66.74354) (xy 58.29937 -66.695986) (xy 58.394595 -66.655889)
			(xy 58.492712 -66.623504) (xy 58.593096 -66.599037) (xy 58.69511 -66.582644) (xy 58.798106 -66.574427)
			(xy 58.849768 -66.573908) (xy 58.850276 -66.573908) (xy 58.901936 -66.574415) (xy 59.004929 -66.582647)
			(xy 59.106938 -66.599054) (xy 59.207318 -66.623531) (xy 59.30543 -66.655923) (xy 59.400652 -66.696023)
			(xy 59.492378 -66.743578) (xy 59.580027 -66.798286) (xy 59.663041 -66.859798) (xy 59.740894 -66.927725)
			(xy 59.777376 -66.964306) (xy 59.784828 -66.971357) (xy 59.803703 -66.979346) (xy 59.813952 -66.9798)
			(xy 59.886088 -66.9798) (xy 59.896329 -66.979325) (xy 59.915183 -66.971318) (xy 59.922664 -66.964306)
			(xy 59.959121 -66.927699) (xy 60.036971 -66.859765) (xy 60.119986 -66.798249) (xy 60.207636 -66.743539)
			(xy 60.299365 -66.695985) (xy 60.394591 -66.655888) (xy 60.492708 -66.623503) (xy 60.593092 -66.599035)
			(xy 60.695106 -66.582641) (xy 60.798102 -66.574425) (xy 60.849764 -66.573908) (xy 60.850272 -66.573908)
			(xy 60.901932 -66.574414) (xy 61.004925 -66.582647) (xy 61.106935 -66.599053) (xy 61.207315 -66.62353)
			(xy 61.305427 -66.655921) (xy 61.400649 -66.696022) (xy 61.492375 -66.743577) (xy 61.580024 -66.798284)
			(xy 61.663039 -66.859796) (xy 61.740892 -66.927723) (xy 61.777372 -66.964306) (xy 61.784823 -66.971358)
			(xy 61.803698 -66.979349) (xy 61.813948 -66.9798) (xy 61.886084 -66.9798) (xy 61.896325 -66.979325)
			(xy 61.91518 -66.97132) (xy 61.92266 -66.964306) (xy 61.959108 -66.927708) (xy 62.036938 -66.859789)
			(xy 62.119929 -66.798284) (xy 62.207554 -66.743582) (xy 62.299257 -66.696032) (xy 62.394456 -66.655935)
			(xy 62.492545 -66.623546) (xy 62.592901 -66.599071) (xy 62.694888 -66.582665) (xy 62.797857 -66.574432)
			(xy 62.849506 -66.573908) (xy 62.850014 -66.573908) (xy 62.90091 -66.574408) (xy 63.002387 -66.582396)
			(xy 63.102926 -66.59832) (xy 63.201904 -66.622084) (xy 63.298714 -66.65354) (xy 63.392756 -66.692495)
			(xy 63.483453 -66.738708) (xy 63.570244 -66.791894) (xy 63.652595 -66.851726) (xy 63.729997 -66.917835)
			(xy 63.801974 -66.989813) (xy 63.868082 -67.067216) (xy 63.927913 -67.149568) (xy 63.981099 -67.236359)
			(xy 64.027311 -67.327056) (xy 64.066265 -67.4211) (xy 64.09772 -67.517909) (xy 64.121483 -67.616888)
			(xy 64.137406 -67.717427) (xy 64.145393 -67.818904) (xy 64.145393 -67.920696) (xy 64.137406 -68.022173)
			(xy 64.121483 -68.122712) (xy 64.09772 -68.221691) (xy 64.066265 -68.3185) (xy 64.027311 -68.412544)
			(xy 63.981099 -68.503241) (xy 63.927913 -68.590032) (xy 63.868082 -68.672384) (xy 63.801974 -68.749787)
			(xy 63.729997 -68.821765) (xy 63.652595 -68.887874) (xy 63.570244 -68.947706) (xy 63.483453 -69.000892)
			(xy 63.392756 -69.047105) (xy 63.298714 -69.08606) (xy 63.201904 -69.117516) (xy 63.102926 -69.14128)
			(xy 63.002387 -69.157204) (xy 62.90091 -69.165192) (xy 62.850014 -69.165724) (xy 62.849506 -69.165724)
			(xy 62.797858 -69.165209) (xy 62.694891 -69.156963) (xy 62.592907 -69.140547) (xy 62.492553 -69.116065)
			(xy 62.394467 -69.083673) (xy 62.29927 -69.043575) (xy 62.207567 -68.996027) (xy 62.11994 -68.94133)
			(xy 62.036945 -68.879832) (xy 61.959109 -68.811922) (xy 61.92266 -68.775326) (xy 61.915212 -68.768266)
			(xy 61.896337 -68.760258) (xy 61.886084 -68.759832) (xy 61.813948 -68.759832) (xy 61.803702 -68.760299)
			(xy 61.784832 -68.768288) (xy 61.777372 -68.775326) (xy 61.740915 -68.811933) (xy 61.663064 -68.879867)
			(xy 61.58005 -68.941385) (xy 61.4924 -68.996096) (xy 61.400671 -69.043651) (xy 61.305446 -69.08375)
			(xy 61.207329 -69.116137) (xy 61.106945 -69.140606) (xy 61.00493 -69.157003) (xy 60.901934 -69.165222)
			(xy 60.850272 -69.165724) (xy 60.849764 -69.165724) (xy 60.798103 -69.165219) (xy 60.695109 -69.15699)
			(xy 60.593097 -69.140586) (xy 60.492715 -69.116112) (xy 60.394601 -69.083723) (xy 60.299376 -69.043625)
			(xy 60.207647 -68.996073) (xy 60.119995 -68.941368) (xy 60.036977 -68.879858) (xy 59.95912 -68.811933)
			(xy 59.922664 -68.775326) (xy 59.915216 -68.768265) (xy 59.896341 -68.760256) (xy 59.886088 -68.759832)
			(xy 59.813952 -68.759832) (xy 59.803706 -68.760298) (xy 59.784835 -68.768286) (xy 59.777376 -68.775326)
			(xy 59.740919 -68.811933) (xy 59.663068 -68.879868) (xy 59.580054 -68.941386) (xy 59.492404 -68.996097)
			(xy 59.400675 -69.043653) (xy 59.30545 -69.083752) (xy 59.207333 -69.116139) (xy 59.106949 -69.140608)
			(xy 59.004934 -69.157005) (xy 58.901938 -69.165225) (xy 58.850276 -69.165724) (xy 58.849768 -69.165724)
			(xy 58.798107 -69.165219) (xy 58.695113 -69.15699) (xy 58.593101 -69.140587) (xy 58.492719 -69.116113)
			(xy 58.394604 -69.083724) (xy 58.299379 -69.043627) (xy 58.20765 -68.996074) (xy 58.119998 -68.94137)
			(xy 58.03698 -68.879859) (xy 57.959122 -68.811935) (xy 57.922668 -68.775326) (xy 57.91522 -68.768264)
			(xy 57.896345 -68.760254) (xy 57.886092 -68.759832) (xy 57.813956 -68.759832) (xy 57.80371 -68.760297)
			(xy 57.784837 -68.768285) (xy 57.77738 -68.775326) (xy 57.740923 -68.811934) (xy 57.663073 -68.879868)
			(xy 57.580059 -68.941386) (xy 57.492409 -68.996097) (xy 57.400679 -69.043654) (xy 57.305454 -69.083753)
			(xy 57.207337 -69.116141) (xy 57.106953 -69.140611) (xy 57.004938 -69.157008) (xy 56.901942 -69.165227)
			(xy 56.85028 -69.165724) (xy 56.849772 -69.165724) (xy 56.798111 -69.165219) (xy 56.695116 -69.15699)
			(xy 56.593104 -69.140587) (xy 56.492722 -69.116114) (xy 56.394607 -69.083725) (xy 56.299383 -69.043628)
			(xy 56.207653 -68.996076) (xy 56.12 -68.941371) (xy 56.036982 -68.879861) (xy 55.959125 -68.811937)
			(xy 55.922672 -68.775326) (xy 55.915225 -68.768264) (xy 55.89635 -68.760251) (xy 55.886096 -68.759832)
			(xy 55.81396 -68.759832) (xy 55.803713 -68.760296) (xy 55.78484 -68.768283) (xy 55.777384 -68.775326)
			(xy 55.740927 -68.811934) (xy 55.663077 -68.879869) (xy 55.580063 -68.941387) (xy 55.492413 -68.996098)
			(xy 55.400684 -69.043655) (xy 55.305458 -69.083754) (xy 55.207342 -69.116142) (xy 55.106957 -69.140613)
			(xy 55.004943 -69.15701) (xy 54.901946 -69.16523) (xy 54.850284 -69.165724) (xy 54.849776 -69.165724)
			(xy 54.798115 -69.165219) (xy 54.69512 -69.156991) (xy 54.593108 -69.140588) (xy 54.492726 -69.116115)
			(xy 54.39461 -69.083727) (xy 54.299386 -69.043629) (xy 54.207656 -68.996078) (xy 54.120003 -68.941373)
			(xy 54.036984 -68.879863) (xy 53.959127 -68.811939) (xy 53.922676 -68.775326) (xy 53.915229 -68.768263)
			(xy 53.896354 -68.760249) (xy 53.8861 -68.759832) (xy 53.813964 -68.759832) (xy 53.803717 -68.760296)
			(xy 53.784842 -68.768281) (xy 53.777388 -68.775326) (xy 53.740931 -68.811934) (xy 53.663081 -68.879869)
			(xy 53.580067 -68.941388) (xy 53.492417 -68.996099) (xy 53.400688 -69.043656) (xy 53.305463 -69.083756)
			(xy 53.207346 -69.116144) (xy 53.106961 -69.140615) (xy 53.004947 -69.157012) (xy 52.90195 -69.165233)
			(xy 52.850288 -69.165724) (xy 52.84978 -69.165724) (xy 52.798119 -69.16522) (xy 52.695124 -69.156991)
			(xy 52.593112 -69.140589) (xy 52.492729 -69.116116) (xy 52.394614 -69.083728) (xy 52.299389 -69.043631)
			(xy 52.207658 -68.996079) (xy 52.120006 -68.941375) (xy 52.036987 -68.879865) (xy 51.959129 -68.811941)
			(xy 51.92268 -68.775326) (xy 51.915233 -68.768262) (xy 51.896358 -68.760247) (xy 51.886104 -68.759832)
			(xy 51.813968 -68.759832) (xy 51.803721 -68.760295) (xy 51.784845 -68.768279) (xy 51.777392 -68.775326)
			(xy 51.739301 -68.813527) (xy 51.657754 -68.884166) (xy 51.570615 -68.947777) (xy 51.478487 -69.003921)
			(xy 51.382008 -69.052207) (xy 51.33213 -69.07276) (xy 51.320192 -69.077586) (xy 51.303936 -69.097144)
			(xy 51.284378 -69.192902) (xy 51.282498 -69.205365) (xy 51.289683 -69.229491) (xy 51.298094 -69.238876)
			(xy 56.369204 -74.309986) (xy 56.376602 -74.316833) (xy 56.3952 -74.324568) (xy 56.405272 -74.324972)
		)
		(stroke
			(width 0)
			(type solid)
		)
		(fill yes)
		(layer "In5.Cu")
		(net "P12V_BRICK")
	)
	(gr_arc
		(start 2.999994 -128.729994)
		(mid 0.878678 -129.608672)
		(end 0 -131.729988)
		(stroke
			(width 2.032)
			(type default)
		)
		(layer "In5.Cu")
	)
	(gr_line
		(start 2.999994 -116.229892)
		(end 9.59993 -116.229892)
		(stroke
			(width 2.032)
			(type default)
		)
		(layer "In5.Cu")
	)
	(gr_arc
		(start 2.999994 -31.569914)
		(mid 0.878678 -32.448592)
		(end 0 -34.569908)
		(stroke
			(width 2.032)
			(type default)
		)
		(layer "In5.Cu")
	)
	(gr_line
		(start 2.999994 -19.070066)
		(end 9.59993 -19.070066)
		(stroke
			(width 2.032)
			(type default)
		)
		(layer "In5.Cu")
	)
	(gr_arc
		(start 4.99999 0)
		(mid 1.464463 -1.464463)
		(end 0 -4.99999)
		(stroke
			(width 2.032)
			(type default)
		)
		(layer "In5.Cu")
	)
	(gr_line
		(start 8.1534 -77.1906)
		(end 8.1534 -68.5546)
		(stroke
			(width 1.016)
			(type default)
		)
		(layer "In5.Cu")
	)
	(gr_line
		(start 8.1534 -68.5546)
		(end 9.1186 -67.5894)
		(stroke
			(width 1.016)
			(type default)
		)
		(layer "In5.Cu")
	)
	(gr_line
		(start 8.9154 -77.9526)
		(end 8.1534 -77.1906)
		(stroke
			(width 1.016)
			(type default)
		)
		(layer "In5.Cu")
	)
	(gr_line
		(start 9.1186 -67.5894)
		(end 37.4904 -67.5894)
		(stroke
			(width 1.016)
			(type default)
		)
		(layer "In5.Cu")
	)
	(gr_line
		(start 9.59993 -128.729994)
		(end 2.999994 -128.729994)
		(stroke
			(width 2.032)
			(type default)
		)
		(layer "In5.Cu")
	)
	(gr_arc
		(start 9.59993 -128.729994)
		(mid 9.953557 -128.583675)
		(end 10.100056 -128.230122)
		(stroke
			(width 2.032)
			(type default)
		)
		(layer "In5.Cu")
	)
	(gr_line
		(start 9.59993 -31.569914)
		(end 2.999994 -31.569914)
		(stroke
			(width 2.032)
			(type default)
		)
		(layer "In5.Cu")
	)
	(gr_arc
		(start 9.59993 -31.569914)
		(mid 9.953647 -31.42361)
		(end 10.100056 -31.070042)
		(stroke
			(width 2.032)
			(type default)
		)
		(layer "In5.Cu")
	)
	(gr_line
		(start 10.100056 -118.917974)
		(end 10.100056 -128.230122)
		(stroke
			(width 2.032)
			(type default)
		)
		(layer "In5.Cu")
	)
	(gr_line
		(start 10.100056 -118.917974)
		(end 10.100056 -116.730018)
		(stroke
			(width 2.032)
			(type default)
		)
		(layer "In5.Cu")
	)
	(gr_arc
		(start 10.100056 -116.730018)
		(mid 9.953572 -116.376376)
		(end 9.59993 -116.229892)
		(stroke
			(width 2.032)
			(type default)
		)
		(layer "In5.Cu")
	)
	(gr_arc
		(start 10.100056 -19.569938)
		(mid 9.953467 -19.21655)
		(end 9.59993 -19.070066)
		(stroke
			(width 2.032)
			(type default)
		)
		(layer "In5.Cu")
	)
	(gr_line
		(start 10.100056 -19.569938)
		(end 10.100056 -31.070042)
		(stroke
			(width 2.032)
			(type default)
		)
		(layer "In5.Cu")
	)
	(gr_line
		(start 14.9606 -77.9526)
		(end 8.9154 -77.9526)
		(stroke
			(width 1.016)
			(type default)
		)
		(layer "In5.Cu")
	)
	(gr_line
		(start 14.9606 -77.9526)
		(end 15.24 -78.232)
		(stroke
			(width 1.016)
			(type default)
		)
		(layer "In5.Cu")
	)
	(gr_line
		(start 15.24 -117.91061)
		(end 15.24 -78.232)
		(stroke
			(width 1.016)
			(type default)
		)
		(layer "In5.Cu")
	)
	(gr_line
		(start 16.247364 -118.917974)
		(end 15.24 -117.91061)
		(stroke
			(width 1.016)
			(type default)
		)
		(layer "In5.Cu")
	)
	(gr_circle
		(center 27.5844 -66.43624)
		(end 28.4734 -66.43624)
		(stroke
			(width 0.2)
			(type default)
		)
		(fill no)
		(layer "In5.Cu")
	)
	(gr_circle
		(center 27.5844 -65.67424)
		(end 28.4734 -65.67424)
		(stroke
			(width 0.2)
			(type default)
		)
		(fill no)
		(layer "In5.Cu")
	)
	(gr_circle
		(center 27.5844 -64.91224)
		(end 28.4734 -64.91224)
		(stroke
			(width 0.2)
			(type default)
		)
		(fill no)
		(layer "In5.Cu")
	)
	(gr_circle
		(center 28.3464 -66.43624)
		(end 29.2354 -66.43624)
		(stroke
			(width 0.2)
			(type default)
		)
		(fill no)
		(layer "In5.Cu")
	)
	(gr_circle
		(center 28.3464 -65.67424)
		(end 29.2354 -65.67424)
		(stroke
			(width 0.2)
			(type default)
		)
		(fill no)
		(layer "In5.Cu")
	)
	(gr_circle
		(center 28.3464 -64.91224)
		(end 29.2354 -64.91224)
		(stroke
			(width 0.2)
			(type default)
		)
		(fill no)
		(layer "In5.Cu")
	)
	(gr_line
		(start 34.925 -57.15)
		(end 34.925 -46.433994)
		(stroke
			(width 1.016)
			(type default)
		)
		(layer "In5.Cu")
	)
	(gr_line
		(start 34.925 -57.15)
		(end 39.630858 -61.855858)
		(stroke
			(width 1.016)
			(type default)
		)
		(layer "In5.Cu")
	)
	(gr_line
		(start 34.925 -46.433994)
		(end 57.531 -23.827994)
		(stroke
			(width 1.016)
			(type default)
		)
		(layer "In5.Cu")
	)
	(gr_line
		(start 35.51174 -117.856508)
		(end 34.450274 -118.917974)
		(stroke
			(width 1.016)
			(type default)
		)
		(layer "In5.Cu")
	)
	(gr_line
		(start 35.51174 -117.856508)
		(end 36.573206 -118.917974)
		(stroke
			(width 1.016)
			(type default)
		)
		(layer "In5.Cu")
	)
	(gr_line
		(start 35.51174 -84.78266)
		(end 35.51174 -118.917974)
		(stroke
			(width 1.016)
			(type default)
		)
		(layer "In5.Cu")
	)
	(gr_line
		(start 36.9824 -83.312)
		(end 35.51174 -84.78266)
		(stroke
			(width 1.016)
			(type default)
		)
		(layer "In5.Cu")
	)
	(gr_line
		(start 37.4904 -67.5894)
		(end 38.354 -68.453)
		(stroke
			(width 1.016)
			(type default)
		)
		(layer "In5.Cu")
	)
	(gr_line
		(start 37.4904 -67.5894)
		(end 39.296086 -67.5894)
		(stroke
			(width 1.016)
			(type default)
		)
		(layer "In5.Cu")
	)
	(gr_circle
		(center 38.261036 -55.642002)
		(end 39.150036 -55.642002)
		(stroke
			(width 0.2)
			(type default)
		)
		(fill no)
		(layer "In5.Cu")
	)
	(gr_line
		(start 38.354 -74.832972)
		(end 38.41496 -74.893932)
		(stroke
			(width 1.016)
			(type default)
		)
		(layer "In5.Cu")
	)
	(gr_line
		(start 38.354 -68.453)
		(end 38.354 -74.832972)
		(stroke
			(width 1.016)
			(type default)
		)
		(layer "In5.Cu")
	)
	(gr_line
		(start 38.354 -68.453)
		(end 49.793906 -68.453)
		(stroke
			(width 1.016)
			(type default)
		)
		(layer "In5.Cu")
	)
	(gr_line
		(start 38.41496 -74.893932)
		(end 46.833028 -83.312)
		(stroke
			(width 1.016)
			(type default)
		)
		(layer "In5.Cu")
	)
	(gr_circle
		(center 38.692836 -58.436002)
		(end 39.581836 -58.436002)
		(stroke
			(width 0.2)
			(type default)
		)
		(fill no)
		(layer "In5.Cu")
	)
	(gr_circle
		(center 38.692836 -57.547002)
		(end 39.581836 -57.547002)
		(stroke
			(width 0.2)
			(type default)
		)
		(fill no)
		(layer "In5.Cu")
	)
	(gr_circle
		(center 38.692836 -56.658002)
		(end 39.581836 -56.658002)
		(stroke
			(width 0.2)
			(type default)
		)
		(fill no)
		(layer "In5.Cu")
	)
	(gr_circle
		(center 38.98392 -54.1909)
		(end 39.87292 -54.1909)
		(stroke
			(width 0.2)
			(type default)
		)
		(fill no)
		(layer "In5.Cu")
	)
	(gr_circle
		(center 39.378636 -58.817002)
		(end 40.267636 -58.817002)
		(stroke
			(width 0.2)
			(type default)
		)
		(fill no)
		(layer "In5.Cu")
	)
	(gr_circle
		(center 39.378636 -57.928002)
		(end 40.267636 -57.928002)
		(stroke
			(width 0.2)
			(type default)
		)
		(fill no)
		(layer "In5.Cu")
	)
	(gr_circle
		(center 39.378636 -57.039002)
		(end 40.267636 -57.039002)
		(stroke
			(width 0.2)
			(type default)
		)
		(fill no)
		(layer "In5.Cu")
	)
	(gr_line
		(start 39.497 -146.99996)
		(end 4.99999 -146.99996)
		(stroke
			(width 2.032)
			(type default)
		)
		(layer "In5.Cu")
	)
	(gr_line
		(start 39.497 -146.99996)
		(end 39.497 -118.917974)
		(stroke
			(width 1.016)
			(type default)
		)
		(layer "In5.Cu")
	)
	(gr_line
		(start 39.497 -145.316702)
		(end 38.485064 -146.328638)
		(stroke
			(width 1.016)
			(type default)
		)
		(layer "In5.Cu")
	)
	(gr_line
		(start 39.497 -120.523)
		(end 37.891974 -118.917974)
		(stroke
			(width 1.016)
			(type default)
		)
		(layer "In5.Cu")
	)
	(gr_line
		(start 39.497 -120.523)
		(end 41.102026 -118.917974)
		(stroke
			(width 1.016)
			(type default)
		)
		(layer "In5.Cu")
	)
	(gr_line
		(start 39.497 -118.917974)
		(end 222.159322 -118.917974)
		(stroke
			(width 1.016)
			(type default)
		)
		(layer "In5.Cu")
	)
	(gr_line
		(start 39.605458 -66.922142)
		(end 38.3286 -68.199)
		(stroke
			(width 1.016)
			(type default)
		)
		(layer "In5.Cu")
	)
	(gr_line
		(start 39.630858 -68.453)
		(end 38.354 -69.729858)
		(stroke
			(width 1.016)
			(type default)
		)
		(layer "In5.Cu")
	)
	(gr_line
		(start 39.630858 -61.855858)
		(end 39.630858 -68.453)
		(stroke
			(width 1.016)
			(type default)
		)
		(layer "In5.Cu")
	)
	(gr_line
		(start 40.508936 -146.328638)
		(end 39.497 -145.316702)
		(stroke
			(width 1.016)
			(type default)
		)
		(layer "In5.Cu")
	)
	(gr_line
		(start 41.102026 -118.917974)
		(end 16.247364 -118.917974)
		(stroke
			(width 1.016)
			(type default)
		)
		(layer "In5.Cu")
	)
	(gr_line
		(start 45.363384 -82.550254)
		(end 44.601638 -83.312)
		(stroke
			(width 1.016)
			(type default)
		)
		(layer "In5.Cu")
	)
	(gr_line
		(start 45.363384 -81.842356)
		(end 45.363384 -82.550254)
		(stroke
			(width 1.016)
			(type default)
		)
		(layer "In5.Cu")
	)
	(gr_line
		(start 46.833028 -83.312)
		(end 36.9824 -83.312)
		(stroke
			(width 1.016)
			(type default)
		)
		(layer "In5.Cu")
	)
	(gr_line
		(start 56.173878 -74.832972)
		(end 49.793906 -68.453)
		(stroke
			(width 1.016)
			(type default)
		)
		(layer "In5.Cu")
	)
	(gr_line
		(start 57.531 -23.827994)
		(end 202.389994 -23.827994)
		(stroke
			(width 1.016)
			(type default)
		)
		(layer "In5.Cu")
	)
	(gr_circle
		(center 62.850014 -77.71765)
		(end 63.739014 -77.71765)
		(stroke
			(width 0.2)
			(type default)
		)
		(fill no)
		(layer "In5.Cu")
	)
	(gr_line
		(start 78.476094 -74.832972)
		(end 56.173878 -74.832972)
		(stroke
			(width 1.016)
			(type default)
		)
		(layer "In5.Cu")
	)
	(gr_line
		(start 84.856066 -68.453)
		(end 78.476094 -74.832972)
		(stroke
			(width 1.016)
			(type default)
		)
		(layer "In5.Cu")
	)
	(gr_line
		(start 89.793826 -68.453)
		(end 84.856066 -68.453)
		(stroke
			(width 1.016)
			(type default)
		)
		(layer "In5.Cu")
	)
	(gr_line
		(start 96.173798 -74.832972)
		(end 89.793826 -68.453)
		(stroke
			(width 1.016)
			(type default)
		)
		(layer "In5.Cu")
	)
	(gr_circle
		(center 102.849934 -77.71765)
		(end 103.738934 -77.71765)
		(stroke
			(width 0.2)
			(type default)
		)
		(fill no)
		(layer "In5.Cu")
	)
	(gr_line
		(start 118.476268 -74.832972)
		(end 96.173798 -74.832972)
		(stroke
			(width 1.016)
			(type default)
		)
		(layer "In5.Cu")
	)
	(gr_line
		(start 124.85624 -68.453)
		(end 118.476268 -74.832972)
		(stroke
			(width 1.016)
			(type default)
		)
		(layer "In5.Cu")
	)
	(gr_line
		(start 129.794 -68.453)
		(end 124.85624 -68.453)
		(stroke
			(width 1.016)
			(type default)
		)
		(layer "In5.Cu")
	)
	(gr_line
		(start 136.173972 -74.832972)
		(end 129.794 -68.453)
		(stroke
			(width 1.016)
			(type default)
		)
		(layer "In5.Cu")
	)
	(gr_line
		(start 136.173972 -74.832972)
		(end 158.476442 -74.832972)
		(stroke
			(width 1.016)
			(type default)
		)
		(layer "In5.Cu")
	)
	(gr_circle
		(center 142.850108 -77.71765)
		(end 143.739108 -77.71765)
		(stroke
			(width 0.2)
			(type default)
		)
		(fill no)
		(layer "In5.Cu")
	)
	(gr_line
		(start 149.098 -83.312)
		(end 46.833028 -83.312)
		(stroke
			(width 1.016)
			(type default)
		)
		(layer "In5.Cu")
	)
	(gr_line
		(start 157.099 -91.313)
		(end 149.098 -83.312)
		(stroke
			(width 1.016)
			(type default)
		)
		(layer "In5.Cu")
	)
	(gr_line
		(start 158.476442 -74.832972)
		(end 164.856414 -68.453)
		(stroke
			(width 1.016)
			(type default)
		)
		(layer "In5.Cu")
	)
	(gr_circle
		(center 162.1028 -11.811)
		(end 162.9918 -11.811)
		(stroke
			(width 0.2)
			(type default)
		)
		(fill no)
		(layer "In5.Cu")
	)
	(gr_circle
		(center 162.1028 -11.176)
		(end 162.9918 -11.176)
		(stroke
			(width 0.2)
			(type default)
		)
		(fill no)
		(layer "In5.Cu")
	)
	(gr_circle
		(center 162.7886 -10.7442)
		(end 163.6776 -10.7442)
		(stroke
			(width 0.2)
			(type default)
		)
		(fill no)
		(layer "In5.Cu")
	)
	(gr_circle
		(center 162.8394 -12.2174)
		(end 163.7284 -12.2174)
		(stroke
			(width 0.2)
			(type default)
		)
		(fill no)
		(layer "In5.Cu")
	)
	(gr_line
		(start 169.794174 -68.453)
		(end 164.856414 -68.453)
		(stroke
			(width 1.016)
			(type default)
		)
		(layer "In5.Cu")
	)
	(gr_line
		(start 169.794174 -68.453)
		(end 176.174146 -74.832972)
		(stroke
			(width 1.016)
			(type default)
		)
		(layer "In5.Cu")
	)
	(gr_line
		(start 175.895 -91.313)
		(end 157.099 -91.313)
		(stroke
			(width 1.016)
			(type default)
		)
		(layer "In5.Cu")
	)
	(gr_line
		(start 176.174146 -74.832972)
		(end 204.119734 -74.832972)
		(stroke
			(width 1.016)
			(type default)
		)
		(layer "In5.Cu")
	)
	(gr_circle
		(center 182.850282 -77.71765)
		(end 183.739282 -77.71765)
		(stroke
			(width 0.2)
			(type default)
		)
		(fill no)
		(layer "In5.Cu")
	)
	(gr_line
		(start 184.785 -146.99996)
		(end 39.497 -146.99996)
		(stroke
			(width 2.032)
			(type default)
		)
		(layer "In5.Cu")
	)
	(gr_line
		(start 202.389994 -23.827994)
		(end 204.216 -25.654)
		(stroke
			(width 1.016)
			(type default)
		)
		(layer "In5.Cu")
	)
	(gr_line
		(start 204.119734 -74.832972)
		(end 214.150448 -64.802258)
		(stroke
			(width 1.016)
			(type default)
		)
		(layer "In5.Cu")
	)
	(gr_line
		(start 204.216 -45.226732)
		(end 204.216 -25.654)
		(stroke
			(width 1.016)
			(type default)
		)
		(layer "In5.Cu")
	)
	(gr_line
		(start 205.121002 -46.131734)
		(end 204.216 -45.226732)
		(stroke
			(width 1.016)
			(type default)
		)
		(layer "In5.Cu")
	)
	(gr_line
		(start 212.598508 -46.131734)
		(end 205.121002 -46.131734)
		(stroke
			(width 1.016)
			(type default)
		)
		(layer "In5.Cu")
	)
	(gr_line
		(start 214.150448 -64.802258)
		(end 214.150448 -47.683674)
		(stroke
			(width 1.016)
			(type default)
		)
		(layer "In5.Cu")
	)
	(gr_line
		(start 214.150448 -47.683674)
		(end 212.598508 -46.131734)
		(stroke
			(width 1.016)
			(type default)
		)
		(layer "In5.Cu")
	)
	(gr_line
		(start 219.583 -91.313)
		(end 175.895 -91.313)
		(stroke
			(width 1.016)
			(type default)
		)
		(layer "In5.Cu")
	)
	(gr_line
		(start 219.963746 -72.730614)
		(end 219.964 -72.73036)
		(stroke
			(width 1.016)
			(type default)
		)
		(layer "In5.Cu")
	)
	(gr_line
		(start 219.964 -90.932)
		(end 219.583 -91.313)
		(stroke
			(width 1.016)
			(type default)
		)
		(layer "In5.Cu")
	)
	(gr_line
		(start 219.964 -90.932)
		(end 219.964 -72.73036)
		(stroke
			(width 1.016)
			(type default)
		)
		(layer "In5.Cu")
	)
	(gr_line
		(start 219.964 -72.73036)
		(end 234.40136 -58.293)
		(stroke
			(width 1.016)
			(type default)
		)
		(layer "In5.Cu")
	)
	(gr_line
		(start 221.605602 -146.873976)
		(end 223.256602 -145.222976)
		(stroke
			(width 1.016)
			(type default)
		)
		(layer "In5.Cu")
	)
	(gr_line
		(start 222.159322 -118.917974)
		(end 223.256602 -120.015254)
		(stroke
			(width 1.016)
			(type default)
		)
		(layer "In5.Cu")
	)
	(gr_line
		(start 223.256602 -120.015254)
		(end 223.256602 -147.000214)
		(stroke
			(width 1.016)
			(type default)
		)
		(layer "In5.Cu")
	)
	(gr_line
		(start 224.907602 -146.873976)
		(end 223.256602 -145.222976)
		(stroke
			(width 1.016)
			(type default)
		)
		(layer "In5.Cu")
	)
	(gr_line
		(start 234.40136 -58.293)
		(end 251.82195 -58.293)
		(stroke
			(width 1.016)
			(type default)
		)
		(layer "In5.Cu")
	)
	(gr_line
		(start 237.109 -146.99996)
		(end 184.785 -146.99996)
		(stroke
			(width 2.032)
			(type default)
		)
		(layer "In5.Cu")
	)
	(gr_line
		(start 251.82195 -58.293)
		(end 258.55295 -51.562)
		(stroke
			(width 1.016)
			(type default)
		)
		(layer "In5.Cu")
	)
	(gr_circle
		(center 258.219956 -50.232818)
		(end 259.108956 -50.232818)
		(stroke
			(width 0.2)
			(type default)
		)
		(fill no)
		(layer "In5.Cu")
	)
	(gr_circle
		(center 258.219956 -48.327818)
		(end 259.108956 -48.327818)
		(stroke
			(width 0.2)
			(type default)
		)
		(fill no)
		(layer "In5.Cu")
	)
	(gr_circle
		(center 258.219956 -47.565818)
		(end 259.108956 -47.565818)
		(stroke
			(width 0.2)
			(type default)
		)
		(fill no)
		(layer "In5.Cu")
	)
	(gr_circle
		(center 258.530598 -39.18712)
		(end 259.419598 -39.18712)
		(stroke
			(width 0.2)
			(type default)
		)
		(fill no)
		(layer "In5.Cu")
	)
	(gr_circle
		(center 258.548886 -38.461696)
		(end 259.437886 -38.461696)
		(stroke
			(width 0.2)
			(type default)
		)
		(fill no)
		(layer "In5.Cu")
	)
	(gr_line
		(start 258.55295 -51.562)
		(end 270.637 -51.562)
		(stroke
			(width 1.016)
			(type default)
		)
		(layer "In5.Cu")
	)
	(gr_circle
		(center 258.83362 -40.72382)
		(end 259.72262 -40.72382)
		(stroke
			(width 0.2)
			(type default)
		)
		(fill no)
		(layer "In5.Cu")
	)
	(gr_circle
		(center 258.83616 -39.95674)
		(end 259.72516 -39.95674)
		(stroke
			(width 0.2)
			(type default)
		)
		(fill no)
		(layer "In5.Cu")
	)
	(gr_circle
		(center 259.0038 -42.3164)
		(end 259.8928 -42.3164)
		(stroke
			(width 0.2)
			(type default)
		)
		(fill no)
		(layer "In5.Cu")
	)
	(gr_circle
		(center 259.588 -43.4848)
		(end 260.477 -43.4848)
		(stroke
			(width 0.2)
			(type default)
		)
		(fill no)
		(layer "In5.Cu")
	)
	(gr_circle
		(center 259.630672 -41.092882)
		(end 260.519672 -41.092882)
		(stroke
			(width 0.2)
			(type default)
		)
		(fill no)
		(layer "In5.Cu")
	)
	(gr_circle
		(center 259.630672 -39.592758)
		(end 260.519672 -39.592758)
		(stroke
			(width 0.2)
			(type default)
		)
		(fill no)
		(layer "In5.Cu")
	)
	(gr_circle
		(center 260.182106 -37.2364)
		(end 261.071106 -37.2364)
		(stroke
			(width 0.2)
			(type default)
		)
		(fill no)
		(layer "In5.Cu")
	)
	(gr_line
		(start 268.6812 -132.1562)
		(end 268.6812 -128.016)
		(stroke
			(width 1.016)
			(type default)
		)
		(layer "In5.Cu")
	)
	(gr_line
		(start 268.6812 -128.016)
		(end 269.4178 -127.2794)
		(stroke
			(width 1.016)
			(type default)
		)
		(layer "In5.Cu")
	)
	(gr_line
		(start 268.6812 -119.9642)
		(end 268.6812 -116.0018)
		(stroke
			(width 1.016)
			(type default)
		)
		(layer "In5.Cu")
	)
	(gr_line
		(start 268.6812 -116.0018)
		(end 269.3162 -115.3668)
		(stroke
			(width 1.016)
			(type default)
		)
		(layer "In5.Cu")
	)
	(gr_line
		(start 268.6812 -107.5182)
		(end 268.6812 -105.751122)
		(stroke
			(width 1.016)
			(type default)
		)
		(layer "In5.Cu")
	)
	(gr_line
		(start 268.6812 -105.751122)
		(end 269.125954 -105.306368)
		(stroke
			(width 1.016)
			(type default)
		)
		(layer "In5.Cu")
	)
	(gr_line
		(start 268.6812 -93.594174)
		(end 268.6812 -91.3638)
		(stroke
			(width 1.016)
			(type default)
		)
		(layer "In5.Cu")
	)
	(gr_line
		(start 268.6812 -91.3638)
		(end 269.494 -90.551)
		(stroke
			(width 1.016)
			(type default)
		)
		(layer "In5.Cu")
	)
	(gr_line
		(start 268.6812 -84.2772)
		(end 269.367 -84.963)
		(stroke
			(width 1.016)
			(type default)
		)
		(layer "In5.Cu")
	)
	(gr_line
		(start 268.6812 -79.9338)
		(end 268.6812 -84.2772)
		(stroke
			(width 1.016)
			(type default)
		)
		(layer "In5.Cu")
	)
	(gr_line
		(start 268.6812 -70.4342)
		(end 269.5194 -71.2724)
		(stroke
			(width 1.016)
			(type default)
		)
		(layer "In5.Cu")
	)
	(gr_line
		(start 268.6812 -67.2338)
		(end 268.6812 -70.4342)
		(stroke
			(width 1.016)
			(type default)
		)
		(layer "In5.Cu")
	)
	(gr_line
		(start 269.067026 -93.98)
		(end 268.6812 -93.594174)
		(stroke
			(width 1.016)
			(type default)
		)
		(layer "In5.Cu")
	)
	(gr_line
		(start 269.125954 -105.306368)
		(end 277.368 -105.306368)
		(stroke
			(width 1.016)
			(type default)
		)
		(layer "In5.Cu")
	)
	(gr_line
		(start 269.2654 -120.5484)
		(end 268.6812 -119.9642)
		(stroke
			(width 1.016)
			(type default)
		)
		(layer "In5.Cu")
	)
	(gr_line
		(start 269.3162 -115.3668)
		(end 272.8722 -115.3668)
		(stroke
			(width 1.016)
			(type default)
		)
		(layer "In5.Cu")
	)
	(gr_line
		(start 269.367 -84.963)
		(end 272.923 -84.963)
		(stroke
			(width 1.016)
			(type default)
		)
		(layer "In5.Cu")
	)
	(gr_line
		(start 269.3924 -108.2294)
		(end 268.6812 -107.5182)
		(stroke
			(width 1.016)
			(type default)
		)
		(layer "In5.Cu")
	)
	(gr_line
		(start 269.3924 -66.5226)
		(end 268.6812 -67.2338)
		(stroke
			(width 1.016)
			(type default)
		)
		(layer "In5.Cu")
	)
	(gr_line
		(start 269.4178 -127.2794)
		(end 273.0246 -127.2794)
		(stroke
			(width 1.016)
			(type default)
		)
		(layer "In5.Cu")
	)
	(gr_line
		(start 269.4432 -79.1718)
		(end 268.6812 -79.9338)
		(stroke
			(width 1.016)
			(type default)
		)
		(layer "In5.Cu")
	)
	(gr_line
		(start 269.48511 -132.96011)
		(end 268.6812 -132.1562)
		(stroke
			(width 1.016)
			(type default)
		)
		(layer "In5.Cu")
	)
	(gr_line
		(start 269.494 -90.551)
		(end 273.177 -90.551)
		(stroke
			(width 1.016)
			(type default)
		)
		(layer "In5.Cu")
	)
	(gr_line
		(start 269.5194 -71.2724)
		(end 272.9484 -71.2724)
		(stroke
			(width 1.016)
			(type default)
		)
		(layer "In5.Cu")
	)
	(gr_line
		(start 270.637 -51.562)
		(end 271.78 -50.419)
		(stroke
			(width 1.016)
			(type default)
		)
		(layer "In5.Cu")
	)
	(gr_line
		(start 271.486884 -105.306368)
		(end 271.8562 -104.937052)
		(stroke
			(width 1.016)
			(type default)
		)
		(layer "In5.Cu")
	)
	(gr_line
		(start 271.78 -50.419)
		(end 271.78 -43.18)
		(stroke
			(width 1.016)
			(type default)
		)
		(layer "In5.Cu")
	)
	(gr_line
		(start 271.78 -43.18)
		(end 274.066 -40.894)
		(stroke
			(width 1.016)
			(type default)
		)
		(layer "In5.Cu")
	)
	(gr_line
		(start 271.8562 -104.937052)
		(end 271.8562 -102.9716)
		(stroke
			(width 1.016)
			(type default)
		)
		(layer "In5.Cu")
	)
	(gr_line
		(start 271.8562 -104.937052)
		(end 272.225516 -105.306368)
		(stroke
			(width 1.016)
			(type default)
		)
		(layer "In5.Cu")
	)
	(gr_line
		(start 271.8562 -102.9716)
		(end 272.3388 -102.489)
		(stroke
			(width 1.016)
			(type default)
		)
		(layer "In5.Cu")
	)
	(gr_line
		(start 272.3388 -102.489)
		(end 273.177 -102.489)
		(stroke
			(width 1.016)
			(type default)
		)
		(layer "In5.Cu")
	)
	(gr_line
		(start 272.5547 -93.98)
		(end 269.067026 -93.98)
		(stroke
			(width 1.016)
			(type default)
		)
		(layer "In5.Cu")
	)
	(gr_line
		(start 272.5547 -93.98)
		(end 275.336 -93.98)
		(stroke
			(width 1.016)
			(type default)
		)
		(layer "In5.Cu")
	)
	(gr_circle
		(center 272.5928 -23.0886)
		(end 273.4818 -23.0886)
		(stroke
			(width 0.2)
			(type default)
		)
		(fill no)
		(layer "In5.Cu")
	)
	(gr_line
		(start 272.6944 -108.2294)
		(end 269.3924 -108.2294)
		(stroke
			(width 1.016)
			(type default)
		)
		(layer "In5.Cu")
	)
	(gr_line
		(start 272.8722 -115.3668)
		(end 273.685 -114.554)
		(stroke
			(width 1.016)
			(type default)
		)
		(layer "In5.Cu")
	)
	(gr_line
		(start 272.923 -84.963)
		(end 273.685 -85.725)
		(stroke
			(width 1.016)
			(type default)
		)
		(layer "In5.Cu")
	)
	(gr_line
		(start 272.9484 -120.5484)
		(end 269.2654 -120.5484)
		(stroke
			(width 1.016)
			(type default)
		)
		(layer "In5.Cu")
	)
	(gr_line
		(start 272.9484 -71.2724)
		(end 273.685 -72.009)
		(stroke
			(width 1.016)
			(type default)
		)
		(layer "In5.Cu")
	)
	(gr_line
		(start 272.9992 -79.1718)
		(end 269.4432 -79.1718)
		(stroke
			(width 1.016)
			(type default)
		)
		(layer "In5.Cu")
	)
	(gr_line
		(start 273.0246 -127.2794)
		(end 273.685 -126.619)
		(stroke
			(width 1.016)
			(type default)
		)
		(layer "In5.Cu")
	)
	(gr_line
		(start 273.05 -97.155)
		(end 273.05 -94.4753)
		(stroke
			(width 1.016)
			(type default)
		)
		(layer "In5.Cu")
	)
	(gr_line
		(start 273.05 -94.4753)
		(end 272.5547 -93.98)
		(stroke
			(width 1.016)
			(type default)
		)
		(layer "In5.Cu")
	)
	(gr_line
		(start 273.05 -94.4753)
		(end 273.5453 -93.98)
		(stroke
			(width 1.016)
			(type default)
		)
		(layer "In5.Cu")
	)
	(gr_line
		(start 273.177 -102.489)
		(end 273.685 -101.981)
		(stroke
			(width 1.016)
			(type default)
		)
		(layer "In5.Cu")
	)
	(gr_line
		(start 273.177 -90.551)
		(end 273.685 -90.043)
		(stroke
			(width 1.016)
			(type default)
		)
		(layer "In5.Cu")
	)
	(gr_circle
		(center 273.6088 -23.0886)
		(end 274.4978 -23.0886)
		(stroke
			(width 0.2)
			(type default)
		)
		(fill no)
		(layer "In5.Cu")
	)
	(gr_line
		(start 273.685 -126.619)
		(end 273.685 -121.285)
		(stroke
			(width 1.016)
			(type default)
		)
		(layer "In5.Cu")
	)
	(gr_line
		(start 273.685 -121.285)
		(end 272.9484 -120.5484)
		(stroke
			(width 1.016)
			(type default)
		)
		(layer "In5.Cu")
	)
	(gr_line
		(start 273.685 -114.554)
		(end 273.685 -109.22)
		(stroke
			(width 1.016)
			(type default)
		)
		(layer "In5.Cu")
	)
	(gr_line
		(start 273.685 -109.22)
		(end 272.6944 -108.2294)
		(stroke
			(width 1.016)
			(type default)
		)
		(layer "In5.Cu")
	)
	(gr_line
		(start 273.685 -101.981)
		(end 273.685 -97.79)
		(stroke
			(width 1.016)
			(type default)
		)
		(layer "In5.Cu")
	)
	(gr_line
		(start 273.685 -97.79)
		(end 273.05 -97.155)
		(stroke
			(width 1.016)
			(type default)
		)
		(layer "In5.Cu")
	)
	(gr_line
		(start 273.685 -90.043)
		(end 273.685 -85.725)
		(stroke
			(width 1.016)
			(type default)
		)
		(layer "In5.Cu")
	)
	(gr_line
		(start 273.685 -78.486)
		(end 272.9992 -79.1718)
		(stroke
			(width 1.016)
			(type default)
		)
		(layer "In5.Cu")
	)
	(gr_line
		(start 273.685 -72.009)
		(end 273.685 -78.486)
		(stroke
			(width 1.016)
			(type default)
		)
		(layer "In5.Cu")
	)
	(gr_line
		(start 274.066 -40.894)
		(end 282.321 -40.894)
		(stroke
			(width 1.016)
			(type default)
		)
		(layer "In5.Cu")
	)
	(gr_line
		(start 275.336 -93.98)
		(end 275.942552 -93.373448)
		(stroke
			(width 1.016)
			(type default)
		)
		(layer "In5.Cu")
	)
	(gr_circle
		(center 275.41855 -33.070038)
		(end 276.30755 -33.070038)
		(stroke
			(width 0.2)
			(type default)
		)
		(fill no)
		(layer "In5.Cu")
	)
	(gr_line
		(start 275.472652 -66.5226)
		(end 269.3924 -66.5226)
		(stroke
			(width 1.016)
			(type default)
		)
		(layer "In5.Cu")
	)
	(gr_line
		(start 275.472652 -66.5226)
		(end 275.942552 -66.9925)
		(stroke
			(width 1.016)
			(type default)
		)
		(layer "In5.Cu")
	)
	(gr_line
		(start 275.942552 -93.373448)
		(end 275.942552 -51.209448)
		(stroke
			(width 1.016)
			(type default)
		)
		(layer "In5.Cu")
	)
	(gr_line
		(start 275.942552 -66.0527)
		(end 275.472652 -66.5226)
		(stroke
			(width 1.016)
			(type default)
		)
		(layer "In5.Cu")
	)
	(gr_line
		(start 275.942552 -51.209448)
		(end 280.4795 -46.6725)
		(stroke
			(width 1.016)
			(type default)
		)
		(layer "In5.Cu")
	)
	(gr_line
		(start 276.833838 -132.96011)
		(end 298.533566 -132.96011)
		(stroke
			(width 1.016)
			(type default)
		)
		(layer "In5.Cu")
	)
	(gr_line
		(start 277.368 -105.306368)
		(end 278.19985 -106.138218)
		(stroke
			(width 1.016)
			(type default)
		)
		(layer "In5.Cu")
	)
	(gr_line
		(start 277.368 -105.306368)
		(end 278.19985 -104.474518)
		(stroke
			(width 1.016)
			(type default)
		)
		(layer "In5.Cu")
	)
	(gr_circle
		(center 277.368 -20.955)
		(end 278.257 -20.955)
		(stroke
			(width 0.2)
			(type default)
		)
		(fill no)
		(layer "In5.Cu")
	)
	(gr_line
		(start 278.19985 -146.99996)
		(end 237.109 -146.99996)
		(stroke
			(width 2.032)
			(type default)
		)
		(layer "In5.Cu")
	)
	(gr_line
		(start 278.19985 -146.99996)
		(end 278.19985 -132.96011)
		(stroke
			(width 1.016)
			(type default)
		)
		(layer "In5.Cu")
	)
	(gr_line
		(start 278.19985 -145.508218)
		(end 276.833838 -146.87423)
		(stroke
			(width 1.016)
			(type default)
		)
		(layer "In5.Cu")
	)
	(gr_line
		(start 278.19985 -145.508218)
		(end 279.565862 -146.87423)
		(stroke
			(width 1.016)
			(type default)
		)
		(layer "In5.Cu")
	)
	(gr_line
		(start 278.19985 -134.326122)
		(end 276.833838 -132.96011)
		(stroke
			(width 1.016)
			(type default)
		)
		(layer "In5.Cu")
	)
	(gr_line
		(start 278.19985 -134.326122)
		(end 279.565862 -132.96011)
		(stroke
			(width 1.016)
			(type default)
		)
		(layer "In5.Cu")
	)
	(gr_line
		(start 278.19985 -132.96011)
		(end 269.48511 -132.96011)
		(stroke
			(width 1.016)
			(type default)
		)
		(layer "In5.Cu")
	)
	(gr_line
		(start 278.19985 -131.594098)
		(end 276.833838 -132.96011)
		(stroke
			(width 1.016)
			(type default)
		)
		(layer "In5.Cu")
	)
	(gr_line
		(start 278.19985 -131.594098)
		(end 279.565862 -132.96011)
		(stroke
			(width 1.016)
			(type default)
		)
		(layer "In5.Cu")
	)
	(gr_line
		(start 278.19985 -97.85985)
		(end 279.6921 -96.3676)
		(stroke
			(width 1.016)
			(type default)
		)
		(layer "In5.Cu")
	)
	(gr_line
		(start 278.19985 -94.87535)
		(end 279.6921 -96.3676)
		(stroke
			(width 1.016)
			(type default)
		)
		(layer "In5.Cu")
	)
	(gr_line
		(start 278.19985 -66.675)
		(end 278.19985 -146.99996)
		(stroke
			(width 1.016)
			(type default)
		)
		(layer "In5.Cu")
	)
	(gr_line
		(start 278.19985 -66.675)
		(end 278.19985 -58.268108)
		(stroke
			(width 1.016)
			(type default)
		)
		(layer "In5.Cu")
	)
	(gr_line
		(start 278.19985 -61.16574)
		(end 279.648666 -59.716924)
		(stroke
			(width 1.016)
			(type default)
		)
		(layer "In5.Cu")
	)
	(gr_line
		(start 278.19985 -58.268108)
		(end 282.02763 -54.440328)
		(stroke
			(width 1.016)
			(type default)
		)
		(layer "In5.Cu")
	)
	(gr_line
		(start 278.318976 -59.716924)
		(end 280.367994 -59.716924)
		(stroke
			(width 1.016)
			(type default)
		)
		(layer "In5.Cu")
	)
	(gr_line
		(start 279.648666 -59.716924)
		(end 278.19985 -58.268108)
		(stroke
			(width 1.016)
			(type default)
		)
		(layer "In5.Cu")
	)
	(gr_line
		(start 280.4795 -46.6725)
		(end 295.7195 -46.6725)
		(stroke
			(width 1.016)
			(type default)
		)
		(layer "In5.Cu")
	)
	(gr_line
		(start 282.02763 -54.440328)
		(end 292.362636 -54.440328)
		(stroke
			(width 1.016)
			(type default)
		)
		(layer "In5.Cu")
	)
	(gr_line
		(start 282.321 -40.894)
		(end 283.845 -39.37)
		(stroke
			(width 1.016)
			(type default)
		)
		(layer "In5.Cu")
	)
	(gr_circle
		(center 283.4132 -32.1564)
		(end 284.3022 -32.1564)
		(stroke
			(width 0.2)
			(type default)
		)
		(fill no)
		(layer "In5.Cu")
	)
	(gr_line
		(start 283.845 -39.37)
		(end 283.845 -30.099)
		(stroke
			(width 1.016)
			(type default)
		)
		(layer "In5.Cu")
	)
	(gr_line
		(start 283.845 -30.099)
		(end 284.353 -29.591)
		(stroke
			(width 1.016)
			(type default)
		)
		(layer "In5.Cu")
	)
	(gr_line
		(start 284.353 -29.591)
		(end 289.296856 -29.591)
		(stroke
			(width 1.016)
			(type default)
		)
		(layer "In5.Cu")
	)
	(gr_line
		(start 289.296856 -29.591)
		(end 289.687 -29.981144)
		(stroke
			(width 1.016)
			(type default)
		)
		(layer "In5.Cu")
	)
	(gr_line
		(start 289.687 -40.132)
		(end 290.449 -40.894)
		(stroke
			(width 1.016)
			(type default)
		)
		(layer "In5.Cu")
	)
	(gr_line
		(start 289.687 -29.981144)
		(end 289.687 -40.132)
		(stroke
			(width 1.016)
			(type default)
		)
		(layer "In5.Cu")
	)
	(gr_line
		(start 290.449 -40.894)
		(end 294.767 -40.894)
		(stroke
			(width 1.016)
			(type default)
		)
		(layer "In5.Cu")
	)
	(gr_line
		(start 291.200078 -59.716924)
		(end 279.648666 -59.716924)
		(stroke
			(width 1.016)
			(type default)
		)
		(layer "In5.Cu")
	)
	(gr_line
		(start 292.362636 -54.440328)
		(end 296.0878 -50.715164)
		(stroke
			(width 1.016)
			(type default)
		)
		(layer "In5.Cu")
	)
	(gr_circle
		(center 294.1828 -34.9758)
		(end 295.0718 -34.9758)
		(stroke
			(width 0.2)
			(type default)
		)
		(fill no)
		(layer "In5.Cu")
	)
	(gr_line
		(start 294.767 -40.894)
		(end 296.0878 -42.2148)
		(stroke
			(width 1.016)
			(type default)
		)
		(layer "In5.Cu")
	)
	(gr_line
		(start 295.2623 -46.6725)
		(end 296.0878 -47.498)
		(stroke
			(width 1.016)
			(type default)
		)
		(layer "In5.Cu")
	)
	(gr_line
		(start 296.0878 -50.715164)
		(end 296.0878 -48.472344)
		(stroke
			(width 1.016)
			(type default)
		)
		(layer "In5.Cu")
	)
	(gr_line
		(start 296.0878 -45.847)
		(end 295.2623 -46.6725)
		(stroke
			(width 1.016)
			(type default)
		)
		(layer "In5.Cu")
	)
	(gr_line
		(start 296.0878 -45.847)
		(end 296.0878 -48.472344)
		(stroke
			(width 1.016)
			(type default)
		)
		(layer "In5.Cu")
	)
	(gr_line
		(start 296.0878 -42.2148)
		(end 296.0878 -45.847)
		(stroke
			(width 1.016)
			(type default)
		)
		(layer "In5.Cu")
	)
	(gr_circle
		(center 297.561 -54.356)
		(end 298.45 -54.356)
		(stroke
			(width 0.2)
			(type default)
		)
		(fill no)
		(layer "In5.Cu")
	)
	(gr_circle
		(center 297.561 -53.594)
		(end 298.45 -53.594)
		(stroke
			(width 0.2)
			(type default)
		)
		(fill no)
		(layer "In5.Cu")
	)
	(gr_circle
		(center 297.561 -52.832)
		(end 298.45 -52.832)
		(stroke
			(width 0.2)
			(type default)
		)
		(fill no)
		(layer "In5.Cu")
	)
	(gr_circle
		(center 297.561 -52.07)
		(end 298.45 -52.07)
		(stroke
			(width 0.2)
			(type default)
		)
		(fill no)
		(layer "In5.Cu")
	)
	(gr_line
		(start 298.271184 -96.3676)
		(end 278.19985 -96.3676)
		(stroke
			(width 1.016)
			(type default)
		)
		(layer "In5.Cu")
	)
	(gr_circle
		(center 298.323 -54.356)
		(end 299.212 -54.356)
		(stroke
			(width 0.2)
			(type default)
		)
		(fill no)
		(layer "In5.Cu")
	)
	(gr_circle
		(center 298.323 -53.594)
		(end 299.212 -53.594)
		(stroke
			(width 0.2)
			(type default)
		)
		(fill no)
		(layer "In5.Cu")
	)
	(gr_circle
		(center 298.323 -52.832)
		(end 299.212 -52.832)
		(stroke
			(width 0.2)
			(type default)
		)
		(fill no)
		(layer "In5.Cu")
	)
	(gr_circle
		(center 298.323 -52.07)
		(end 299.212 -52.07)
		(stroke
			(width 0.2)
			(type default)
		)
		(fill no)
		(layer "In5.Cu")
	)
	(gr_line
		(start 298.525184 -59.716924)
		(end 291.200078 -59.716924)
		(stroke
			(width 1.016)
			(type default)
		)
		(layer "In5.Cu")
	)
	(gr_line
		(start 298.533566 -132.96011)
		(end 299.763434 -131.730242)
		(stroke
			(width 1.016)
			(type default)
		)
		(layer "In5.Cu")
	)
	(gr_line
		(start 299.763434 -131.730242)
		(end 299.763434 -126.359666)
		(stroke
			(width 1.016)
			(type default)
		)
		(layer "In5.Cu")
	)
	(gr_line
		(start 299.763434 -127.672338)
		(end 299.763434 -126.219966)
		(stroke
			(width 1.016)
			(type default)
		)
		(layer "In5.Cu")
	)
	(gr_line
		(start 299.763434 -126.359666)
		(end 299.763434 -60.955174)
		(stroke
			(width 1.016)
			(type default)
		)
		(layer "In5.Cu")
	)
	(gr_line
		(start 299.763434 -126.219966)
		(end 303.6824 -122.301)
		(stroke
			(width 1.016)
			(type default)
		)
		(layer "In5.Cu")
	)
	(gr_line
		(start 299.763434 -125.046994)
		(end 299.763434 -126.359666)
		(stroke
			(width 1.016)
			(type default)
		)
		(layer "In5.Cu")
	)
	(gr_line
		(start 299.763434 -125.046994)
		(end 299.763434 -122.1994)
		(stroke
			(width 1.016)
			(type default)
		)
		(layer "In5.Cu")
	)
	(gr_line
		(start 299.763434 -97.85985)
		(end 298.271184 -96.3676)
		(stroke
			(width 1.016)
			(type default)
		)
		(layer "In5.Cu")
	)
	(gr_line
		(start 299.763434 -96.3676)
		(end 298.271184 -96.3676)
		(stroke
			(width 1.016)
			(type default)
		)
		(layer "In5.Cu")
	)
	(gr_line
		(start 299.763434 -94.87535)
		(end 298.271184 -96.3676)
		(stroke
			(width 1.016)
			(type default)
		)
		(layer "In5.Cu")
	)
	(gr_line
		(start 299.763434 -60.955174)
		(end 298.525184 -59.716924)
		(stroke
			(width 1.016)
			(type default)
		)
		(layer "In5.Cu")
	)
	(gr_line
		(start 300.498764 -73.6092)
		(end 299.906436 -74.201528)
		(stroke
			(width 1.016)
			(type default)
		)
		(layer "In5.Cu")
	)
	(gr_line
		(start 300.498764 -73.6092)
		(end 299.906436 -73.016872)
		(stroke
			(width 1.016)
			(type default)
		)
		(layer "In5.Cu")
	)
	(gr_line
		(start 301.084742 -122.1994)
		(end 299.763434 -123.520708)
		(stroke
			(width 1.016)
			(type default)
		)
		(layer "In5.Cu")
	)
	(gr_line
		(start 301.084742 -122.1994)
		(end 299.763434 -120.878092)
		(stroke
			(width 1.016)
			(type default)
		)
		(layer "In5.Cu")
	)
	(gr_line
		(start 301.447708 -122.503692)
		(end 300.1264 -123.825)
		(stroke
			(width 1.016)
			(type default)
		)
		(layer "In5.Cu")
	)
	(gr_line
		(start 302.509428 -122.301)
		(end 299.763434 -125.046994)
		(stroke
			(width 1.016)
			(type default)
		)
		(layer "In5.Cu")
	)
	(gr_line
		(start 303.6824 -122.301)
		(end 302.509428 -122.301)
		(stroke
			(width 1.016)
			(type default)
		)
		(layer "In5.Cu")
	)
	(gr_line
		(start 306.451 -73.6092)
		(end 300.498764 -73.6092)
		(stroke
			(width 1.016)
			(type default)
		)
		(layer "In5.Cu")
	)
	(gr_line
		(start 308.6608 -75.819)
		(end 306.451 -73.6092)
		(stroke
			(width 1.016)
			(type default)
		)
		(layer "In5.Cu")
	)
	(gr_line
		(start 308.6608 -75.819)
		(end 319.8876 -75.819)
		(stroke
			(width 1.016)
			(type default)
		)
		(layer "In5.Cu")
	)
	(gr_circle
		(center 311.410096 -72.879966)
		(end 312.809128 -72.879966)
		(stroke
			(width 0.2)
			(type default)
		)
		(fill no)
		(layer "In5.Cu")
	)
	(gr_line
		(start 319.6336 -122.1994)
		(end 299.763434 -122.1994)
		(stroke
			(width 1.016)
			(type default)
		)
		(layer "In5.Cu")
	)
	(gr_line
		(start 319.8876 -75.819)
		(end 320.929 -76.8604)
		(stroke
			(width 1.016)
			(type default)
		)
		(layer "In5.Cu")
	)
	(gr_line
		(start 320.929 -120.904)
		(end 319.6336 -122.1994)
		(stroke
			(width 1.016)
			(type default)
		)
		(layer "In5.Cu")
	)
	(gr_line
		(start 320.929 -76.8604)
		(end 320.929 -120.904)
		(stroke
			(width 1.016)
			(type default)
		)
		(layer "In5.Cu")
	)
	(gr_line
		(start 323.000116 -146.99996)
		(end 278.19985 -146.99996)
		(stroke
			(width 2.032)
			(type default)
		)
		(layer "In5.Cu")
	)
	(gr_arc
		(start 323.000116 -146.99996)
		(mid 326.535643 -145.535497)
		(end 328.000106 -141.99997)
		(stroke
			(width 2.032)
			(type default)
		)
		(layer "In5.Cu")
	)
	(gr_line
		(start 323.000116 0)
		(end 4.99999 0)
		(stroke
			(width 2.032)
			(type default)
		)
		(layer "In5.Cu")
	)
	(gr_arc
		(start 328.000106 -4.99999)
		(mid 326.53564 -1.464464)
		(end 323.000116 0)
		(stroke
			(width 2.032)
			(type default)
		)
		(layer "In5.Cu")
	)
	(gr_line
		(start 328.000106 -4.99999)
		(end 328.000106 -141.99997)
		(stroke
			(width 2.032)
			(type default)
		)
		(layer "In5.Cu")
	)
	(gr_poly
		(pts
			(arc
				(start 298.302172 -132.452364)
				(mid 298.321695 -132.448463)
				(end 298.33824 -132.437378)
			)
			(arc
				(start 299.240448 -131.53517)
				(mid 299.251559 -131.518636)
				(end 299.255434 -131.499102)
			)
			(xy 299.255434 -122.167396) (xy 299.252894 -122.156474)
			(arc
				(start 299.250354 -122.15114)
				(mid 299.221372 -122.069537)
				(end 299.211492 -121.9835)
			)
			(arc
				(start 299.211492 -121.9835)
				(mid 299.221323 -121.897451)
				(end 299.250354 -121.81586)
			)
			(xy 299.252894 -121.810526) (xy 299.255434 -121.799604) (xy 299.255434 -121.278396) (xy 299.252894 -121.267474)
			(arc
				(start 299.250354 -121.26214)
				(mid 299.221372 -121.180537)
				(end 299.211492 -121.0945)
			)
			(arc
				(start 299.211492 -121.0945)
				(mid 299.221323 -121.008451)
				(end 299.250354 -120.92686)
			)
			(xy 299.252894 -120.921526) (xy 299.255434 -120.910604) (xy 299.255434 -120.389396) (xy 299.252894 -120.378474)
			(arc
				(start 299.250354 -120.37314)
				(mid 299.221372 -120.291537)
				(end 299.211492 -120.2055)
			)
			(arc
				(start 299.211492 -120.2055)
				(mid 299.221323 -120.119451)
				(end 299.250354 -120.03786)
			)
			(xy 299.252894 -120.032526) (xy 299.255434 -120.021604) (xy 299.255434 -119.500396) (xy 299.252894 -119.489474)
			(arc
				(start 299.250354 -119.48414)
				(mid 299.221372 -119.402537)
				(end 299.211492 -119.3165)
			)
			(arc
				(start 299.211492 -119.3165)
				(mid 299.221323 -119.230451)
				(end 299.250354 -119.14886)
			)
			(xy 299.252894 -119.143526) (xy 299.255434 -119.132604)
			(arc
				(start 299.255434 -98.091244)
				(mid 299.251533 -98.071721)
				(end 299.240448 -98.055176)
			)
			(arc
				(start 298.075858 -96.890586)
				(mid 298.059324 -96.879475)
				(end 298.03979 -96.8756)
			)
			(arc
				(start 279.923494 -96.8756)
				(mid 279.903971 -96.879501)
				(end 279.887426 -96.890586)
			)
			(arc
				(start 278.722836 -98.055176)
				(mid 278.711725 -98.07171)
				(end 278.70785 -98.091244)
			)
			(arc
				(start 278.70785 -131.362958)
				(mid 278.711751 -131.382481)
				(end 278.722836 -131.399026)
			)
			(arc
				(start 279.761188 -132.437378)
				(mid 279.777722 -132.448489)
				(end 279.797256 -132.452364)
			)
		)
		(stroke
			(width 0)
			(type solid)
		)
		(fill yes)
		(layer "In6.Cu")
		(net "P52V_HS1_DRAIN_1")
	)
	(gr_poly
		(pts
			(arc
				(start 298.03979 -95.8596)
				(mid 298.059313 -95.855699)
				(end 298.075858 -95.844614)
			)
			(arc
				(start 299.240448 -94.680024)
				(mid 299.251559 -94.66349)
				(end 299.255434 -94.643956)
			)
			(arc
				(start 299.255434 -86.018878)
				(mid 299.25339 -86.004863)
				(end 299.24756 -85.991954)
			)
			(arc
				(start 299.24756 -85.991954)
				(mid 299.203848 -85.894376)
				(end 299.188886 -85.7885)
			)
			(arc
				(start 299.188886 -85.7885)
				(mid 299.203802 -85.682611)
				(end 299.24756 -85.585046)
			)
			(arc
				(start 299.24756 -85.585046)
				(mid 299.253395 -85.572139)
				(end 299.255434 -85.558122)
			)
			(arc
				(start 299.255434 -85.129878)
				(mid 299.25339 -85.115863)
				(end 299.24756 -85.102954)
			)
			(arc
				(start 299.24756 -85.102954)
				(mid 299.203848 -85.005376)
				(end 299.188886 -84.8995)
			)
			(arc
				(start 299.188886 -84.8995)
				(mid 299.203802 -84.793611)
				(end 299.24756 -84.696046)
			)
			(arc
				(start 299.24756 -84.696046)
				(mid 299.253395 -84.683139)
				(end 299.255434 -84.669122)
			)
			(arc
				(start 299.255434 -84.240878)
				(mid 299.25339 -84.226863)
				(end 299.24756 -84.213954)
			)
			(arc
				(start 299.24756 -84.213954)
				(mid 299.203848 -84.116376)
				(end 299.188886 -84.0105)
			)
			(arc
				(start 299.188886 -84.0105)
				(mid 299.203802 -83.904611)
				(end 299.24756 -83.807046)
			)
			(arc
				(start 299.24756 -83.807046)
				(mid 299.253395 -83.794139)
				(end 299.255434 -83.780122)
			)
			(arc
				(start 299.255434 -83.351878)
				(mid 299.25339 -83.337863)
				(end 299.24756 -83.324954)
			)
			(arc
				(start 299.24756 -83.324954)
				(mid 299.203848 -83.227376)
				(end 299.188886 -83.1215)
			)
			(arc
				(start 299.188886 -83.1215)
				(mid 299.203802 -83.015611)
				(end 299.24756 -82.918046)
			)
			(arc
				(start 299.24756 -82.918046)
				(mid 299.253395 -82.905139)
				(end 299.255434 -82.891122)
			)
			(xy 299.255434 -78.790546)
			(arc
				(start 299.254672 -78.786482)
				(mid 299.251029 -78.755972)
				(end 299.249846 -78.725268)
			)
			(arc
				(start 299.249846 -78.725268)
				(mid 299.251022 -78.694563)
				(end 299.254672 -78.664054)
			)
			(xy 299.255434 -78.65999) (xy 299.255434 -77.774546)
			(arc
				(start 299.254672 -77.770482)
				(mid 299.251029 -77.739972)
				(end 299.249846 -77.709268)
			)
			(arc
				(start 299.249846 -77.709268)
				(mid 299.251022 -77.678563)
				(end 299.254672 -77.648054)
			)
			(xy 299.255434 -77.64399)
			(arc
				(start 299.255434 -61.186822)
				(mid 299.251533 -61.167299)
				(end 299.240448 -61.150754)
			)
			(arc
				(start 298.329858 -60.240164)
				(mid 298.313324 -60.229053)
				(end 298.29379 -60.225178)
			)
			(arc
				(start 279.88006 -60.225178)
				(mid 279.860537 -60.229079)
				(end 279.843992 -60.240164)
			)
			(arc
				(start 278.722836 -61.36132)
				(mid 278.711725 -61.377854)
				(end 278.70785 -61.397388)
			)
			(arc
				(start 278.70785 -94.643956)
				(mid 278.711751 -94.663479)
				(end 278.722836 -94.680024)
			)
			(arc
				(start 279.887426 -95.844614)
				(mid 279.90396 -95.855725)
				(end 279.923494 -95.8596)
			)
		)
		(stroke
			(width 0)
			(type solid)
		)
		(fill yes)
		(layer "In6.Cu")
		(net "P52V_HS1_DRAIN_2")
	)
	(gr_poly
		(pts
			(xy 319.402206 -121.6914) (xy 319.412276 -121.690976) (xy 319.430879 -121.68326) (xy 319.438274 -121.676414)
			(xy 320.406014 -120.708674) (xy 320.412866 -120.701278) (xy 320.420604 -120.682679) (xy 320.421 -120.672606)
			(xy 320.421 -77.091794) (xy 320.420576 -77.081724) (xy 320.41286 -77.063121) (xy 320.406014 -77.055726)
			(xy 319.692274 -76.341986) (xy 319.684878 -76.335134) (xy 319.666279 -76.327396) (xy 319.656206 -76.327)
			(xy 308.6608 -76.327) (xy 308.62754 -76.326479) (xy 308.56159 -76.317791) (xy 308.497339 -76.300566)
			(xy 308.435888 -76.275097) (xy 308.378289 -76.241821) (xy 308.325529 -76.201308) (xy 308.301644 -76.178156)
			(xy 306.185824 -74.062336) (xy 306.178423 -74.055498) (xy 306.159824 -74.047785) (xy 306.149756 -74.04735)
			(xy 300.86427 -74.04735) (xy 300.854203 -74.04778) (xy 300.835612 -74.055508) (xy 300.828202 -74.062336)
			(xy 300.28642 -74.604118) (xy 300.279574 -74.611517) (xy 300.271843 -74.630115) (xy 300.271434 -74.640186)
			(xy 300.271434 -88.45423) (xy 300.271729 -88.462103) (xy 300.276515 -88.477104) (xy 300.280832 -88.483694)
			(xy 300.295759 -88.505354) (xy 300.32016 -88.551955) (xy 300.337926 -88.601467) (xy 300.348721 -88.652951)
			(xy 300.352339 -88.705429) (xy 300.348712 -88.757907) (xy 300.33791 -88.809389) (xy 300.320136 -88.858899)
			(xy 300.295729 -88.905496) (xy 300.280832 -88.927178) (xy 300.276501 -88.933762) (xy 300.271707 -88.948766)
			(xy 300.271434 -88.956642) (xy 300.271434 -101.454966) (xy 307.269651 -101.454966) (xy 307.273647 -101.2731)
			(xy 307.285627 -101.091585) (xy 307.305569 -100.910772) (xy 307.333434 -100.731009) (xy 307.369168 -100.552644)
			(xy 307.412701 -100.37602) (xy 307.463951 -100.201479) (xy 307.522818 -100.029357) (xy 307.589189 -99.859987)
			(xy 307.662935 -99.693696) (xy 307.743914 -99.530805) (xy 307.831969 -99.371628) (xy 307.926932 -99.216472)
			(xy 308.028617 -99.065637) (xy 308.13683 -98.919415) (xy 308.251362 -98.778086) (xy 308.37199 -98.641925)
			(xy 308.498483 -98.511193) (xy 308.630596 -98.386144) (xy 308.768074 -98.267018) (xy 308.910652 -98.154046)
			(xy 309.058055 -98.047446) (xy 309.209998 -97.947423) (xy 309.366187 -97.854171) (xy 309.526322 -97.767869)
			(xy 309.690093 -97.688684) (xy 309.857184 -97.616769) (xy 310.027272 -97.552263) (xy 310.20003 -97.495291)
			(xy 310.375124 -97.445961) (xy 310.552215 -97.40437) (xy 310.730962 -97.370597) (xy 310.91102 -97.344709)
			(xy 311.092042 -97.326754) (xy 311.273677 -97.316768) (xy 311.455576 -97.31477) (xy 311.637387 -97.320764)
			(xy 311.818759 -97.334737) (xy 311.999343 -97.356664) (xy 312.178789 -97.386502) (xy 312.356751 -97.424193)
			(xy 312.532886 -97.469664) (xy 312.706854 -97.522828) (xy 312.878318 -97.583582) (xy 313.046949 -97.651809)
			(xy 313.21242 -97.727377) (xy 313.374412 -97.81014) (xy 313.532612 -97.899939) (xy 313.686715 -97.9966)
			(xy 313.836424 -98.099937) (xy 313.981449 -98.209749) (xy 314.121511 -98.325826) (xy 314.256339 -98.447943)
			(xy 314.385673 -98.575864) (xy 314.509264 -98.709343) (xy 314.626872 -98.848121) (xy 314.738271 -98.991932)
			(xy 314.843246 -99.140496) (xy 314.941594 -99.293528) (xy 315.033125 -99.450733) (xy 315.117663 -99.611806)
			(xy 315.195044 -99.776437) (xy 315.265119 -99.944308) (xy 315.327753 -100.115095) (xy 315.382824 -100.288468)
			(xy 315.430228 -100.464093) (xy 315.469871 -100.64163) (xy 315.501678 -100.820737) (xy 315.525587 -101.001069)
			(xy 315.541552 -101.182277) (xy 315.549542 -101.364011) (xy 315.550042 -101.454966) (xy 315.549542 -101.545921)
			(xy 315.541552 -101.727655) (xy 315.525587 -101.908863) (xy 315.501678 -102.089195) (xy 315.469871 -102.268302)
			(xy 315.430228 -102.445839) (xy 315.382824 -102.621464) (xy 315.327753 -102.794837) (xy 315.265119 -102.965624)
			(xy 315.195044 -103.133495) (xy 315.117663 -103.298126) (xy 315.033125 -103.459199) (xy 314.941594 -103.616404)
			(xy 314.843246 -103.769436) (xy 314.738271 -103.918) (xy 314.626872 -104.061811) (xy 314.509264 -104.200589)
			(xy 314.385673 -104.334068) (xy 314.256339 -104.461989) (xy 314.121511 -104.584106) (xy 313.981449 -104.700183)
			(xy 313.836424 -104.809995) (xy 313.686715 -104.913332) (xy 313.532612 -105.009993) (xy 313.374412 -105.099792)
			(xy 313.21242 -105.182555) (xy 313.046949 -105.258123) (xy 312.878318 -105.32635) (xy 312.706854 -105.387104)
			(xy 312.532886 -105.440268) (xy 312.356751 -105.485739) (xy 312.178789 -105.52343) (xy 311.999343 -105.553268)
			(xy 311.818759 -105.575195) (xy 311.637387 -105.589168) (xy 311.455576 -105.595162) (xy 311.273677 -105.593164)
			(xy 311.092042 -105.583178) (xy 310.91102 -105.565223) (xy 310.730962 -105.539335) (xy 310.552215 -105.505562)
			(xy 310.375124 -105.463971) (xy 310.20003 -105.414641) (xy 310.027272 -105.357669) (xy 309.857184 -105.293163)
			(xy 309.690093 -105.221248) (xy 309.526322 -105.142063) (xy 309.366187 -105.055761) (xy 309.209998 -104.962509)
			(xy 309.058055 -104.862486) (xy 308.910652 -104.755886) (xy 308.768074 -104.642914) (xy 308.630596 -104.523788)
			(xy 308.498483 -104.398739) (xy 308.37199 -104.268007) (xy 308.251362 -104.131846) (xy 308.13683 -103.990517)
			(xy 308.028617 -103.844295) (xy 307.926932 -103.69346) (xy 307.831969 -103.538304) (xy 307.743914 -103.379127)
			(xy 307.662935 -103.216236) (xy 307.589189 -103.049945) (xy 307.522818 -102.880575) (xy 307.463951 -102.708453)
			(xy 307.412701 -102.533912) (xy 307.369168 -102.357288) (xy 307.333434 -102.178923) (xy 307.305569 -101.99916)
			(xy 307.285627 -101.818347) (xy 307.273647 -101.636832) (xy 307.269651 -101.454966) (xy 300.271434 -101.454966)
			(xy 300.271434 -120.646698) (xy 300.271857 -120.656768) (xy 300.279575 -120.67537) (xy 300.28642 -120.682766)
			(xy 301.280068 -121.676414) (xy 301.287466 -121.683259) (xy 301.306065 -121.690982) (xy 301.316136 -121.6914)
		)
		(stroke
			(width 0)
			(type solid)
		)
		(fill yes)
		(layer "In6.Cu")
		(net "P52V_1")
	)
	(gr_poly
		(pts
			(xy 326.00011 -166.271956) (xy 326.055917 -166.271446) (xy 326.167218 -166.263105) (xy 326.277585 -166.246469)
			(xy 326.386399 -166.221631) (xy 326.493054 -166.188731) (xy 326.596951 -166.147953) (xy 326.697511 -166.099525)
			(xy 326.79417 -166.043717) (xy 326.886389 -165.980841) (xy 326.973651 -165.91125) (xy 327.055468 -165.835332)
			(xy 327.131383 -165.753513) (xy 327.200971 -165.666249) (xy 327.263843 -165.574028) (xy 327.319648 -165.477367)
			(xy 327.368073 -165.376806) (xy 327.408848 -165.272907) (xy 327.441744 -165.166251) (xy 327.466578 -165.057436)
			(xy 327.48321 -164.947068) (xy 327.491548 -164.835767) (xy 327.492106 -164.77996) (xy 327.492106 -150.999952)
			(xy 327.491583 -150.944146) (xy 327.483238 -150.832846) (xy 327.4666 -150.722481) (xy 327.441761 -150.613668)
			(xy 327.408861 -150.507016) (xy 327.368082 -150.40312) (xy 327.319653 -150.302562) (xy 327.263845 -150.205904)
			(xy 327.20097 -150.113687) (xy 327.13138 -150.026426) (xy 327.055463 -149.94461) (xy 326.973645 -149.868695)
			(xy 326.886382 -149.799107) (xy 326.794164 -149.736235) (xy 326.697504 -149.680429) (xy 326.596945 -149.632003)
			(xy 326.493048 -149.591227) (xy 326.386395 -149.558329) (xy 326.277581 -149.533493) (xy 326.167216 -149.516857)
			(xy 326.055916 -149.508516) (xy 326.00011 -149.507956) (xy 154.399996 -149.507956) (xy 154.344188 -149.508478)
			(xy 154.232885 -149.516819) (xy 154.122517 -149.533454) (xy 154.0137 -149.558291) (xy 153.907043 -149.591189)
			(xy 153.803144 -149.631966) (xy 153.702581 -149.680394) (xy 153.605919 -149.7362) (xy 153.513698 -149.799075)
			(xy 153.426433 -149.868664) (xy 153.344612 -149.944581) (xy 153.268693 -150.026399) (xy 153.199101 -150.113662)
			(xy 153.136224 -150.205882) (xy 153.080414 -150.302543) (xy 153.031984 -150.403103) (xy 152.991204 -150.507002)
			(xy 152.958302 -150.613657) (xy 152.933462 -150.722474) (xy 152.916824 -150.832842) (xy 152.908479 -150.944144)
			(xy 152.908 -150.999952) (xy 152.908 -161.844536) (xy 155.304225 -161.844536) (xy 155.304225 -161.715396)
			(xy 155.312175 -161.586501) (xy 155.328045 -161.458341) (xy 155.351774 -161.3314) (xy 155.383273 -161.206161)
			(xy 155.422422 -161.083098) (xy 155.469073 -160.962679) (xy 155.523048 -160.84536) (xy 155.584143 -160.731586)
			(xy 155.652126 -160.621789) (xy 155.72674 -160.516386) (xy 155.807701 -160.415776) (xy 155.894701 -160.320341)
			(xy 155.987412 -160.230442) (xy 156.085482 -160.146421) (xy 156.188537 -160.068597) (xy 156.296188 -159.997265)
			(xy 156.408027 -159.932695) (xy 156.523628 -159.875133) (xy 156.642553 -159.824796) (xy 156.764352 -159.781876)
			(xy 156.888562 -159.746535) (xy 157.014711 -159.718908) (xy 157.142323 -159.699099) (xy 157.270912 -159.687183)
			(xy 157.39999 -159.683207) (xy 157.529068 -159.687183) (xy 157.657657 -159.699099) (xy 157.785269 -159.718908)
			(xy 157.911418 -159.746535) (xy 158.035628 -159.781876) (xy 158.157427 -159.824796) (xy 158.276352 -159.875133)
			(xy 158.391953 -159.932695) (xy 158.503792 -159.997265) (xy 158.611443 -160.068597) (xy 158.714498 -160.146421)
			(xy 158.812568 -160.230442) (xy 158.905279 -160.320341) (xy 158.992279 -160.415776) (xy 159.07324 -160.516386)
			(xy 159.147854 -160.621789) (xy 159.215837 -160.731586) (xy 159.276932 -160.84536) (xy 159.330907 -160.962679)
			(xy 159.377558 -161.083098) (xy 159.416707 -161.206161) (xy 159.448206 -161.3314) (xy 159.471935 -161.458341)
			(xy 159.487805 -161.586501) (xy 159.495755 -161.715396) (xy 159.496252 -161.779966) (xy 159.495755 -161.844536)
			(xy 320.904351 -161.844536) (xy 320.904351 -161.715396) (xy 320.912301 -161.586501) (xy 320.928171 -161.458341)
			(xy 320.9519 -161.3314) (xy 320.983399 -161.206161) (xy 321.022548 -161.083098) (xy 321.069199 -160.962679)
			(xy 321.123174 -160.84536) (xy 321.184269 -160.731586) (xy 321.252252 -160.621789) (xy 321.326866 -160.516386)
			(xy 321.407827 -160.415776) (xy 321.494827 -160.320341) (xy 321.587538 -160.230442) (xy 321.685608 -160.146421)
			(xy 321.788663 -160.068597) (xy 321.896314 -159.997265) (xy 322.008153 -159.932695) (xy 322.123754 -159.875133)
			(xy 322.242679 -159.824796) (xy 322.364478 -159.781876) (xy 322.488688 -159.746535) (xy 322.614837 -159.718908)
			(xy 322.742449 -159.699099) (xy 322.871038 -159.687183) (xy 323.000116 -159.683207) (xy 323.129194 -159.687183)
			(xy 323.257783 -159.699099) (xy 323.385395 -159.718908) (xy 323.511544 -159.746535) (xy 323.635754 -159.781876)
			(xy 323.757553 -159.824796) (xy 323.876478 -159.875133) (xy 323.992079 -159.932695) (xy 324.103918 -159.997265)
			(xy 324.211569 -160.068597) (xy 324.314624 -160.146421) (xy 324.412694 -160.230442) (xy 324.505405 -160.320341)
			(xy 324.592405 -160.415776) (xy 324.673366 -160.516386) (xy 324.74798 -160.621789) (xy 324.815963 -160.731586)
			(xy 324.877058 -160.84536) (xy 324.931033 -160.962679) (xy 324.977684 -161.083098) (xy 325.016833 -161.206161)
			(xy 325.048332 -161.3314) (xy 325.072061 -161.458341) (xy 325.087931 -161.586501) (xy 325.095881 -161.715396)
			(xy 325.096378 -161.779966) (xy 325.095881 -161.844536) (xy 325.087931 -161.973431) (xy 325.072061 -162.101591)
			(xy 325.048332 -162.228532) (xy 325.016833 -162.353771) (xy 324.977684 -162.476834) (xy 324.931033 -162.597253)
			(xy 324.877058 -162.714572) (xy 324.815963 -162.828346) (xy 324.74798 -162.938143) (xy 324.673366 -163.043546)
			(xy 324.592405 -163.144156) (xy 324.505405 -163.239591) (xy 324.412694 -163.32949) (xy 324.314624 -163.413511)
			(xy 324.211569 -163.491335) (xy 324.103918 -163.562667) (xy 323.992079 -163.627237) (xy 323.876478 -163.684799)
			(xy 323.757553 -163.735136) (xy 323.635754 -163.778056) (xy 323.511544 -163.813397) (xy 323.385395 -163.841024)
			(xy 323.257783 -163.860833) (xy 323.129194 -163.872749) (xy 323.000116 -163.876726) (xy 322.871038 -163.872749)
			(xy 322.742449 -163.860833) (xy 322.614837 -163.841024) (xy 322.488688 -163.813397) (xy 322.364478 -163.778056)
			(xy 322.242679 -163.735136) (xy 322.123754 -163.684799) (xy 322.008153 -163.627237) (xy 321.896314 -163.562667)
			(xy 321.788663 -163.491335) (xy 321.685608 -163.413511) (xy 321.587538 -163.32949) (xy 321.494827 -163.239591)
			(xy 321.407827 -163.144156) (xy 321.326866 -163.043546) (xy 321.252252 -162.938143) (xy 321.184269 -162.828346)
			(xy 321.123174 -162.714572) (xy 321.069199 -162.597253) (xy 321.022548 -162.476834) (xy 320.983399 -162.353771)
			(xy 320.9519 -162.228532) (xy 320.928171 -162.101591) (xy 320.912301 -161.973431) (xy 320.904351 -161.844536)
			(xy 159.495755 -161.844536) (xy 159.487805 -161.973431) (xy 159.471935 -162.101591) (xy 159.448206 -162.228532)
			(xy 159.416707 -162.353771) (xy 159.377558 -162.476834) (xy 159.330907 -162.597253) (xy 159.276932 -162.714572)
			(xy 159.215837 -162.828346) (xy 159.147854 -162.938143) (xy 159.07324 -163.043546) (xy 158.992279 -163.144156)
			(xy 158.905279 -163.239591) (xy 158.812568 -163.32949) (xy 158.714498 -163.413511) (xy 158.611443 -163.491335)
			(xy 158.503792 -163.562667) (xy 158.391953 -163.627237) (xy 158.276352 -163.684799) (xy 158.157427 -163.735136)
			(xy 158.035628 -163.778056) (xy 157.911418 -163.813397) (xy 157.785269 -163.841024) (xy 157.657657 -163.860833)
			(xy 157.529068 -163.872749) (xy 157.39999 -163.876726) (xy 157.270912 -163.872749) (xy 157.142323 -163.860833)
			(xy 157.014711 -163.841024) (xy 156.888562 -163.813397) (xy 156.764352 -163.778056) (xy 156.642553 -163.735136)
			(xy 156.523628 -163.684799) (xy 156.408027 -163.627237) (xy 156.296188 -163.562667) (xy 156.188537 -163.491335)
			(xy 156.085482 -163.413511) (xy 155.987412 -163.32949) (xy 155.894701 -163.239591) (xy 155.807701 -163.144156)
			(xy 155.72674 -163.043546) (xy 155.652126 -162.938143) (xy 155.584143 -162.828346) (xy 155.523048 -162.714572)
			(xy 155.469073 -162.597253) (xy 155.422422 -162.476834) (xy 155.383273 -162.353771) (xy 155.351774 -162.228532)
			(xy 155.328045 -162.101591) (xy 155.312175 -161.973431) (xy 155.304225 -161.844536) (xy 152.908 -161.844536)
			(xy 152.908 -164.77996) (xy 152.908508 -164.835769) (xy 152.916846 -164.947074) (xy 152.933479 -165.057444)
			(xy 152.958314 -165.166264) (xy 152.991211 -165.272922) (xy 153.031987 -165.376825) (xy 153.080414 -165.477389)
			(xy 153.13622 -165.574053) (xy 153.199095 -165.666277) (xy 153.268686 -165.753543) (xy 153.344603 -165.835366)
			(xy 153.426423 -165.911286) (xy 153.513688 -165.980879) (xy 153.605909 -166.043756) (xy 153.702572 -166.099566)
			(xy 153.803135 -166.147995) (xy 153.907036 -166.188775) (xy 154.013694 -166.221675) (xy 154.122512 -166.246513)
			(xy 154.232883 -166.263149) (xy 154.344187 -166.271491) (xy 154.399996 -166.271956)
		)
		(stroke
			(width 0)
			(type solid)
		)
		(fill yes)
		(layer "In6.Cu")
		(net "GND3")
	)
	(gr_poly
		(pts
			(xy 266.666472 -146.490944) (xy 323.000116 -146.490944) (xy 323.095449 -146.490445) (xy 323.285943 -146.482352)
			(xy 323.475923 -146.466182) (xy 323.665044 -146.441963) (xy 323.852968 -146.409739) (xy 324.039354 -146.369569)
			(xy 324.223868 -146.321525) (xy 324.406177 -146.265693) (xy 324.585951 -146.202173) (xy 324.762868 -146.131082)
			(xy 324.936608 -146.052545) (xy 325.106858 -145.966706) (xy 325.273312 -145.873718) (xy 325.43567 -145.77375)
			(xy 325.593638 -145.666981) (xy 325.746932 -145.553604) (xy 325.895277 -145.433823) (xy 326.038404 -145.307853)
			(xy 326.176056 -145.175923) (xy 326.307985 -145.03827) (xy 326.433952 -144.895142) (xy 326.553732 -144.746796)
			(xy 326.667107 -144.5935) (xy 326.773875 -144.435531) (xy 326.873841 -144.273173) (xy 326.966827 -144.106718)
			(xy 327.052665 -143.936467) (xy 327.1312 -143.762726) (xy 327.20229 -143.585808) (xy 327.265807 -143.406033)
			(xy 327.321637 -143.223724) (xy 327.36968 -143.03921) (xy 327.409848 -142.852823) (xy 327.44207 -142.664899)
			(xy 327.466287 -142.475777) (xy 327.482455 -142.285798) (xy 327.490546 -142.095303) (xy 327.49109 -141.99997)
			(xy 327.49109 -4.99999) (xy 327.490584 -4.904657) (xy 327.482491 -4.714162) (xy 327.466321 -4.524182)
			(xy 327.442103 -4.335059) (xy 327.40988 -4.147135) (xy 327.36971 -3.960748) (xy 327.321666 -3.776234)
			(xy 327.265834 -3.593925) (xy 327.202315 -3.414149) (xy 327.131224 -3.237232) (xy 327.052688 -3.063491)
			(xy 326.966849 -2.89324) (xy 326.873862 -2.726785) (xy 326.773894 -2.564427) (xy 326.667125 -2.406457)
			(xy 326.553748 -2.253162) (xy 326.433968 -2.104816) (xy 326.307999 -1.961688) (xy 326.176069 -1.824035)
			(xy 326.038416 -1.692105) (xy 325.895288 -1.566136) (xy 325.746943 -1.446355) (xy 325.593648 -1.332978)
			(xy 325.435678 -1.22621) (xy 325.27332 -1.126241) (xy 325.106866 -1.033254) (xy 324.936615 -0.947415)
			(xy 324.762874 -0.868878) (xy 324.585956 -0.797787) (xy 324.406181 -0.734268) (xy 324.223872 -0.678436)
			(xy 324.039358 -0.630391) (xy 323.852971 -0.590221) (xy 323.665046 -0.557998) (xy 323.475924 -0.533779)
			(xy 323.285944 -0.517609) (xy 323.095449 -0.509516) (xy 323.000116 -0.509016) (xy 4.99999 -0.509016)
			(xy 4.904657 -0.509522) (xy 4.714162 -0.517614) (xy 4.524182 -0.533784) (xy 4.335059 -0.558002) (xy 4.147135 -0.590225)
			(xy 3.960748 -0.630394) (xy 3.776233 -0.678438) (xy 3.593924 -0.73427) (xy 3.414149 -0.797788) (xy 3.237231 -0.86888)
			(xy 3.06349 -0.947415) (xy 2.893239 -1.033254) (xy 2.726784 -1.126242) (xy 2.564426 -1.22621) (xy 2.406456 -1.332978)
			(xy 2.253161 -1.446355) (xy 2.104815 -1.566136) (xy 1.961687 -1.692104) (xy 1.824034 -1.824034) (xy 1.692104 -1.961687)
			(xy 1.566136 -2.104815) (xy 1.446355 -2.253161) (xy 1.332978 -2.406456) (xy 1.22621 -2.564426) (xy 1.126242 -2.726784)
			(xy 1.033254 -2.893239) (xy 0.947415 -3.06349) (xy 0.86888 -3.237231) (xy 0.797788 -3.414149) (xy 0.73427 -3.593924)
			(xy 0.678438 -3.776233) (xy 0.630394 -3.960748) (xy 0.590225 -4.147135) (xy 0.558002 -4.335059) (xy 0.553544 -4.36987)
			(xy 242.877075 -4.36987) (xy 242.877075 -4.24073) (xy 242.885025 -4.111835) (xy 242.900895 -3.983675)
			(xy 242.924624 -3.856734) (xy 242.956123 -3.731495) (xy 242.995272 -3.608432) (xy 243.041923 -3.488013)
			(xy 243.095898 -3.370694) (xy 243.156993 -3.25692) (xy 243.224976 -3.147123) (xy 243.29959 -3.04172)
			(xy 243.380551 -2.94111) (xy 243.467551 -2.845675) (xy 243.560262 -2.755776) (xy 243.658332 -2.671755)
			(xy 243.761387 -2.593931) (xy 243.869038 -2.522599) (xy 243.980877 -2.458029) (xy 244.096478 -2.400467)
			(xy 244.215403 -2.35013) (xy 244.337202 -2.30721) (xy 244.461412 -2.271869) (xy 244.587561 -2.244242)
			(xy 244.715173 -2.224433) (xy 244.843762 -2.212517) (xy 244.97284 -2.208541) (xy 245.101918 -2.212517)
			(xy 245.230507 -2.224433) (xy 245.358119 -2.244242) (xy 245.484268 -2.271869) (xy 245.608478 -2.30721)
			(xy 245.730277 -2.35013) (xy 245.849202 -2.400467) (xy 245.964803 -2.458029) (xy 246.076642 -2.522599)
			(xy 246.184293 -2.593931) (xy 246.287348 -2.671755) (xy 246.385418 -2.755776) (xy 246.478129 -2.845675)
			(xy 246.565129 -2.94111) (xy 246.64609 -3.04172) (xy 246.720704 -3.147123) (xy 246.788687 -3.25692)
			(xy 246.849782 -3.370694) (xy 246.903757 -3.488013) (xy 246.950408 -3.608432) (xy 246.989557 -3.731495)
			(xy 247.021056 -3.856734) (xy 247.044785 -3.983675) (xy 247.060655 -4.111835) (xy 247.068605 -4.24073)
			(xy 247.069102 -4.3053) (xy 247.068605 -4.36987) (xy 247.060655 -4.498765) (xy 247.044785 -4.626925)
			(xy 247.021056 -4.753866) (xy 246.989557 -4.879105) (xy 246.950408 -5.002168) (xy 246.903757 -5.122587)
			(xy 246.849782 -5.239906) (xy 246.788687 -5.35368) (xy 246.720704 -5.463477) (xy 246.64609 -5.56888)
			(xy 246.565129 -5.66949) (xy 246.478129 -5.764925) (xy 246.385418 -5.854824) (xy 246.287348 -5.938845)
			(xy 246.184293 -6.016669) (xy 246.076642 -6.088001) (xy 245.964803 -6.152571) (xy 245.849202 -6.210133)
			(xy 245.730277 -6.26047) (xy 245.608478 -6.30339) (xy 245.484268 -6.338731) (xy 245.358119 -6.366358)
			(xy 245.230507 -6.386167) (xy 245.101918 -6.398083) (xy 244.97284 -6.40206) (xy 244.843762 -6.398083)
			(xy 244.715173 -6.386167) (xy 244.587561 -6.366358) (xy 244.461412 -6.338731) (xy 244.337202 -6.30339)
			(xy 244.215403 -6.26047) (xy 244.096478 -6.210133) (xy 243.980877 -6.152571) (xy 243.869038 -6.088001)
			(xy 243.761387 -6.016669) (xy 243.658332 -5.938845) (xy 243.560262 -5.854824) (xy 243.467551 -5.764925)
			(xy 243.380551 -5.66949) (xy 243.29959 -5.56888) (xy 243.224976 -5.463477) (xy 243.156993 -5.35368)
			(xy 243.095898 -5.239906) (xy 243.041923 -5.122587) (xy 242.995272 -5.002168) (xy 242.956123 -4.879105)
			(xy 242.924624 -4.753866) (xy 242.900895 -4.626925) (xy 242.885025 -4.498765) (xy 242.877075 -4.36987)
			(xy 0.553544 -4.36987) (xy 0.533784 -4.524182) (xy 0.517614 -4.714162) (xy 0.509522 -4.904657) (xy 0.509016 -4.99999)
			(xy 0.509016 -11.811) (xy 161.213292 -11.811) (xy 161.21368 -11.772716) (xy 161.220219 -11.696427)
			(xy 161.2333 -11.620985) (xy 161.252827 -11.546948) (xy 161.265362 -11.510772) (xy 161.268013 -11.502335)
			(xy 161.268013 -11.484665) (xy 161.265362 -11.476228) (xy 161.252837 -11.44005) (xy 161.233329 -11.36601)
			(xy 161.220249 -11.290569) (xy 161.213694 -11.214283) (xy 161.213292 -11.176) (xy 161.213787 -11.132867)
			(xy 161.222145 -11.047006) (xy 161.238773 -10.962358) (xy 161.263515 -10.879715) (xy 161.296139 -10.799856)
			(xy 161.336337 -10.723528) (xy 161.383734 -10.651448) (xy 161.437884 -10.584294) (xy 161.498278 -10.522696)
			(xy 161.564351 -10.467231) (xy 161.63548 -10.41842) (xy 161.711 -10.376723) (xy 161.7902 -10.342529)
			(xy 161.872338 -10.316161) (xy 161.956642 -10.297865) (xy 161.999422 -10.292334) (xy 162.010643 -10.290369)
			(xy 162.029893 -10.278242) (xy 162.036506 -10.268966) (xy 162.058636 -10.234762) (xy 162.108294 -10.170172)
			(xy 162.163649 -10.110392) (xy 162.224237 -10.055923) (xy 162.289549 -10.007219) (xy 162.35904 -9.964689)
			(xy 162.432128 -9.928689) (xy 162.508201 -9.899521) (xy 162.586621 -9.877428) (xy 162.666732 -9.862596)
			(xy 162.747864 -9.855149) (xy 162.7886 -9.854692) (xy 162.829702 -9.855167) (xy 162.911557 -9.862752)
			(xy 162.992362 -9.877857) (xy 163.071429 -9.900353) (xy 163.148083 -9.930049) (xy 163.22167 -9.966691)
			(xy 163.291562 -10.009966) (xy 163.357163 -10.059506) (xy 163.417913 -10.114887) (xy 163.473294 -10.175637)
			(xy 163.522834 -10.241238) (xy 163.566109 -10.31113) (xy 163.602751 -10.384717) (xy 163.632447 -10.461371)
			(xy 163.654943 -10.540438) (xy 163.670048 -10.621243) (xy 163.677633 -10.703098) (xy 163.678108 -10.7442)
			(xy 163.677552 -10.788906) (xy 163.668575 -10.877868) (xy 163.650722 -10.96548) (xy 163.624174 -11.050861)
			(xy 163.589197 -11.133148) (xy 163.546144 -11.211513) (xy 163.495449 -11.285166) (xy 163.437624 -11.353364)
			(xy 163.40582 -11.384788) (xy 163.397946 -11.392408) (xy 163.390072 -11.41222) (xy 163.393374 -11.509502)
			(xy 163.402772 -11.528806) (xy 163.411154 -11.535918) (xy 163.44386 -11.564051) (xy 163.50427 -11.625646)
			(xy 163.558433 -11.692801) (xy 163.605841 -11.764883) (xy 163.646049 -11.841217) (xy 163.678677 -11.921084)
			(xy 163.703421 -12.003735) (xy 163.720046 -12.088393) (xy 163.728399 -12.174262) (xy 163.728908 -12.2174)
			(xy 163.728433 -12.258502) (xy 163.720848 -12.340357) (xy 163.705743 -12.421162) (xy 163.683247 -12.500229)
			(xy 163.653551 -12.576883) (xy 163.616909 -12.65047) (xy 163.573634 -12.720362) (xy 163.524094 -12.785963)
			(xy 163.468713 -12.846713) (xy 163.407963 -12.902094) (xy 163.342362 -12.951634) (xy 163.27247 -12.994909)
			(xy 163.198883 -13.031551) (xy 163.122229 -13.061247) (xy 163.043162 -13.083743) (xy 162.962357 -13.098848)
			(xy 162.880502 -13.106433) (xy 162.8394 -13.106908) (xy 162.79634 -13.10644) (xy 162.710622 -13.098119)
			(xy 162.626109 -13.081554) (xy 162.543592 -13.056902) (xy 162.463843 -13.024392) (xy 162.387608 -12.984328)
			(xy 162.315601 -12.937087) (xy 162.248496 -12.883108) (xy 162.18692 -12.822899) (xy 162.131449 -12.757022)
			(xy 162.10661 -12.721844) (xy 162.099372 -12.712425) (xy 162.078566 -12.701028) (xy 162.066732 -12.7)
			(xy 162.02424 -12.697737) (xy 161.939934 -12.686166) (xy 161.857118 -12.666598) (xy 161.776548 -12.639212)
			(xy 161.698961 -12.604258) (xy 161.625066 -12.562056) (xy 161.555538 -12.512991) (xy 161.491013 -12.457512)
			(xy 161.432079 -12.396125) (xy 161.379276 -12.329392) (xy 161.333087 -12.257922) (xy 161.293932 -12.182368)
			(xy 161.26217 -12.103421) (xy 161.23809 -12.021802) (xy 161.221914 -11.938257) (xy 161.213789 -11.853548)
			(xy 161.213292 -11.811) (xy 0.509016 -11.811) (xy 0.509016 -16.070072) (xy 0.509506 -16.139948) (xy 0.517342 -16.279481)
			(xy 0.53299 -16.418355) (xy 0.556399 -16.556133) (xy 0.587497 -16.692382) (xy 0.626186 -16.826673)
			(xy 0.672343 -16.958583) (xy 0.725824 -17.087698) (xy 0.78646 -17.21361) (xy 0.854061 -17.335925)
			(xy 0.928414 -17.454257) (xy 1.009285 -17.568234) (xy 1.09642 -17.677497) (xy 1.189543 -17.781703)
			(xy 1.288363 -17.880523) (xy 1.392569 -17.973646) (xy 1.501832 -18.060781) (xy 1.615809 -18.141652)
			(xy 1.734141 -18.216005) (xy 1.856456 -18.283606) (xy 1.982368 -18.344242) (xy 2.111483 -18.397723)
			(xy 2.243393 -18.44388) (xy 2.377684 -18.482569) (xy 2.513933 -18.513667) (xy 2.651711 -18.537076)
			(xy 2.790585 -18.552724) (xy 2.930118 -18.56056) (xy 2.999994 -18.56105) (xy 9.600184 -18.56105)
			(xy 9.644215 -18.561509) (xy 9.731942 -18.569171) (xy 9.818668 -18.584451) (xy 9.903731 -18.607233)
			(xy 9.986485 -18.637344) (xy 10.066298 -18.674554) (xy 10.142564 -18.71858) (xy 10.214702 -18.769087)
			(xy 10.282162 -18.825691) (xy 10.344431 -18.88796) (xy 10.401034 -18.95542) (xy 10.451541 -19.027557)
			(xy 10.495567 -19.103823) (xy 10.532777 -19.183637) (xy 10.562888 -19.266391) (xy 10.58567 -19.351454)
			(xy 10.60095 -19.43818) (xy 10.608611 -19.525907) (xy 10.609072 -19.569938) (xy 10.609072 -20.997361)
			(xy 276.478742 -20.997361) (xy 276.478742 -20.912639) (xy 276.486795 -20.828302) (xy 276.502829 -20.745112)
			(xy 276.526697 -20.663822) (xy 276.558185 -20.58517) (xy 276.597007 -20.509867) (xy 276.64281 -20.438595)
			(xy 276.695181 -20.371999) (xy 276.753646 -20.310684) (xy 276.817674 -20.255203) (xy 276.886686 -20.20606)
			(xy 276.960056 -20.1637) (xy 277.037121 -20.128505) (xy 277.117183 -20.100796) (xy 277.199516 -20.080822)
			(xy 277.283375 -20.068765) (xy 277.368 -20.064734) (xy 277.452625 -20.068765) (xy 277.536484 -20.080822)
			(xy 277.618817 -20.100796) (xy 277.698879 -20.128505) (xy 277.775944 -20.1637) (xy 277.849314 -20.20606)
			(xy 277.918326 -20.255203) (xy 277.982354 -20.310684) (xy 278.040819 -20.371999) (xy 278.09319 -20.438595)
			(xy 278.138993 -20.509867) (xy 278.177815 -20.58517) (xy 278.209303 -20.663822) (xy 278.233171 -20.745112)
			(xy 278.249205 -20.828302) (xy 278.257258 -20.912639) (xy 278.257762 -20.955) (xy 278.257258 -20.997361)
			(xy 278.249205 -21.081698) (xy 278.233171 -21.164888) (xy 278.209303 -21.246178) (xy 278.177815 -21.32483)
			(xy 278.138993 -21.400133) (xy 278.09319 -21.471405) (xy 278.040819 -21.538001) (xy 277.982354 -21.599316)
			(xy 277.918326 -21.654797) (xy 277.849314 -21.70394) (xy 277.775944 -21.7463) (xy 277.698879 -21.781495)
			(xy 277.618817 -21.809204) (xy 277.536484 -21.829178) (xy 277.452625 -21.841235) (xy 277.368 -21.845267)
			(xy 277.283375 -21.841235) (xy 277.199516 -21.829178) (xy 277.117183 -21.809204) (xy 277.037121 -21.781495)
			(xy 276.960056 -21.7463) (xy 276.886686 -21.70394) (xy 276.817674 -21.654797) (xy 276.753646 -21.599316)
			(xy 276.695181 -21.538001) (xy 276.64281 -21.471405) (xy 276.597007 -21.400133) (xy 276.558185 -21.32483)
			(xy 276.526697 -21.246178) (xy 276.502829 -21.164888) (xy 276.486795 -21.081698) (xy 276.478742 -20.997361)
			(xy 10.609072 -20.997361) (xy 10.609072 -25.329903) (xy 12.90965 -25.329903) (xy 12.913613 -25.189472)
			(xy 12.925487 -25.049488) (xy 12.945237 -24.910397) (xy 12.972799 -24.77264) (xy 13.008084 -24.636657)
			(xy 13.050982 -24.50288) (xy 13.101355 -24.371734) (xy 13.159043 -24.243638) (xy 13.223863 -24.118999)
			(xy 13.295608 -23.998213) (xy 13.374049 -23.881665) (xy 13.458938 -23.769726) (xy 13.550004 -23.662752)
			(xy 13.646958 -23.561083) (xy 13.74949 -23.465043) (xy 13.857275 -23.374937) (xy 13.969969 -23.291053)
			(xy 14.087214 -23.213657) (xy 14.208637 -23.142996) (xy 14.333851 -23.079294) (xy 14.462458 -23.022755)
			(xy 14.594049 -22.973557) (xy 14.728204 -22.931858) (xy 14.864498 -22.89779) (xy 15.002496 -22.871462)
			(xy 15.141758 -22.852958) (xy 15.281843 -22.842336) (xy 15.422304 -22.83963) (xy 15.562693 -22.844849)
			(xy 15.702565 -22.857976) (xy 15.841475 -22.87897) (xy 15.978979 -22.907763) (xy 16.114641 -22.944264)
			(xy 16.248029 -22.988357) (xy 16.378718 -23.039902) (xy 16.506293 -23.098734) (xy 16.630347 -23.164666)
			(xy 16.750486 -23.237489) (xy 16.866328 -23.316971) (xy 16.977503 -23.402858) (xy 17.083658 -23.494878)
			(xy 17.184455 -23.592737) (xy 17.232376 -23.644098) (xy 17.241266 -23.65375) (xy 17.264888 -23.661878)
			(xy 17.3736 -23.645368) (xy 17.393666 -23.630382) (xy 17.399 -23.618698) (xy 17.438143 -23.536826)
			(xy 17.522872 -23.376323) (xy 17.614769 -23.219815) (xy 17.713645 -23.067619) (xy 17.819299 -22.920048)
			(xy 17.931515 -22.777404) (xy 18.050063 -22.639976) (xy 18.174701 -22.508047) (xy 18.305175 -22.381886)
			(xy 18.441218 -22.261751) (xy 18.582551 -22.147887) (xy 18.728885 -22.040528) (xy 18.879923 -21.939892)
			(xy 19.035355 -21.846185) (xy 19.194863 -21.759599) (xy 19.358121 -21.68031) (xy 19.524796 -21.608481)
			(xy 19.694548 -21.544259) (xy 19.867028 -21.487775) (xy 20.041885 -21.439144) (xy 20.218761 -21.398465)
			(xy 20.397295 -21.365823) (xy 20.577122 -21.341282) (xy 20.757875 -21.324895) (xy 20.939183 -21.316693)
			(xy 21.02993 -21.316188) (xy 21.120001 -21.316693) (xy 21.299962 -21.324775) (xy 21.479379 -21.340923)
			(xy 21.657891 -21.365104) (xy 21.835139 -21.39727) (xy 22.010765 -21.437355) (xy 22.184415 -21.48528)
			(xy 22.355741 -21.540947) (xy 22.524396 -21.604244) (xy 22.690042 -21.675045) (xy 22.852345 -21.753206)
			(xy 23.010977 -21.838569) (xy 23.16562 -21.930964) (xy 23.315962 -22.030204) (xy 23.461701 -22.136089)
			(xy 23.602542 -22.248406) (xy 23.738202 -22.366929) (xy 23.868408 -22.491418) (xy 23.992897 -22.621624)
			(xy 24.11142 -22.757284) (xy 24.223737 -22.898125) (xy 24.329622 -23.043864) (xy 24.428862 -23.194206)
			(xy 24.521257 -23.348849) (xy 24.60662 -23.507481) (xy 24.684781 -23.669784) (xy 24.755582 -23.83543)
			(xy 24.818879 -24.004085) (xy 24.874546 -24.175411) (xy 24.922471 -24.349061) (xy 24.962556 -24.524687)
			(xy 24.994722 -24.701935) (xy 25.018903 -24.880447) (xy 25.035051 -25.059864) (xy 25.043133 -25.239825)
			(xy 25.043133 -25.329896) (xy 25.159471 -25.329896) (xy 25.16346 -25.188998) (xy 25.175414 -25.048551)
			(xy 25.195294 -24.909006) (xy 25.223037 -24.770809) (xy 25.258555 -24.634403) (xy 25.301732 -24.500224)
			(xy 25.352432 -24.368704) (xy 25.410492 -24.240262) (xy 25.475724 -24.115311) (xy 25.547922 -23.99425)
			(xy 25.626853 -23.877468) (xy 25.712264 -23.765339) (xy 25.803883 -23.658221) (xy 25.901415 -23.556458)
			(xy 26.004547 -23.460376) (xy 26.112951 -23.370283) (xy 26.226278 -23.286466) (xy 26.344165 -23.209196)
			(xy 26.466235 -23.138719) (xy 26.592097 -23.07526) (xy 26.721347 -23.019025) (xy 26.853572 -22.970191)
			(xy 26.988348 -22.928916) (xy 27.125243 -22.895333) (xy 27.263819 -22.869548) (xy 27.403632 -22.851644)
			(xy 27.544234 -22.841679) (xy 27.685174 -22.839684) (xy 27.826002 -22.845667) (xy 27.966265 -22.859607)
			(xy 28.105515 -22.88146) (xy 28.243306 -22.911156) (xy 28.379196 -22.9486) (xy 28.51275 -22.993672)
			(xy 28.64354 -23.046228) (xy 28.73385 -23.0886) (xy 271.702788 -23.0886) (xy 271.706818 -23.003999)
			(xy 271.718871 -22.920164) (xy 271.738839 -22.837855) (xy 271.766541 -22.757816) (xy 271.801725 -22.680773)
			(xy 271.844074 -22.607423) (xy 271.893203 -22.538431) (xy 271.948668 -22.474421) (xy 272.009966 -22.415973)
			(xy 272.076542 -22.363617) (xy 272.147794 -22.317827) (xy 272.223075 -22.279016) (xy 272.301705 -22.247537)
			(xy 272.382972 -22.223676) (xy 272.466138 -22.207647) (xy 272.550452 -22.199596) (xy 272.5928 -22.199092)
			(xy 272.635108 -22.199589) (xy 272.719344 -22.207592) (xy 272.80244 -22.223553) (xy 272.883646 -22.24733)
			(xy 272.962229 -22.278706) (xy 273.037479 -22.317399) (xy 273.073368 -22.339808) (xy 273.081757 -22.344691)
			(xy 273.1008 -22.348362) (xy 273.119843 -22.344691) (xy 273.128232 -22.339808) (xy 273.164109 -22.317376)
			(xy 273.239354 -22.278665) (xy 273.317937 -22.247279) (xy 273.399147 -22.223503) (xy 273.482249 -22.20755)
			(xy 273.56649 -22.199566) (xy 273.6088 -22.199092) (xy 273.651148 -22.199596) (xy 273.735462 -22.207647)
			(xy 273.818628 -22.223676) (xy 273.899895 -22.247537) (xy 273.978525 -22.279016) (xy 274.053806 -22.317827)
			(xy 274.125058 -22.363617) (xy 274.191634 -22.415973) (xy 274.252932 -22.474421) (xy 274.308397 -22.538431)
			(xy 274.357526 -22.607423) (xy 274.399875 -22.680773) (xy 274.435059 -22.757816) (xy 274.462761 -22.837855)
			(xy 274.482729 -22.920164) (xy 274.494782 -23.003999) (xy 274.498813 -23.0886) (xy 274.494782 -23.173201)
			(xy 274.482729 -23.257036) (xy 274.462761 -23.339345) (xy 274.435059 -23.419384) (xy 274.399875 -23.496427)
			(xy 274.357526 -23.569777) (xy 274.308397 -23.638769) (xy 274.252932 -23.702779) (xy 274.191634 -23.761227)
			(xy 274.125058 -23.813583) (xy 274.053806 -23.859373) (xy 273.978525 -23.898184) (xy 273.899895 -23.929663)
			(xy 273.818628 -23.953524) (xy 273.735462 -23.969553) (xy 273.651148 -23.977604) (xy 273.6088 -23.978108)
			(xy 273.566492 -23.977611) (xy 273.482256 -23.969608) (xy 273.39916 -23.953647) (xy 273.317954 -23.92987)
			(xy 273.239371 -23.898494) (xy 273.164121 -23.859801) (xy 273.128232 -23.837392) (xy 273.119843 -23.832509)
			(xy 273.1008 -23.828838) (xy 273.081757 -23.832509) (xy 273.073368 -23.837392) (xy 273.037491 -23.859824)
			(xy 272.962246 -23.898535) (xy 272.883663 -23.929921) (xy 272.802453 -23.953697) (xy 272.719351 -23.96965)
			(xy 272.63511 -23.977634) (xy 272.5928 -23.978108) (xy 272.550452 -23.977604) (xy 272.466138 -23.969553)
			(xy 272.382972 -23.953524) (xy 272.301705 -23.929663) (xy 272.223075 -23.898184) (xy 272.147794 -23.859373)
			(xy 272.076542 -23.813583) (xy 272.009966 -23.761227) (xy 271.948668 -23.702779) (xy 271.893203 -23.638769)
			(xy 271.844074 -23.569777) (xy 271.801725 -23.496427) (xy 271.766541 -23.419384) (xy 271.738839 -23.339345)
			(xy 271.718871 -23.257036) (xy 271.706818 -23.173201) (xy 271.702788 -23.0886) (xy 28.73385 -23.0886)
			(xy 28.771147 -23.106099) (xy 28.895163 -23.173094) (xy 29.015189 -23.246997) (xy 29.130843 -23.327573)
			(xy 29.241752 -23.414562) (xy 29.347563 -23.507687) (xy 29.447935 -23.606649) (xy 29.542548 -23.711131)
			(xy 29.631099 -23.820799) (xy 29.713303 -23.935301) (xy 29.788897 -24.05427) (xy 29.85764 -24.177325)
			(xy 29.919311 -24.304072) (xy 29.973712 -24.434105) (xy 30.02067 -24.567008) (xy 30.060033 -24.702354)
			(xy 30.091676 -24.839711) (xy 30.115498 -24.978638) (xy 30.131421 -25.11869) (xy 30.139396 -25.259419)
			(xy 30.139894 -25.329896) (xy 30.139396 -25.400373) (xy 30.131421 -25.541102) (xy 30.125683 -25.59157)
			(xy 42.354235 -25.59157) (xy 42.354235 -25.46243) (xy 42.362185 -25.333535) (xy 42.378055 -25.205375)
			(xy 42.401784 -25.078434) (xy 42.433283 -24.953195) (xy 42.472432 -24.830132) (xy 42.519083 -24.709713)
			(xy 42.573058 -24.592394) (xy 42.634153 -24.47862) (xy 42.702136 -24.368823) (xy 42.77675 -24.26342)
			(xy 42.857711 -24.16281) (xy 42.944711 -24.067375) (xy 43.037422 -23.977476) (xy 43.135492 -23.893455)
			(xy 43.238547 -23.815631) (xy 43.346198 -23.744299) (xy 43.458037 -23.679729) (xy 43.573638 -23.622167)
			(xy 43.692563 -23.57183) (xy 43.814362 -23.52891) (xy 43.938572 -23.493569) (xy 44.064721 -23.465942)
			(xy 44.192333 -23.446133) (xy 44.320922 -23.434217) (xy 44.45 -23.430241) (xy 44.579078 -23.434217)
			(xy 44.707667 -23.446133) (xy 44.835279 -23.465942) (xy 44.961428 -23.493569) (xy 45.085638 -23.52891)
			(xy 45.207437 -23.57183) (xy 45.326362 -23.622167) (xy 45.441963 -23.679729) (xy 45.553802 -23.744299)
			(xy 45.661453 -23.815631) (xy 45.764508 -23.893455) (xy 45.862578 -23.977476) (xy 45.955289 -24.067375)
			(xy 46.042289 -24.16281) (xy 46.12325 -24.26342) (xy 46.197864 -24.368823) (xy 46.265847 -24.47862)
			(xy 46.326942 -24.592394) (xy 46.380917 -24.709713) (xy 46.427568 -24.830132) (xy 46.466717 -24.953195)
			(xy 46.498216 -25.078434) (xy 46.521945 -25.205375) (xy 46.537815 -25.333535) (xy 46.545765 -25.46243)
			(xy 46.546262 -25.527) (xy 46.545765 -25.59157) (xy 46.537815 -25.720465) (xy 46.521945 -25.848625)
			(xy 46.498216 -25.975566) (xy 46.466717 -26.100805) (xy 46.427568 -26.223868) (xy 46.380917 -26.344287)
			(xy 46.326942 -26.461606) (xy 46.265847 -26.57538) (xy 46.197864 -26.685177) (xy 46.12325 -26.79058)
			(xy 46.042289 -26.89119) (xy 45.955289 -26.986625) (xy 45.862578 -27.076524) (xy 45.764508 -27.160545)
			(xy 45.661453 -27.238369) (xy 45.553802 -27.309701) (xy 45.441963 -27.374271) (xy 45.326362 -27.431833)
			(xy 45.207437 -27.48217) (xy 45.085638 -27.52509) (xy 44.961428 -27.560431) (xy 44.835279 -27.588058)
			(xy 44.707667 -27.607867) (xy 44.579078 -27.619783) (xy 44.45 -27.62376) (xy 44.320922 -27.619783)
			(xy 44.192333 -27.607867) (xy 44.064721 -27.588058) (xy 43.938572 -27.560431) (xy 43.814362 -27.52509)
			(xy 43.692563 -27.48217) (xy 43.573638 -27.431833) (xy 43.458037 -27.374271) (xy 43.346198 -27.309701)
			(xy 43.238547 -27.238369) (xy 43.135492 -27.160545) (xy 43.037422 -27.076524) (xy 42.944711 -26.986625)
			(xy 42.857711 -26.89119) (xy 42.77675 -26.79058) (xy 42.702136 -26.685177) (xy 42.634153 -26.57538)
			(xy 42.573058 -26.461606) (xy 42.519083 -26.344287) (xy 42.472432 -26.223868) (xy 42.433283 -26.100805)
			(xy 42.401784 -25.975566) (xy 42.378055 -25.848625) (xy 42.362185 -25.720465) (xy 42.354235 -25.59157)
			(xy 30.125683 -25.59157) (xy 30.115498 -25.681154) (xy 30.091676 -25.820081) (xy 30.060033 -25.957438)
			(xy 30.02067 -26.092784) (xy 29.973712 -26.225687) (xy 29.919311 -26.35572) (xy 29.85764 -26.482467)
			(xy 29.788897 -26.605522) (xy 29.713303 -26.724491) (xy 29.631099 -26.838993) (xy 29.542548 -26.948661)
			(xy 29.447935 -27.053143) (xy 29.347563 -27.152105) (xy 29.241752 -27.24523) (xy 29.130843 -27.332219)
			(xy 29.015189 -27.412795) (xy 28.895163 -27.486698) (xy 28.771147 -27.553693) (xy 28.64354 -27.613564)
			(xy 28.51275 -27.66612) (xy 28.379196 -27.711192) (xy 28.243306 -27.748636) (xy 28.105515 -27.778332)
			(xy 27.966265 -27.800185) (xy 27.826002 -27.814125) (xy 27.685174 -27.820108) (xy 27.544234 -27.818113)
			(xy 27.403632 -27.808148) (xy 27.263819 -27.790244) (xy 27.125243 -27.764459) (xy 26.988348 -27.730876)
			(xy 26.853572 -27.689601) (xy 26.721347 -27.640767) (xy 26.592097 -27.584532) (xy 26.466235 -27.521073)
			(xy 26.344165 -27.450596) (xy 26.226278 -27.373326) (xy 26.112951 -27.289509) (xy 26.004547 -27.199416)
			(xy 25.901415 -27.103334) (xy 25.803883 -27.001571) (xy 25.712264 -26.894453) (xy 25.626853 -26.782324)
			(xy 25.547922 -26.665542) (xy 25.475724 -26.544481) (xy 25.410492 -26.41953) (xy 25.352432 -26.291088)
			(xy 25.301732 -26.159568) (xy 25.258555 -26.025389) (xy 25.223037 -25.888983) (xy 25.195294 -25.750786)
			(xy 25.175414 -25.611241) (xy 25.16346 -25.470794) (xy 25.159471 -25.329896) (xy 25.043133 -25.329896)
			(xy 25.043133 -25.419967) (xy 25.035051 -25.599928) (xy 25.018903 -25.779345) (xy 24.994722 -25.957857)
			(xy 24.962556 -26.135105) (xy 24.922471 -26.310731) (xy 24.874546 -26.484381) (xy 24.818879 -26.655707)
			(xy 24.755582 -26.824362) (xy 24.684781 -26.990008) (xy 24.60662 -27.152311) (xy 24.521257 -27.310943)
			(xy 24.428862 -27.465586) (xy 24.329622 -27.615928) (xy 24.223737 -27.761667) (xy 24.11142 -27.902508)
			(xy 23.992897 -28.038168) (xy 23.868408 -28.168374) (xy 23.738202 -28.292863) (xy 23.602542 -28.411386)
			(xy 23.461701 -28.523703) (xy 23.315962 -28.629588) (xy 23.16562 -28.728828) (xy 23.010977 -28.821223)
			(xy 22.852345 -28.906586) (xy 22.690042 -28.984747) (xy 22.524396 -29.055548) (xy 22.355741 -29.118845)
			(xy 22.184415 -29.174512) (xy 22.010765 -29.222437) (xy 21.835139 -29.262522) (xy 21.657891 -29.294688)
			(xy 21.479379 -29.318869) (xy 21.299962 -29.335017) (xy 21.120001 -29.343099) (xy 21.02993 -29.343604)
			(xy 20.939184 -29.343097) (xy 20.757877 -29.334889) (xy 20.577127 -29.318497) (xy 20.397302 -29.293952)
			(xy 20.21877 -29.261305) (xy 20.041895 -29.220623) (xy 19.867041 -29.171989) (xy 19.694562 -29.115502)
			(xy 19.524813 -29.051278) (xy 19.35814 -28.979448) (xy 19.194884 -28.900158) (xy 19.035377 -28.813572)
			(xy 18.879947 -28.719865) (xy 18.728911 -28.61923) (xy 18.582577 -28.511871) (xy 18.441244 -28.398009)
			(xy 18.305202 -28.277876) (xy 18.174728 -28.151717) (xy 18.050089 -28.01979) (xy 17.93154 -27.882366)
			(xy 17.819322 -27.739724) (xy 17.713666 -27.592156) (xy 17.614787 -27.439964) (xy 17.522887 -27.283459)
			(xy 17.438154 -27.12296) (xy 17.399 -27.041094) (xy 17.393666 -27.02941) (xy 17.3736 -27.014424)
			(xy 17.264888 -26.997914) (xy 17.241266 -27.006042) (xy 17.232376 -27.015694) (xy 17.184459 -27.067059)
			(xy 17.083662 -27.164918) (xy 16.977507 -27.256938) (xy 16.866332 -27.342826) (xy 16.750491 -27.422308)
			(xy 16.630352 -27.495131) (xy 16.506298 -27.561063) (xy 16.378724 -27.619896) (xy 16.248035 -27.671441)
			(xy 16.114647 -27.715534) (xy 15.978985 -27.752036) (xy 15.841481 -27.780829) (xy 15.702571 -27.801823)
			(xy 15.562699 -27.814951) (xy 15.42231 -27.82017) (xy 15.281849 -27.817465) (xy 15.141764 -27.806843)
			(xy 15.002501 -27.788339) (xy 14.864504 -27.762011) (xy 14.72821 -27.727944) (xy 14.594054 -27.686245)
			(xy 14.462464 -27.637048) (xy 14.333856 -27.580508) (xy 14.208642 -27.516807) (xy 14.087219 -27.446146)
			(xy 13.969974 -27.36875) (xy 13.857279 -27.284866) (xy 13.749494 -27.194761) (xy 13.646962 -27.098721)
			(xy 13.550008 -26.997053) (xy 13.458942 -26.890079) (xy 13.374053 -26.77814) (xy 13.295611 -26.661592)
			(xy 13.223866 -26.540806) (xy 13.159046 -26.416167) (xy 13.101357 -26.288071) (xy 13.050984 -26.156926)
			(xy 13.008086 -26.023149) (xy 12.9728 -25.887166) (xy 12.945238 -25.749409) (xy 12.925488 -25.610318)
			(xy 12.913613 -25.470334) (xy 12.90965 -25.329903) (xy 10.609072 -25.329903) (xy 10.609072 -31.070042)
			(xy 10.608582 -31.114068) (xy 10.600889 -31.201783) (xy 10.585583 -31.288494) (xy 10.562781 -31.373542)
			(xy 10.532655 -31.456279) (xy 10.495435 -31.536078) (xy 10.451404 -31.61233) (xy 10.400897 -31.684456)
			(xy 10.344298 -31.751907) (xy 10.282038 -31.81417) (xy 10.214589 -31.870772) (xy 10.142465 -31.921282)
			(xy 10.066215 -31.965316) (xy 9.986418 -32.002539) (xy 9.903682 -32.032668) (xy 9.818635 -32.055474)
			(xy 9.731924 -32.070783) (xy 9.64421 -32.07848) (xy 9.600184 -32.07893) (xy 2.999994 -32.07893) (xy 2.930118 -32.07942)
			(xy 2.790585 -32.087256) (xy 2.651711 -32.102904) (xy 2.513933 -32.126313) (xy 2.377684 -32.157411)
			(xy 2.243393 -32.1961) (xy 2.111483 -32.242257) (xy 1.982368 -32.295738) (xy 1.856456 -32.356374)
			(xy 1.734141 -32.423975) (xy 1.615809 -32.498328) (xy 1.501832 -32.579199) (xy 1.392569 -32.666334)
			(xy 1.288363 -32.759457) (xy 1.189543 -32.858277) (xy 1.09642 -32.962483) (xy 1.04643 -33.025168)
			(xy 59.677545 -33.025168) (xy 59.677545 -32.854812) (xy 59.68553 -32.684644) (xy 59.701482 -32.515037)
			(xy 59.725367 -32.346365) (xy 59.757131 -32.178997) (xy 59.796706 -32.013302) (xy 59.844003 -31.849644)
			(xy 59.89892 -31.688383) (xy 59.961335 -31.529873) (xy 60.031111 -31.374463) (xy 60.108094 -31.222495)
			(xy 60.192116 -31.074301) (xy 60.282992 -30.930209) (xy 60.380522 -30.790535) (xy 60.484492 -30.655586)
			(xy 60.594673 -30.525658) (xy 60.710822 -30.401038) (xy 60.832686 -30.281999) (xy 60.959994 -30.168803)
			(xy 61.092469 -30.061698) (xy 61.229819 -29.960921) (xy 61.371741 -29.866692) (xy 61.517923 -29.779219)
			(xy 61.668046 -29.698694) (xy 61.821777 -29.625294) (xy 61.97878 -29.55918) (xy 62.13871 -29.500498)
			(xy 62.301214 -29.449377) (xy 62.465935 -29.405929) (xy 62.632513 -29.37025) (xy 62.800579 -29.342418)
			(xy 62.969765 -29.322494) (xy 63.139699 -29.310522) (xy 63.310008 -29.306529) (xy 63.480317 -29.310522)
			(xy 63.650251 -29.322494) (xy 63.819437 -29.342418) (xy 63.987503 -29.37025) (xy 64.154081 -29.405929)
			(xy 64.318802 -29.449377) (xy 64.481306 -29.500498) (xy 64.641236 -29.55918) (xy 64.798239 -29.625294)
			(xy 64.95197 -29.698694) (xy 65.102093 -29.779219) (xy 65.248275 -29.866692) (xy 65.390197 -29.960921)
			(xy 65.527547 -30.061698) (xy 65.660022 -30.168803) (xy 65.78733 -30.281999) (xy 65.909194 -30.401038)
			(xy 66.025343 -30.525658) (xy 66.135524 -30.655586) (xy 66.239494 -30.790535) (xy 66.337024 -30.930209)
			(xy 66.4279 -31.074301) (xy 66.511922 -31.222495) (xy 66.588905 -31.374463) (xy 66.658681 -31.529873)
			(xy 66.721096 -31.688383) (xy 66.776013 -31.849644) (xy 66.82331 -32.013302) (xy 66.862885 -32.178997)
			(xy 66.894649 -32.346365) (xy 66.918534 -32.515037) (xy 66.934486 -32.684644) (xy 66.942471 -32.854812)
			(xy 66.94297 -32.93999) (xy 66.942471 -33.025168) (xy 66.934486 -33.195336) (xy 66.918534 -33.364943)
			(xy 66.894649 -33.533615) (xy 66.862885 -33.700983) (xy 66.82331 -33.866678) (xy 66.776013 -34.030336)
			(xy 66.721096 -34.191597) (xy 66.658681 -34.350107) (xy 66.588905 -34.505517) (xy 66.511922 -34.657485)
			(xy 66.4279 -34.805679) (xy 66.337024 -34.949771) (xy 66.239494 -35.089445) (xy 66.135524 -35.224394)
			(xy 66.025343 -35.354322) (xy 65.909194 -35.478942) (xy 65.78733 -35.597981) (xy 65.660022 -35.711177)
			(xy 65.527547 -35.818282) (xy 65.390197 -35.919059) (xy 65.248275 -36.013288) (xy 65.102093 -36.100761)
			(xy 64.95197 -36.181286) (xy 64.798239 -36.254686) (xy 64.641236 -36.3208) (xy 64.481306 -36.379482)
			(xy 64.318802 -36.430603) (xy 64.154081 -36.474051) (xy 63.987503 -36.50973) (xy 63.819437 -36.537562)
			(xy 63.650251 -36.557486) (xy 63.480317 -36.569458) (xy 63.310008 -36.573452) (xy 63.139699 -36.569458)
			(xy 62.969765 -36.557486) (xy 62.800579 -36.537562) (xy 62.632513 -36.50973) (xy 62.465935 -36.474051)
			(xy 62.301214 -36.430603) (xy 62.13871 -36.379482) (xy 61.97878 -36.3208) (xy 61.821777 -36.254686)
			(xy 61.668046 -36.181286) (xy 61.517923 -36.100761) (xy 61.371741 -36.013288) (xy 61.229819 -35.919059)
			(xy 61.092469 -35.818282) (xy 60.959994 -35.711177) (xy 60.832686 -35.597981) (xy 60.710822 -35.478942)
			(xy 60.594673 -35.354322) (xy 60.484492 -35.224394) (xy 60.380522 -35.089445) (xy 60.282992 -34.949771)
			(xy 60.192116 -34.805679) (xy 60.108094 -34.657485) (xy 60.031111 -34.505517) (xy 59.961335 -34.350107)
			(xy 59.89892 -34.191597) (xy 59.844003 -34.030336) (xy 59.796706 -33.866678) (xy 59.757131 -33.700983)
			(xy 59.725367 -33.533615) (xy 59.701482 -33.364943) (xy 59.68553 -33.195336) (xy 59.677545 -33.025168)
			(xy 1.04643 -33.025168) (xy 1.009285 -33.071746) (xy 0.928414 -33.185723) (xy 0.854061 -33.304055)
			(xy 0.78646 -33.42637) (xy 0.725824 -33.552282) (xy 0.672343 -33.681397) (xy 0.626186 -33.813307)
			(xy 0.587497 -33.947598) (xy 0.556399 -34.083847) (xy 0.53299 -34.221625) (xy 0.517342 -34.360499)
			(xy 0.509506 -34.500032) (xy 0.509016 -34.569908) (xy 0.509016 -38.019995) (xy 100.644968 -38.019995)
			(xy 100.648872 -37.915504) (xy 100.660563 -37.811596) (xy 100.679974 -37.708849) (xy 100.706998 -37.607838)
			(xy 100.741484 -37.509125) (xy 100.783239 -37.41326) (xy 100.832032 -37.320778) (xy 100.887589 -37.232195)
			(xy 100.949602 -37.148005) (xy 101.017724 -37.068676) (xy 101.091575 -36.994652) (xy 101.170744 -36.926345)
			(xy 101.254789 -36.864136) (xy 101.298756 -36.835842) (xy 101.309932 -36.82873) (xy 101.322378 -36.806378)
			(xy 101.322378 -36.693602) (xy 101.309932 -36.67125) (xy 101.298756 -36.664138) (xy 101.25478 -36.635858)
			(xy 101.170735 -36.573648) (xy 101.091567 -36.505341) (xy 101.017716 -36.431316) (xy 100.949595 -36.351987)
			(xy 100.887583 -36.267796) (xy 100.832027 -36.179212) (xy 100.783235 -36.08673) (xy 100.74148 -35.990865)
			(xy 100.706995 -35.892152) (xy 100.679971 -35.79114) (xy 100.660561 -35.688394) (xy 100.648871 -35.584486)
			(xy 100.644968 -35.479995) (xy 100.648872 -35.375504) (xy 100.660563 -35.271596) (xy 100.679974 -35.168849)
			(xy 100.706998 -35.067838) (xy 100.741484 -34.969125) (xy 100.783239 -34.87326) (xy 100.832032 -34.780778)
			(xy 100.887589 -34.692195) (xy 100.949602 -34.608005) (xy 101.017724 -34.528676) (xy 101.091575 -34.454652)
			(xy 101.170744 -34.386345) (xy 101.254789 -34.324136) (xy 101.298756 -34.295842) (xy 101.309932 -34.28873)
			(xy 101.322378 -34.266378) (xy 101.322378 -34.153602) (xy 101.309932 -34.13125) (xy 101.298756 -34.124138)
			(xy 101.253105 -34.094744) (xy 101.166014 -34.02989) (xy 101.084209 -33.958484) (xy 101.008183 -33.880954)
			(xy 100.938393 -33.797766) (xy 100.875258 -33.70942) (xy 100.819159 -33.616449) (xy 100.770431 -33.51941)
			(xy 100.72937 -33.418887) (xy 100.69622 -33.315485) (xy 100.671182 -33.209825) (xy 100.654406 -33.102543)
			(xy 100.645993 -32.994283) (xy 100.645468 -32.93999) (xy 100.645985 -32.887639) (xy 100.653809 -32.783228)
			(xy 100.669413 -32.679695) (xy 100.692709 -32.577616) (xy 100.723568 -32.477564) (xy 100.761816 -32.380097)
			(xy 100.807239 -32.28576) (xy 100.859585 -32.195082) (xy 100.91856 -32.108567) (xy 100.983834 -32.026702)
			(xy 101.055043 -31.949942) (xy 101.131788 -31.878718) (xy 101.213641 -31.813427) (xy 101.300143 -31.754435)
			(xy 101.390811 -31.702071) (xy 101.485138 -31.656629) (xy 101.582598 -31.618361) (xy 101.682644 -31.587482)
			(xy 101.784717 -31.564166) (xy 101.888248 -31.548541) (xy 101.992657 -31.540696) (xy 102.045008 -31.540196)
			(xy 102.099308 -31.540684) (xy 102.207582 -31.549102) (xy 102.314878 -31.565887) (xy 102.42055 -31.590938)
			(xy 102.523962 -31.624104) (xy 102.624493 -31.665187) (xy 102.721537 -31.713937) (xy 102.81451 -31.770063)
			(xy 102.902853 -31.833226) (xy 102.986035 -31.903047) (xy 103.063555 -31.979105) (xy 103.134946 -32.060943)
			(xy 103.199779 -32.148068) (xy 103.229156 -32.193738) (xy 103.236268 -32.204914) (xy 103.25862 -32.21736)
			(xy 103.371396 -32.21736) (xy 103.393748 -32.204914) (xy 103.40086 -32.193738) (xy 103.430248 -32.148075)
			(xy 103.49508 -32.060952) (xy 103.566471 -31.979116) (xy 103.643991 -31.903059) (xy 103.727172 -31.83324)
			(xy 103.815514 -31.770078) (xy 103.908487 -31.713954) (xy 104.00553 -31.665205) (xy 104.106059 -31.624125)
			(xy 104.20947 -31.59096) (xy 104.315141 -31.56591) (xy 104.422436 -31.549126) (xy 104.530708 -31.540709)
			(xy 104.585008 -31.540196) (xy 104.637364 -31.54063) (xy 104.741784 -31.548457) (xy 104.845326 -31.564066)
			(xy 104.947413 -31.58737) (xy 105.047472 -31.618239) (xy 105.144944 -31.6565) (xy 105.239283 -31.701939)
			(xy 105.329963 -31.754302) (xy 105.416476 -31.813296) (xy 105.498337 -31.878591) (xy 105.57509 -31.949821)
			(xy 105.646304 -32.026588) (xy 105.711581 -32.108464) (xy 105.770557 -32.194989) (xy 105.8229 -32.28568)
			(xy 105.868319 -32.38003) (xy 105.906559 -32.47751) (xy 105.937407 -32.577575) (xy 105.960689 -32.679667)
			(xy 105.976277 -32.783212) (xy 105.984081 -32.887634) (xy 105.984548 -32.93999) (xy 105.984054 -32.994284)
			(xy 105.975641 -33.102545) (xy 105.958864 -33.209828) (xy 105.933825 -33.315489) (xy 105.900673 -33.418892)
			(xy 105.859609 -33.519415) (xy 105.810879 -33.616455) (xy 105.754776 -33.709426) (xy 105.691638 -33.797771)
			(xy 105.621844 -33.880957) (xy 105.545813 -33.958486) (xy 105.464005 -34.029889) (xy 105.376909 -34.094739)
			(xy 105.33126 -34.124138) (xy 105.320084 -34.13125) (xy 105.307638 -34.153602) (xy 105.307638 -34.266378)
			(xy 105.320084 -34.28873) (xy 105.33126 -34.295842) (xy 105.37522 -34.324148) (xy 105.459268 -34.386354)
			(xy 105.538441 -34.454658) (xy 105.612295 -34.52868) (xy 105.68042 -34.608006) (xy 105.742436 -34.692195)
			(xy 105.797996 -34.780777) (xy 105.846791 -34.873258) (xy 105.888549 -34.969123) (xy 105.923037 -35.067836)
			(xy 105.950062 -35.168848) (xy 105.969475 -35.271594) (xy 105.981166 -35.375503) (xy 105.98507 -35.479995)
			(xy 105.981167 -35.584486) (xy 105.969476 -35.688395) (xy 105.950065 -35.791142) (xy 105.92304 -35.892154)
			(xy 105.888553 -35.990867) (xy 105.846796 -36.086732) (xy 105.798001 -36.179214) (xy 105.742442 -36.267796)
			(xy 105.680427 -36.351986) (xy 105.612303 -36.431313) (xy 105.538449 -36.505335) (xy 105.459277 -36.57364)
			(xy 105.375229 -36.635846) (xy 105.33126 -36.664138) (xy 105.320084 -36.67125) (xy 105.307638 -36.693602)
			(xy 105.307638 -36.806378) (xy 105.320084 -36.82873) (xy 105.33126 -36.835842) (xy 105.37522 -36.864148)
			(xy 105.459268 -36.926354) (xy 105.538441 -36.994658) (xy 105.612295 -37.06868) (xy 105.68042 -37.148006)
			(xy 105.742436 -37.232195) (xy 105.797996 -37.320777) (xy 105.846791 -37.413258) (xy 105.888549 -37.509123)
			(xy 105.923037 -37.607836) (xy 105.950062 -37.708848) (xy 105.969475 -37.811594) (xy 105.981166 -37.915503)
			(xy 105.98507 -38.019995) (xy 109.534968 -38.019995) (xy 109.538872 -37.915504) (xy 109.550563 -37.811596)
			(xy 109.569974 -37.708849) (xy 109.596998 -37.607838) (xy 109.631484 -37.509125) (xy 109.673239 -37.41326)
			(xy 109.722032 -37.320778) (xy 109.777589 -37.232195) (xy 109.839602 -37.148005) (xy 109.907724 -37.068676)
			(xy 109.981575 -36.994652) (xy 110.060744 -36.926345) (xy 110.144789 -36.864136) (xy 110.188756 -36.835842)
			(xy 110.199932 -36.82873) (xy 110.212378 -36.806378) (xy 110.212378 -36.693602) (xy 110.199932 -36.67125)
			(xy 110.188756 -36.664138) (xy 110.14478 -36.635858) (xy 110.060735 -36.573648) (xy 109.981567 -36.505341)
			(xy 109.907716 -36.431316) (xy 109.839595 -36.351987) (xy 109.777583 -36.267796) (xy 109.722027 -36.179212)
			(xy 109.673235 -36.08673) (xy 109.63148 -35.990865) (xy 109.596995 -35.892152) (xy 109.569971 -35.79114)
			(xy 109.550561 -35.688394) (xy 109.538871 -35.584486) (xy 109.534968 -35.479995) (xy 109.538872 -35.375504)
			(xy 109.550563 -35.271596) (xy 109.569974 -35.168849) (xy 109.596998 -35.067838) (xy 109.631484 -34.969125)
			(xy 109.673239 -34.87326) (xy 109.722032 -34.780778) (xy 109.777589 -34.692195) (xy 109.839602 -34.608005)
			(xy 109.907724 -34.528676) (xy 109.981575 -34.454652) (xy 110.060744 -34.386345) (xy 110.144789 -34.324136)
			(xy 110.188756 -34.295842) (xy 110.199932 -34.28873) (xy 110.212378 -34.266378) (xy 110.212378 -34.153602)
			(xy 110.199932 -34.13125) (xy 110.188756 -34.124138) (xy 110.143105 -34.094744) (xy 110.056014 -34.02989)
			(xy 109.974209 -33.958484) (xy 109.898183 -33.880954) (xy 109.828393 -33.797766) (xy 109.765258 -33.70942)
			(xy 109.709159 -33.616449) (xy 109.660431 -33.51941) (xy 109.61937 -33.418887) (xy 109.58622 -33.315485)
			(xy 109.561182 -33.209825) (xy 109.544406 -33.102543) (xy 109.535993 -32.994283) (xy 109.535468 -32.93999)
			(xy 109.535985 -32.887639) (xy 109.543809 -32.783228) (xy 109.559413 -32.679695) (xy 109.582709 -32.577616)
			(xy 109.613568 -32.477564) (xy 109.651816 -32.380097) (xy 109.697239 -32.28576) (xy 109.749585 -32.195082)
			(xy 109.80856 -32.108567) (xy 109.873834 -32.026702) (xy 109.945043 -31.949942) (xy 110.021788 -31.878718)
			(xy 110.103641 -31.813427) (xy 110.190143 -31.754435) (xy 110.280811 -31.702071) (xy 110.375138 -31.656629)
			(xy 110.472598 -31.618361) (xy 110.572644 -31.587482) (xy 110.674717 -31.564166) (xy 110.778248 -31.548541)
			(xy 110.882657 -31.540696) (xy 110.935008 -31.540196) (xy 110.989308 -31.540684) (xy 111.097582 -31.549102)
			(xy 111.204878 -31.565887) (xy 111.31055 -31.590938) (xy 111.413962 -31.624104) (xy 111.514493 -31.665187)
			(xy 111.611537 -31.713937) (xy 111.70451 -31.770063) (xy 111.792853 -31.833226) (xy 111.876035 -31.903047)
			(xy 111.953555 -31.979105) (xy 112.024946 -32.060943) (xy 112.089779 -32.148068) (xy 112.119156 -32.193738)
			(xy 112.126268 -32.204914) (xy 112.14862 -32.21736) (xy 112.261396 -32.21736) (xy 112.283748 -32.204914)
			(xy 112.29086 -32.193738) (xy 112.320248 -32.148075) (xy 112.38508 -32.060952) (xy 112.456471 -31.979116)
			(xy 112.533991 -31.903059) (xy 112.617172 -31.83324) (xy 112.705514 -31.770078) (xy 112.798487 -31.713954)
			(xy 112.89553 -31.665205) (xy 112.996059 -31.624125) (xy 113.09947 -31.59096) (xy 113.205141 -31.56591)
			(xy 113.312436 -31.549126) (xy 113.420708 -31.540709) (xy 113.475008 -31.540196) (xy 113.527364 -31.54063)
			(xy 113.631784 -31.548457) (xy 113.735326 -31.564066) (xy 113.837413 -31.58737) (xy 113.937472 -31.618239)
			(xy 114.034944 -31.6565) (xy 114.129283 -31.701939) (xy 114.219963 -31.754302) (xy 114.306476 -31.813296)
			(xy 114.388337 -31.878591) (xy 114.46509 -31.949821) (xy 114.536304 -32.026588) (xy 114.601581 -32.108464)
			(xy 114.660557 -32.194989) (xy 114.7129 -32.28568) (xy 114.758319 -32.38003) (xy 114.796559 -32.47751)
			(xy 114.827407 -32.577575) (xy 114.850689 -32.679667) (xy 114.866277 -32.783212) (xy 114.874081 -32.887634)
			(xy 114.874548 -32.93999) (xy 114.874054 -32.994284) (xy 114.865641 -33.102545) (xy 114.848864 -33.209828)
			(xy 114.823825 -33.315489) (xy 114.790673 -33.418892) (xy 114.749609 -33.519415) (xy 114.700879 -33.616455)
			(xy 114.644776 -33.709426) (xy 114.581638 -33.797771) (xy 114.511844 -33.880957) (xy 114.435813 -33.958486)
			(xy 114.354005 -34.029889) (xy 114.266909 -34.094739) (xy 114.22126 -34.124138) (xy 114.210084 -34.13125)
			(xy 114.197638 -34.153602) (xy 114.197638 -34.266378) (xy 114.210084 -34.28873) (xy 114.22126 -34.295842)
			(xy 114.26522 -34.324148) (xy 114.349268 -34.386354) (xy 114.428441 -34.454658) (xy 114.502295 -34.52868)
			(xy 114.57042 -34.608006) (xy 114.632436 -34.692195) (xy 114.687996 -34.780777) (xy 114.736791 -34.873258)
			(xy 114.778549 -34.969123) (xy 114.813037 -35.067836) (xy 114.840062 -35.168848) (xy 114.859475 -35.271594)
			(xy 114.871166 -35.375503) (xy 114.87507 -35.479995) (xy 114.871167 -35.584486) (xy 114.859476 -35.688395)
			(xy 114.840065 -35.791142) (xy 114.81304 -35.892154) (xy 114.778553 -35.990867) (xy 114.736796 -36.086732)
			(xy 114.688001 -36.179214) (xy 114.632442 -36.267796) (xy 114.570427 -36.351986) (xy 114.502303 -36.431313)
			(xy 114.428449 -36.505335) (xy 114.349277 -36.57364) (xy 114.265229 -36.635846) (xy 114.22126 -36.664138)
			(xy 114.210084 -36.67125) (xy 114.197638 -36.693602) (xy 114.197638 -36.806378) (xy 114.210084 -36.82873)
			(xy 114.22126 -36.835842) (xy 114.26522 -36.864148) (xy 114.349268 -36.926354) (xy 114.428441 -36.994658)
			(xy 114.502295 -37.06868) (xy 114.57042 -37.148006) (xy 114.632436 -37.232195) (xy 114.687996 -37.320777)
			(xy 114.736791 -37.413258) (xy 114.778549 -37.509123) (xy 114.813037 -37.607836) (xy 114.840062 -37.708848)
			(xy 114.859475 -37.811594) (xy 114.871166 -37.915503) (xy 114.87507 -38.019995) (xy 118.424968 -38.019995)
			(xy 118.428872 -37.915504) (xy 118.440563 -37.811596) (xy 118.459974 -37.708849) (xy 118.486998 -37.607838)
			(xy 118.521484 -37.509125) (xy 118.563239 -37.41326) (xy 118.612032 -37.320778) (xy 118.667589 -37.232195)
			(xy 118.729602 -37.148005) (xy 118.797724 -37.068676) (xy 118.871575 -36.994652) (xy 118.950744 -36.926345)
			(xy 119.034789 -36.864136) (xy 119.078756 -36.835842) (xy 119.089932 -36.82873) (xy 119.102378 -36.806378)
			(xy 119.102378 -36.693602) (xy 119.089932 -36.67125) (xy 119.078756 -36.664138) (xy 119.03478 -36.635858)
			(xy 118.950735 -36.573648) (xy 118.871567 -36.505341) (xy 118.797716 -36.431316) (xy 118.729595 -36.351987)
			(xy 118.667583 -36.267796) (xy 118.612027 -36.179212) (xy 118.563235 -36.08673) (xy 118.52148 -35.990865)
			(xy 118.486995 -35.892152) (xy 118.459971 -35.79114) (xy 118.440561 -35.688394) (xy 118.428871 -35.584486)
			(xy 118.424968 -35.479995) (xy 118.428872 -35.375504) (xy 118.440563 -35.271596) (xy 118.459974 -35.168849)
			(xy 118.486998 -35.067838) (xy 118.521484 -34.969125) (xy 118.563239 -34.87326) (xy 118.612032 -34.780778)
			(xy 118.667589 -34.692195) (xy 118.729602 -34.608005) (xy 118.797724 -34.528676) (xy 118.871575 -34.454652)
			(xy 118.950744 -34.386345) (xy 119.034789 -34.324136) (xy 119.078756 -34.295842) (xy 119.089932 -34.28873)
			(xy 119.102378 -34.266378) (xy 119.102378 -34.153602) (xy 119.089932 -34.13125) (xy 119.078756 -34.124138)
			(xy 119.033105 -34.094744) (xy 118.946014 -34.02989) (xy 118.864209 -33.958484) (xy 118.788183 -33.880954)
			(xy 118.718393 -33.797766) (xy 118.655258 -33.70942) (xy 118.599159 -33.616449) (xy 118.550431 -33.51941)
			(xy 118.50937 -33.418887) (xy 118.47622 -33.315485) (xy 118.451182 -33.209825) (xy 118.434406 -33.102543)
			(xy 118.425993 -32.994283) (xy 118.425468 -32.93999) (xy 118.425985 -32.887639) (xy 118.433809 -32.783228)
			(xy 118.449413 -32.679695) (xy 118.472709 -32.577616) (xy 118.503568 -32.477564) (xy 118.541816 -32.380097)
			(xy 118.587239 -32.28576) (xy 118.639585 -32.195082) (xy 118.69856 -32.108567) (xy 118.763834 -32.026702)
			(xy 118.835043 -31.949942) (xy 118.911788 -31.878718) (xy 118.993641 -31.813427) (xy 119.080143 -31.754435)
			(xy 119.170811 -31.702071) (xy 119.265138 -31.656629) (xy 119.362598 -31.618361) (xy 119.462644 -31.587482)
			(xy 119.564717 -31.564166) (xy 119.668248 -31.548541) (xy 119.772657 -31.540696) (xy 119.825008 -31.540196)
			(xy 119.879308 -31.540684) (xy 119.987582 -31.549102) (xy 120.094878 -31.565887) (xy 120.20055 -31.590938)
			(xy 120.303962 -31.624104) (xy 120.404493 -31.665187) (xy 120.501537 -31.713937) (xy 120.59451 -31.770063)
			(xy 120.682853 -31.833226) (xy 120.766035 -31.903047) (xy 120.843555 -31.979105) (xy 120.914946 -32.060943)
			(xy 120.979779 -32.148068) (xy 121.009156 -32.193738) (xy 121.016268 -32.204914) (xy 121.03862 -32.21736)
			(xy 121.151396 -32.21736) (xy 121.173748 -32.204914) (xy 121.18086 -32.193738) (xy 121.210248 -32.148075)
			(xy 121.27508 -32.060952) (xy 121.346471 -31.979116) (xy 121.423991 -31.903059) (xy 121.507172 -31.83324)
			(xy 121.595514 -31.770078) (xy 121.688487 -31.713954) (xy 121.78553 -31.665205) (xy 121.886059 -31.624125)
			(xy 121.98947 -31.59096) (xy 122.095141 -31.56591) (xy 122.202436 -31.549126) (xy 122.310708 -31.540709)
			(xy 122.365008 -31.540196) (xy 122.417364 -31.54063) (xy 122.521784 -31.548457) (xy 122.625326 -31.564066)
			(xy 122.727413 -31.58737) (xy 122.827472 -31.618239) (xy 122.924944 -31.6565) (xy 123.019283 -31.701939)
			(xy 123.109963 -31.754302) (xy 123.196476 -31.813296) (xy 123.278337 -31.878591) (xy 123.35509 -31.949821)
			(xy 123.426304 -32.026588) (xy 123.491581 -32.108464) (xy 123.550557 -32.194989) (xy 123.6029 -32.28568)
			(xy 123.648319 -32.38003) (xy 123.686559 -32.47751) (xy 123.717407 -32.577575) (xy 123.740689 -32.679667)
			(xy 123.756277 -32.783212) (xy 123.764081 -32.887634) (xy 123.764548 -32.93999) (xy 123.764054 -32.994284)
			(xy 123.761654 -33.025168) (xy 130.797545 -33.025168) (xy 130.797545 -32.854812) (xy 130.80553 -32.684644)
			(xy 130.821482 -32.515037) (xy 130.845367 -32.346365) (xy 130.877131 -32.178997) (xy 130.916706 -32.013302)
			(xy 130.964003 -31.849644) (xy 131.01892 -31.688383) (xy 131.081335 -31.529873) (xy 131.151111 -31.374463)
			(xy 131.228094 -31.222495) (xy 131.312116 -31.074301) (xy 131.402992 -30.930209) (xy 131.500522 -30.790535)
			(xy 131.604492 -30.655586) (xy 131.714673 -30.525658) (xy 131.830822 -30.401038) (xy 131.952686 -30.281999)
			(xy 132.079994 -30.168803) (xy 132.212469 -30.061698) (xy 132.349819 -29.960921) (xy 132.491741 -29.866692)
			(xy 132.637923 -29.779219) (xy 132.788046 -29.698694) (xy 132.941777 -29.625294) (xy 133.09878 -29.55918)
			(xy 133.25871 -29.500498) (xy 133.421214 -29.449377) (xy 133.585935 -29.405929) (xy 133.752513 -29.37025)
			(xy 133.920579 -29.342418) (xy 134.089765 -29.322494) (xy 134.259699 -29.310522) (xy 134.430008 -29.306529)
			(xy 134.600317 -29.310522) (xy 134.770251 -29.322494) (xy 134.939437 -29.342418) (xy 135.107503 -29.37025)
			(xy 135.274081 -29.405929) (xy 135.438802 -29.449377) (xy 135.601306 -29.500498) (xy 135.761236 -29.55918)
			(xy 135.918239 -29.625294) (xy 136.07197 -29.698694) (xy 136.222093 -29.779219) (xy 136.368275 -29.866692)
			(xy 136.510197 -29.960921) (xy 136.647547 -30.061698) (xy 136.780022 -30.168803) (xy 136.90733 -30.281999)
			(xy 137.029194 -30.401038) (xy 137.145343 -30.525658) (xy 137.255524 -30.655586) (xy 137.359494 -30.790535)
			(xy 137.457024 -30.930209) (xy 137.5479 -31.074301) (xy 137.631922 -31.222495) (xy 137.708905 -31.374463)
			(xy 137.778681 -31.529873) (xy 137.841096 -31.688383) (xy 137.896013 -31.849644) (xy 137.94331 -32.013302)
			(xy 137.982885 -32.178997) (xy 138.014649 -32.346365) (xy 138.038534 -32.515037) (xy 138.054486 -32.684644)
			(xy 138.062471 -32.854812) (xy 138.06297 -32.93999) (xy 138.062471 -33.025168) (xy 138.054486 -33.195336)
			(xy 138.038534 -33.364943) (xy 138.014649 -33.533615) (xy 137.982885 -33.700983) (xy 137.94331 -33.866678)
			(xy 137.896013 -34.030336) (xy 137.841096 -34.191597) (xy 137.778681 -34.350107) (xy 137.708905 -34.505517)
			(xy 137.631922 -34.657485) (xy 137.5479 -34.805679) (xy 137.457024 -34.949771) (xy 137.359494 -35.089445)
			(xy 137.255524 -35.224394) (xy 137.145343 -35.354322) (xy 137.029194 -35.478942) (xy 136.90733 -35.597981)
			(xy 136.780022 -35.711177) (xy 136.647547 -35.818282) (xy 136.510197 -35.919059) (xy 136.368275 -36.013288)
			(xy 136.222093 -36.100761) (xy 136.07197 -36.181286) (xy 135.918239 -36.254686) (xy 135.761236 -36.3208)
			(xy 135.601306 -36.379482) (xy 135.438802 -36.430603) (xy 135.274081 -36.474051) (xy 135.107503 -36.50973)
			(xy 134.939437 -36.537562) (xy 134.770251 -36.557486) (xy 134.600317 -36.569458) (xy 134.430008 -36.573452)
			(xy 134.259699 -36.569458) (xy 134.089765 -36.557486) (xy 133.920579 -36.537562) (xy 133.752513 -36.50973)
			(xy 133.585935 -36.474051) (xy 133.421214 -36.430603) (xy 133.25871 -36.379482) (xy 133.09878 -36.3208)
			(xy 132.941777 -36.254686) (xy 132.788046 -36.181286) (xy 132.637923 -36.100761) (xy 132.491741 -36.013288)
			(xy 132.349819 -35.919059) (xy 132.212469 -35.818282) (xy 132.079994 -35.711177) (xy 131.952686 -35.597981)
			(xy 131.830822 -35.478942) (xy 131.714673 -35.354322) (xy 131.604492 -35.224394) (xy 131.500522 -35.089445)
			(xy 131.402992 -34.949771) (xy 131.312116 -34.805679) (xy 131.228094 -34.657485) (xy 131.151111 -34.505517)
			(xy 131.081335 -34.350107) (xy 131.01892 -34.191597) (xy 130.964003 -34.030336) (xy 130.916706 -33.866678)
			(xy 130.877131 -33.700983) (xy 130.845367 -33.533615) (xy 130.821482 -33.364943) (xy 130.80553 -33.195336)
			(xy 130.797545 -33.025168) (xy 123.761654 -33.025168) (xy 123.755641 -33.102545) (xy 123.738864 -33.209828)
			(xy 123.713825 -33.315489) (xy 123.680673 -33.418892) (xy 123.639609 -33.519415) (xy 123.590879 -33.616455)
			(xy 123.534776 -33.709426) (xy 123.471638 -33.797771) (xy 123.401844 -33.880957) (xy 123.325813 -33.958486)
			(xy 123.244005 -34.029889) (xy 123.156909 -34.094739) (xy 123.11126 -34.124138) (xy 123.100084 -34.13125)
			(xy 123.087638 -34.153602) (xy 123.087638 -34.266378) (xy 123.100084 -34.28873) (xy 123.11126 -34.295842)
			(xy 123.15522 -34.324148) (xy 123.239268 -34.386354) (xy 123.318441 -34.454658) (xy 123.392295 -34.52868)
			(xy 123.46042 -34.608006) (xy 123.522436 -34.692195) (xy 123.577996 -34.780777) (xy 123.626791 -34.873258)
			(xy 123.668549 -34.969123) (xy 123.703037 -35.067836) (xy 123.730062 -35.168848) (xy 123.749475 -35.271594)
			(xy 123.761166 -35.375503) (xy 123.76507 -35.479995) (xy 123.761167 -35.584486) (xy 123.749476 -35.688395)
			(xy 123.730065 -35.791142) (xy 123.70304 -35.892154) (xy 123.668553 -35.990867) (xy 123.626796 -36.086732)
			(xy 123.578001 -36.179214) (xy 123.522442 -36.267796) (xy 123.460427 -36.351986) (xy 123.392303 -36.431313)
			(xy 123.318449 -36.505335) (xy 123.239277 -36.57364) (xy 123.155229 -36.635846) (xy 123.11126 -36.664138)
			(xy 123.100084 -36.67125) (xy 123.087638 -36.693602) (xy 123.087638 -36.806378) (xy 123.100084 -36.82873)
			(xy 123.11126 -36.835842) (xy 123.15522 -36.864148) (xy 123.239268 -36.926354) (xy 123.318441 -36.994658)
			(xy 123.392295 -37.06868) (xy 123.46042 -37.148006) (xy 123.522436 -37.232195) (xy 123.577996 -37.320777)
			(xy 123.626791 -37.413258) (xy 123.668549 -37.509123) (xy 123.703037 -37.607836) (xy 123.730062 -37.708848)
			(xy 123.749475 -37.811594) (xy 123.761166 -37.915503) (xy 123.76507 -38.019995) (xy 123.764517 -38.03481)
			(xy 165.292523 -38.03481) (xy 165.292523 -37.864454) (xy 165.300508 -37.694286) (xy 165.31646 -37.524679)
			(xy 165.340345 -37.356007) (xy 165.372109 -37.188639) (xy 165.411684 -37.022944) (xy 165.458981 -36.859286)
			(xy 165.513898 -36.698025) (xy 165.576313 -36.539515) (xy 165.646089 -36.384105) (xy 165.723072 -36.232137)
			(xy 165.807094 -36.083943) (xy 165.89797 -35.939851) (xy 165.9955 -35.800177) (xy 166.09947 -35.665228)
			(xy 166.209651 -35.5353) (xy 166.3258 -35.41068) (xy 166.447664 -35.291641) (xy 166.574972 -35.178445)
			(xy 166.707447 -35.07134) (xy 166.844797 -34.970563) (xy 166.986719 -34.876334) (xy 167.132901 -34.788861)
			(xy 167.283024 -34.708336) (xy 167.436755 -34.634936) (xy 167.593758 -34.568822) (xy 167.753688 -34.51014)
			(xy 167.916192 -34.459019) (xy 168.080913 -34.415571) (xy 168.247491 -34.379892) (xy 168.415557 -34.35206)
			(xy 168.584743 -34.332136) (xy 168.754677 -34.320164) (xy 168.924986 -34.316171) (xy 169.095295 -34.320164)
			(xy 169.265229 -34.332136) (xy 169.434415 -34.35206) (xy 169.602481 -34.379892) (xy 169.769059 -34.415571)
			(xy 169.93378 -34.459019) (xy 170.096284 -34.51014) (xy 170.256214 -34.568822) (xy 170.413217 -34.634936)
			(xy 170.566948 -34.708336) (xy 170.717071 -34.788861) (xy 170.863253 -34.876334) (xy 171.005175 -34.970563)
			(xy 171.142525 -35.07134) (xy 171.275 -35.178445) (xy 171.402308 -35.291641) (xy 171.523084 -35.409617)
			(xy 179.589712 -35.409617) (xy 179.593616 -35.305116) (xy 179.60531 -35.201197) (xy 179.624729 -35.098442)
			(xy 179.651763 -34.997422) (xy 179.686262 -34.898703) (xy 179.728034 -34.802833) (xy 179.776846 -34.71035)
			(xy 179.832424 -34.621768) (xy 179.89446 -34.537581) (xy 179.962607 -34.458261) (xy 180.036485 -34.384248)
			(xy 180.115681 -34.315956) (xy 180.199754 -34.253767) (xy 180.243734 -34.225484) (xy 180.25491 -34.218372)
			(xy 180.267356 -34.19602) (xy 180.267356 -34.083244) (xy 180.25491 -34.060892) (xy 180.243734 -34.05378)
			(xy 180.199782 -34.025453) (xy 180.115707 -33.963265) (xy 180.03651 -33.894975) (xy 179.96263 -33.820964)
			(xy 179.894482 -33.741645) (xy 179.832444 -33.65746) (xy 179.776863 -33.56888) (xy 179.728049 -33.476397)
			(xy 179.686275 -33.380529) (xy 179.651773 -33.28181) (xy 179.624736 -33.180792) (xy 179.605315 -33.078036)
			(xy 179.593619 -32.974118) (xy 179.589712 -32.869617) (xy 179.593616 -32.765116) (xy 179.60531 -32.661197)
			(xy 179.624729 -32.558442) (xy 179.651763 -32.457422) (xy 179.686262 -32.358703) (xy 179.728034 -32.262833)
			(xy 179.776846 -32.17035) (xy 179.832424 -32.081768) (xy 179.89446 -31.997581) (xy 179.962607 -31.918261)
			(xy 180.036485 -31.844248) (xy 180.115681 -31.775956) (xy 180.199754 -31.713767) (xy 180.243734 -31.685484)
			(xy 180.25491 -31.678372) (xy 180.267356 -31.65602) (xy 180.267356 -31.543244) (xy 180.25491 -31.520892)
			(xy 180.243734 -31.51378) (xy 180.198088 -31.484366) (xy 180.110965 -31.419535) (xy 180.029129 -31.348147)
			(xy 179.953072 -31.27063) (xy 179.883253 -31.187451) (xy 179.82009 -31.099111) (xy 179.763965 -31.006141)
			(xy 179.715214 -30.9091) (xy 179.674132 -30.808573) (xy 179.640965 -30.705163) (xy 179.615913 -30.599495)
			(xy 179.599126 -30.492202) (xy 179.590707 -30.383931) (xy 179.590192 -30.329632) (xy 179.590669 -30.277276)
			(xy 179.598492 -30.172858) (xy 179.614099 -30.069316) (xy 179.6374 -29.967231) (xy 179.668266 -29.867172)
			(xy 179.706525 -29.7697) (xy 179.751961 -29.675361) (xy 179.804321 -29.584681) (xy 179.863313 -29.498168)
			(xy 179.928605 -29.416307) (xy 179.999834 -29.339554) (xy 180.076599 -29.26834) (xy 180.158473 -29.203062)
			(xy 180.244996 -29.144086) (xy 180.335685 -29.091742) (xy 180.430033 -29.046323) (xy 180.527512 -29.008082)
			(xy 180.627576 -28.977234) (xy 180.729666 -28.953951) (xy 180.83321 -28.938364) (xy 180.93763 -28.930559)
			(xy 180.989986 -28.930092) (xy 181.04428 -28.93057) (xy 181.152542 -28.938984) (xy 181.259826 -28.955761)
			(xy 181.365488 -28.980801) (xy 181.468891 -29.013953) (xy 181.569415 -29.055018) (xy 181.666455 -29.10375)
			(xy 181.759426 -29.159854) (xy 181.847771 -29.222994) (xy 181.930957 -29.29279) (xy 182.008485 -29.368822)
			(xy 182.079887 -29.450632) (xy 182.144736 -29.53773) (xy 182.174134 -29.58338) (xy 182.181246 -29.594556)
			(xy 182.203598 -29.607002) (xy 182.316374 -29.607002) (xy 182.338726 -29.594556) (xy 182.345838 -29.58338)
			(xy 182.375221 -29.537722) (xy 182.440077 -29.450633) (xy 182.511486 -29.36883) (xy 182.589018 -29.292806)
			(xy 182.672208 -29.223017) (xy 182.760554 -29.159884) (xy 182.853527 -29.103785) (xy 182.950566 -29.055059)
			(xy 183.051089 -29.013997) (xy 183.154491 -28.980848) (xy 183.260151 -28.955809) (xy 183.367433 -28.939033)
			(xy 183.475693 -28.930618) (xy 183.529986 -28.930092) (xy 183.582338 -28.930608) (xy 183.686749 -28.938431)
			(xy 183.790283 -28.954033) (xy 183.892362 -28.977328) (xy 183.992415 -29.008186) (xy 184.089883 -29.046433)
			(xy 184.18422 -29.091856) (xy 184.2749 -29.144202) (xy 184.361415 -29.203176) (xy 184.443281 -29.268451)
			(xy 184.520041 -29.33966) (xy 184.591265 -29.416405) (xy 184.656556 -29.498258) (xy 184.715548 -29.584761)
			(xy 184.767912 -29.67543) (xy 184.813354 -29.769758) (xy 184.851621 -29.867218) (xy 184.882499 -29.967265)
			(xy 184.905814 -30.06934) (xy 184.921437 -30.172871) (xy 184.929281 -30.27728) (xy 184.92978 -30.329632)
			(xy 184.929276 -30.383932) (xy 184.920857 -30.492205) (xy 184.904071 -30.599499) (xy 184.87902 -30.70517)
			(xy 184.845853 -30.808581) (xy 184.804772 -30.909111) (xy 184.756023 -31.006154) (xy 184.699899 -31.099127)
			(xy 184.636737 -31.18747) (xy 184.566919 -31.270653) (xy 184.490864 -31.348173) (xy 184.409029 -31.419566)
			(xy 184.321907 -31.484402) (xy 184.276238 -31.51378) (xy 184.265062 -31.520892) (xy 184.252616 -31.543244)
			(xy 184.252616 -31.65602) (xy 184.265062 -31.678372) (xy 184.276238 -31.685484) (xy 184.320247 -31.713723)
			(xy 184.404319 -31.775918) (xy 184.483515 -31.844214) (xy 184.557391 -31.918231) (xy 184.625537 -31.997556)
			(xy 184.687572 -32.081746) (xy 184.74315 -32.170331) (xy 184.791961 -32.262818) (xy 184.833732 -32.35869)
			(xy 184.868231 -32.457412) (xy 184.895265 -32.558434) (xy 184.914682 -32.661192) (xy 184.926376 -32.765113)
			(xy 184.930281 -32.869617) (xy 184.926374 -32.974121) (xy 184.914677 -33.078041) (xy 184.895257 -33.180799)
			(xy 184.868221 -33.28182) (xy 184.83372 -33.380542) (xy 184.791946 -33.476413) (xy 184.743133 -33.568899)
			(xy 184.687553 -33.657483) (xy 184.625516 -33.741671) (xy 184.557368 -33.820994) (xy 184.48349 -33.895009)
			(xy 184.404293 -33.963304) (xy 184.320219 -34.025496) (xy 184.276238 -34.05378) (xy 184.265062 -34.060892)
			(xy 184.252616 -34.083244) (xy 184.252616 -34.19602) (xy 184.265062 -34.218372) (xy 184.276238 -34.225484)
			(xy 184.320247 -34.253723) (xy 184.404319 -34.315918) (xy 184.483515 -34.384214) (xy 184.557391 -34.458231)
			(xy 184.625537 -34.537556) (xy 184.687572 -34.621746) (xy 184.74315 -34.710331) (xy 184.791961 -34.802818)
			(xy 184.833732 -34.89869) (xy 184.868231 -34.997412) (xy 184.895265 -35.098434) (xy 184.914682 -35.201192)
			(xy 184.926376 -35.305113) (xy 184.930281 -35.409617) (xy 188.479712 -35.409617) (xy 188.483616 -35.305116)
			(xy 188.49531 -35.201197) (xy 188.514729 -35.098442) (xy 188.541763 -34.997422) (xy 188.576262 -34.898703)
			(xy 188.618034 -34.802833) (xy 188.666846 -34.71035) (xy 188.722424 -34.621768) (xy 188.78446 -34.537581)
			(xy 188.852607 -34.458261) (xy 188.926485 -34.384248) (xy 189.005681 -34.315956) (xy 189.089754 -34.253767)
			(xy 189.133734 -34.225484) (xy 189.14491 -34.218372) (xy 189.157356 -34.19602) (xy 189.157356 -34.083244)
			(xy 189.14491 -34.060892) (xy 189.133734 -34.05378) (xy 189.089782 -34.025453) (xy 189.005707 -33.963265)
			(xy 188.92651 -33.894975) (xy 188.85263 -33.820964) (xy 188.784482 -33.741645) (xy 188.722444 -33.65746)
			(xy 188.666863 -33.56888) (xy 188.618049 -33.476397) (xy 188.576275 -33.380529) (xy 188.541773 -33.28181)
			(xy 188.514736 -33.180792) (xy 188.495315 -33.078036) (xy 188.483619 -32.974118) (xy 188.479712 -32.869617)
			(xy 188.483616 -32.765116) (xy 188.49531 -32.661197) (xy 188.514729 -32.558442) (xy 188.541763 -32.457422)
			(xy 188.576262 -32.358703) (xy 188.618034 -32.262833) (xy 188.666846 -32.17035) (xy 188.722424 -32.081768)
			(xy 188.78446 -31.997581) (xy 188.852607 -31.918261) (xy 188.926485 -31.844248) (xy 189.005681 -31.775956)
			(xy 189.089754 -31.713767) (xy 189.133734 -31.685484) (xy 189.14491 -31.678372) (xy 189.157356 -31.65602)
			(xy 189.157356 -31.543244) (xy 189.14491 -31.520892) (xy 189.133734 -31.51378) (xy 189.088088 -31.484366)
			(xy 189.000965 -31.419535) (xy 188.919129 -31.348147) (xy 188.843072 -31.27063) (xy 188.773253 -31.187451)
			(xy 188.71009 -31.099111) (xy 188.653965 -31.006141) (xy 188.605214 -30.9091) (xy 188.564132 -30.808573)
			(xy 188.530965 -30.705163) (xy 188.505913 -30.599495) (xy 188.489126 -30.492202) (xy 188.480707 -30.383931)
			(xy 188.480192 -30.329632) (xy 188.480669 -30.277276) (xy 188.488492 -30.172858) (xy 188.504099 -30.069316)
			(xy 188.5274 -29.967231) (xy 188.558266 -29.867172) (xy 188.596525 -29.7697) (xy 188.641961 -29.675361)
			(xy 188.694321 -29.584681) (xy 188.753313 -29.498168) (xy 188.818605 -29.416307) (xy 188.889834 -29.339554)
			(xy 188.966599 -29.26834) (xy 189.048473 -29.203062) (xy 189.134996 -29.144086) (xy 189.225685 -29.091742)
			(xy 189.320033 -29.046323) (xy 189.417512 -29.008082) (xy 189.517576 -28.977234) (xy 189.619666 -28.953951)
			(xy 189.72321 -28.938364) (xy 189.82763 -28.930559) (xy 189.879986 -28.930092) (xy 189.93428 -28.93057)
			(xy 190.042542 -28.938984) (xy 190.149826 -28.955761) (xy 190.255488 -28.980801) (xy 190.358891 -29.013953)
			(xy 190.459415 -29.055018) (xy 190.556455 -29.10375) (xy 190.649426 -29.159854) (xy 190.737771 -29.222994)
			(xy 190.820957 -29.29279) (xy 190.898485 -29.368822) (xy 190.969887 -29.450632) (xy 191.034736 -29.53773)
			(xy 191.064134 -29.58338) (xy 191.071246 -29.594556) (xy 191.093598 -29.607002) (xy 191.206374 -29.607002)
			(xy 191.228726 -29.594556) (xy 191.235838 -29.58338) (xy 191.265221 -29.537722) (xy 191.330077 -29.450633)
			(xy 191.401486 -29.36883) (xy 191.479018 -29.292806) (xy 191.562208 -29.223017) (xy 191.650554 -29.159884)
			(xy 191.743527 -29.103785) (xy 191.840566 -29.055059) (xy 191.941089 -29.013997) (xy 192.044491 -28.980848)
			(xy 192.150151 -28.955809) (xy 192.257433 -28.939033) (xy 192.365693 -28.930618) (xy 192.419986 -28.930092)
			(xy 192.472338 -28.930608) (xy 192.576749 -28.938431) (xy 192.680283 -28.954033) (xy 192.782362 -28.977328)
			(xy 192.882415 -29.008186) (xy 192.979883 -29.046433) (xy 193.07422 -29.091856) (xy 193.1649 -29.144202)
			(xy 193.251415 -29.203176) (xy 193.333281 -29.268451) (xy 193.410041 -29.33966) (xy 193.481265 -29.416405)
			(xy 193.546556 -29.498258) (xy 193.605548 -29.584761) (xy 193.657912 -29.67543) (xy 193.703354 -29.769758)
			(xy 193.741621 -29.867218) (xy 193.772499 -29.967265) (xy 193.795814 -30.06934) (xy 193.811437 -30.172871)
			(xy 193.819281 -30.27728) (xy 193.81978 -30.329632) (xy 193.819276 -30.383932) (xy 193.810857 -30.492205)
			(xy 193.794071 -30.599499) (xy 193.76902 -30.70517) (xy 193.735853 -30.808581) (xy 193.694772 -30.909111)
			(xy 193.646023 -31.006154) (xy 193.589899 -31.099127) (xy 193.526737 -31.18747) (xy 193.456919 -31.270653)
			(xy 193.380864 -31.348173) (xy 193.299029 -31.419566) (xy 193.211907 -31.484402) (xy 193.166238 -31.51378)
			(xy 193.155062 -31.520892) (xy 193.142616 -31.543244) (xy 193.142616 -31.65602) (xy 193.155062 -31.678372)
			(xy 193.166238 -31.685484) (xy 193.210247 -31.713723) (xy 193.294319 -31.775918) (xy 193.373515 -31.844214)
			(xy 193.447391 -31.918231) (xy 193.515537 -31.997556) (xy 193.577572 -32.081746) (xy 193.63315 -32.170331)
			(xy 193.681961 -32.262818) (xy 193.723732 -32.35869) (xy 193.758231 -32.457412) (xy 193.785265 -32.558434)
			(xy 193.804682 -32.661192) (xy 193.816376 -32.765113) (xy 193.820281 -32.869617) (xy 193.816374 -32.974121)
			(xy 193.804677 -33.078041) (xy 193.785257 -33.180799) (xy 193.758221 -33.28182) (xy 193.72372 -33.380542)
			(xy 193.681946 -33.476413) (xy 193.633133 -33.568899) (xy 193.577553 -33.657483) (xy 193.515516 -33.741671)
			(xy 193.447368 -33.820994) (xy 193.37349 -33.895009) (xy 193.294293 -33.963304) (xy 193.210219 -34.025496)
			(xy 193.166238 -34.05378) (xy 193.155062 -34.060892) (xy 193.142616 -34.083244) (xy 193.142616 -34.19602)
			(xy 193.155062 -34.218372) (xy 193.166238 -34.225484) (xy 193.210247 -34.253723) (xy 193.294319 -34.315918)
			(xy 193.373515 -34.384214) (xy 193.447391 -34.458231) (xy 193.515537 -34.537556) (xy 193.577572 -34.621746)
			(xy 193.63315 -34.710331) (xy 193.681961 -34.802818) (xy 193.723732 -34.89869) (xy 193.758231 -34.997412)
			(xy 193.785265 -35.098434) (xy 193.804682 -35.201192) (xy 193.816376 -35.305113) (xy 193.820281 -35.409617)
			(xy 197.369712 -35.409617) (xy 197.373616 -35.305116) (xy 197.38531 -35.201197) (xy 197.404729 -35.098442)
			(xy 197.431763 -34.997422) (xy 197.466262 -34.898703) (xy 197.508034 -34.802833) (xy 197.556846 -34.71035)
			(xy 197.612424 -34.621768) (xy 197.67446 -34.537581) (xy 197.742607 -34.458261) (xy 197.816485 -34.384248)
			(xy 197.895681 -34.315956) (xy 197.979754 -34.253767) (xy 198.023734 -34.225484) (xy 198.03491 -34.218372)
			(xy 198.047356 -34.19602) (xy 198.047356 -34.083244) (xy 198.03491 -34.060892) (xy 198.023734 -34.05378)
			(xy 197.979782 -34.025453) (xy 197.895707 -33.963265) (xy 197.81651 -33.894975) (xy 197.74263 -33.820964)
			(xy 197.674482 -33.741645) (xy 197.612444 -33.65746) (xy 197.556863 -33.56888) (xy 197.508049 -33.476397)
			(xy 197.466275 -33.380529) (xy 197.431773 -33.28181) (xy 197.404736 -33.180792) (xy 197.385315 -33.078036)
			(xy 197.373619 -32.974118) (xy 197.369712 -32.869617) (xy 197.373616 -32.765116) (xy 197.38531 -32.661197)
			(xy 197.404729 -32.558442) (xy 197.431763 -32.457422) (xy 197.466262 -32.358703) (xy 197.508034 -32.262833)
			(xy 197.556846 -32.17035) (xy 197.612424 -32.081768) (xy 197.67446 -31.997581) (xy 197.742607 -31.918261)
			(xy 197.816485 -31.844248) (xy 197.895681 -31.775956) (xy 197.979754 -31.713767) (xy 198.023734 -31.685484)
			(xy 198.03491 -31.678372) (xy 198.047356 -31.65602) (xy 198.047356 -31.543244) (xy 198.03491 -31.520892)
			(xy 198.023734 -31.51378) (xy 197.978088 -31.484366) (xy 197.890965 -31.419535) (xy 197.809129 -31.348147)
			(xy 197.733072 -31.27063) (xy 197.663253 -31.187451) (xy 197.60009 -31.099111) (xy 197.543965 -31.006141)
			(xy 197.495214 -30.9091) (xy 197.454132 -30.808573) (xy 197.420965 -30.705163) (xy 197.395913 -30.599495)
			(xy 197.379126 -30.492202) (xy 197.370707 -30.383931) (xy 197.370192 -30.329632) (xy 197.370669 -30.277276)
			(xy 197.378492 -30.172858) (xy 197.394099 -30.069316) (xy 197.4174 -29.967231) (xy 197.448266 -29.867172)
			(xy 197.486525 -29.7697) (xy 197.531961 -29.675361) (xy 197.584321 -29.584681) (xy 197.643313 -29.498168)
			(xy 197.708605 -29.416307) (xy 197.779834 -29.339554) (xy 197.856599 -29.26834) (xy 197.938473 -29.203062)
			(xy 198.024996 -29.144086) (xy 198.115685 -29.091742) (xy 198.210033 -29.046323) (xy 198.307512 -29.008082)
			(xy 198.407576 -28.977234) (xy 198.509666 -28.953951) (xy 198.61321 -28.938364) (xy 198.71763 -28.930559)
			(xy 198.769986 -28.930092) (xy 198.82428 -28.93057) (xy 198.932542 -28.938984) (xy 199.039826 -28.955761)
			(xy 199.145488 -28.980801) (xy 199.248891 -29.013953) (xy 199.349415 -29.055018) (xy 199.446455 -29.10375)
			(xy 199.539426 -29.159854) (xy 199.627771 -29.222994) (xy 199.710957 -29.29279) (xy 199.788485 -29.368822)
			(xy 199.859887 -29.450632) (xy 199.924736 -29.53773) (xy 199.954134 -29.58338) (xy 199.961246 -29.594556)
			(xy 199.983598 -29.607002) (xy 200.096374 -29.607002) (xy 200.118726 -29.594556) (xy 200.125838 -29.58338)
			(xy 200.155221 -29.537722) (xy 200.220077 -29.450633) (xy 200.291486 -29.36883) (xy 200.369018 -29.292806)
			(xy 200.452208 -29.223017) (xy 200.540554 -29.159884) (xy 200.633527 -29.103785) (xy 200.730566 -29.055059)
			(xy 200.831089 -29.013997) (xy 200.934491 -28.980848) (xy 201.040151 -28.955809) (xy 201.147433 -28.939033)
			(xy 201.255693 -28.930618) (xy 201.309986 -28.930092) (xy 201.362338 -28.930608) (xy 201.466749 -28.938431)
			(xy 201.570283 -28.954033) (xy 201.672362 -28.977328) (xy 201.772415 -29.008186) (xy 201.869883 -29.046433)
			(xy 201.96422 -29.091856) (xy 202.0549 -29.144202) (xy 202.141415 -29.203176) (xy 202.223281 -29.268451)
			(xy 202.300041 -29.33966) (xy 202.371265 -29.416405) (xy 202.436556 -29.498258) (xy 202.495548 -29.584761)
			(xy 202.547912 -29.67543) (xy 202.593354 -29.769758) (xy 202.631621 -29.867218) (xy 202.662499 -29.967265)
			(xy 202.685814 -30.06934) (xy 202.701437 -30.172871) (xy 202.709281 -30.27728) (xy 202.70978 -30.329632)
			(xy 202.709276 -30.383932) (xy 202.700857 -30.492205) (xy 202.684071 -30.599499) (xy 202.663256 -30.6873)
			(xy 284.351952 -30.6873) (xy 284.355982 -30.602696) (xy 284.368036 -30.518857) (xy 284.388005 -30.436544)
			(xy 284.415708 -30.356502) (xy 284.450893 -30.279456) (xy 284.493244 -30.206103) (xy 284.542375 -30.137109)
			(xy 284.597842 -30.073096) (xy 284.659142 -30.014646) (xy 284.725721 -29.962288) (xy 284.796976 -29.916495)
			(xy 284.87226 -29.877683) (xy 284.950894 -29.846203) (xy 285.032163 -29.822341) (xy 285.115333 -29.806311)
			(xy 285.19965 -29.79826) (xy 285.242 -29.797756) (xy 285.288396 -29.798333) (xy 285.380684 -29.807979)
			(xy 285.471468 -29.827177) (xy 285.559762 -29.855717) (xy 285.602426 -29.873956) (xy 285.612368 -29.877762)
			(xy 285.633632 -29.877762) (xy 285.643574 -29.873956) (xy 285.686235 -29.855709) (xy 285.774528 -29.827166)
			(xy 285.865313 -29.807974) (xy 285.957604 -29.798341) (xy 286.004 -29.797756) (xy 286.047483 -29.798269)
			(xy 286.134036 -29.806754) (xy 286.219347 -29.823643) (xy 286.302603 -29.848776) (xy 286.38301 -29.881911)
			(xy 286.459801 -29.922733) (xy 286.532242 -29.970853) (xy 286.599643 -30.025811) (xy 286.630872 -30.056074)
			(xy 286.638238 -30.063186) (xy 286.656526 -30.070806) (xy 286.748474 -30.070806) (xy 286.766762 -30.063186)
			(xy 286.774128 -30.056074) (xy 286.805348 -30.025802) (xy 286.872752 -29.970849) (xy 286.945196 -29.922734)
			(xy 287.021989 -29.881915) (xy 287.102397 -29.848783) (xy 287.185654 -29.823654) (xy 287.270965 -29.806766)
			(xy 287.357517 -29.798282) (xy 287.401 -29.797756) (xy 287.447396 -29.798333) (xy 287.539684 -29.807979)
			(xy 287.630468 -29.827177) (xy 287.718762 -29.855717) (xy 287.761426 -29.873956) (xy 287.771368 -29.877762)
			(xy 287.792632 -29.877762) (xy 287.802574 -29.873956) (xy 287.845235 -29.855709) (xy 287.933528 -29.827166)
			(xy 288.024313 -29.807974) (xy 288.116604 -29.798341) (xy 288.163 -29.797756) (xy 288.205347 -29.798332)
			(xy 288.289657 -29.806382) (xy 288.37282 -29.822411) (xy 288.454083 -29.846271) (xy 288.53271 -29.877749)
			(xy 288.607988 -29.916558) (xy 288.679237 -29.962347) (xy 288.745811 -30.014701) (xy 288.807106 -30.073146)
			(xy 288.862569 -30.137153) (xy 288.911696 -30.206142) (xy 288.954043 -30.279489) (xy 288.989226 -30.356529)
			(xy 289.016926 -30.436565) (xy 289.036893 -30.518871) (xy 289.048947 -30.602702) (xy 289.052977 -30.6873)
			(xy 289.048947 -30.771898) (xy 289.036893 -30.855729) (xy 289.016926 -30.938035) (xy 288.989226 -31.018071)
			(xy 288.954043 -31.095111) (xy 288.911696 -31.168458) (xy 288.862569 -31.237447) (xy 288.807106 -31.301454)
			(xy 288.745811 -31.359899) (xy 288.679237 -31.412253) (xy 288.607988 -31.458042) (xy 288.53271 -31.496851)
			(xy 288.454083 -31.528329) (xy 288.37282 -31.552189) (xy 288.289657 -31.568218) (xy 288.205347 -31.576268)
			(xy 288.163 -31.576772) (xy 288.116604 -31.576192) (xy 288.024316 -31.566547) (xy 287.933532 -31.54735)
			(xy 287.845239 -31.518811) (xy 287.802574 -31.500572) (xy 287.792632 -31.496766) (xy 287.771368 -31.496766)
			(xy 287.761426 -31.500572) (xy 287.718763 -31.518815) (xy 287.630471 -31.54736) (xy 287.539686 -31.566553)
			(xy 287.447396 -31.576187) (xy 287.401 -31.576772) (xy 287.357516 -31.57628) (xy 287.270963 -31.567794)
			(xy 287.18565 -31.550903) (xy 287.102393 -31.525769) (xy 287.021986 -31.492631) (xy 286.945195 -31.451805)
			(xy 286.872755 -31.403681) (xy 286.805356 -31.348719) (xy 286.774128 -31.318454) (xy 286.766762 -31.311342)
			(xy 286.748474 -31.303722) (xy 286.656526 -31.303722) (xy 286.638238 -31.311342) (xy 286.630872 -31.318454)
			(xy 286.599639 -31.348712) (xy 286.532238 -31.403668) (xy 286.459797 -31.451787) (xy 286.383007 -31.492607)
			(xy 286.3026 -31.525741) (xy 286.219344 -31.550873) (xy 286.134034 -31.567761) (xy 286.047483 -31.576246)
			(xy 286.004 -31.576772) (xy 285.957604 -31.576192) (xy 285.865316 -31.566547) (xy 285.774532 -31.54735)
			(xy 285.686239 -31.518811) (xy 285.643574 -31.500572) (xy 285.633632 -31.496766) (xy 285.612368 -31.496766)
			(xy 285.602426 -31.500572) (xy 285.559763 -31.518815) (xy 285.471471 -31.54736) (xy 285.380686 -31.566553)
			(xy 285.288396 -31.576187) (xy 285.242 -31.576772) (xy 285.19965 -31.57634) (xy 285.115333 -31.568289)
			(xy 285.032163 -31.552259) (xy 284.950894 -31.528397) (xy 284.87226 -31.496917) (xy 284.796976 -31.458105)
			(xy 284.725721 -31.412312) (xy 284.659142 -31.359954) (xy 284.597842 -31.301504) (xy 284.542375 -31.237491)
			(xy 284.493244 -31.168497) (xy 284.450893 -31.095144) (xy 284.415708 -31.018098) (xy 284.388005 -30.938056)
			(xy 284.368036 -30.855743) (xy 284.355982 -30.771904) (xy 284.351952 -30.6873) (xy 202.663256 -30.6873)
			(xy 202.65902 -30.70517) (xy 202.625853 -30.808581) (xy 202.584772 -30.909111) (xy 202.536023 -31.006154)
			(xy 202.479899 -31.099127) (xy 202.416737 -31.18747) (xy 202.346919 -31.270653) (xy 202.270864 -31.348173)
			(xy 202.189029 -31.419566) (xy 202.101907 -31.484402) (xy 202.056238 -31.51378) (xy 202.045062 -31.520892)
			(xy 202.032616 -31.543244) (xy 202.032616 -31.65602) (xy 202.045062 -31.678372) (xy 202.056238 -31.685484)
			(xy 202.100247 -31.713723) (xy 202.184319 -31.775918) (xy 202.263515 -31.844214) (xy 202.337391 -31.918231)
			(xy 202.405537 -31.997556) (xy 202.467572 -32.081746) (xy 202.52315 -32.170331) (xy 202.571961 -32.262818)
			(xy 202.613732 -32.35869) (xy 202.648231 -32.457412) (xy 202.675265 -32.558434) (xy 202.694682 -32.661192)
			(xy 202.706376 -32.765113) (xy 202.710281 -32.869617) (xy 202.706374 -32.974121) (xy 202.694677 -33.078041)
			(xy 202.688184 -33.112399) (xy 274.529292 -33.112399) (xy 274.529292 -33.027677) (xy 274.537345 -32.94334)
			(xy 274.553379 -32.86015) (xy 274.577247 -32.77886) (xy 274.608735 -32.700208) (xy 274.647557 -32.624905)
			(xy 274.69336 -32.553633) (xy 274.745731 -32.487037) (xy 274.804196 -32.425722) (xy 274.868224 -32.370241)
			(xy 274.937236 -32.321098) (xy 275.010606 -32.278738) (xy 275.087671 -32.243543) (xy 275.167733 -32.215834)
			(xy 275.250066 -32.19586) (xy 275.333925 -32.183803) (xy 275.41855 -32.179772) (xy 275.503175 -32.183803)
			(xy 275.587034 -32.19586) (xy 275.598955 -32.198752) (xy 282.524141 -32.198752) (xy 282.524141 -32.114048)
			(xy 282.532193 -32.029727) (xy 282.548223 -31.946554) (xy 282.572088 -31.865281) (xy 282.60357 -31.786644)
			(xy 282.642385 -31.711356) (xy 282.68818 -31.640099) (xy 282.740542 -31.573518) (xy 282.798996 -31.512216)
			(xy 282.863012 -31.456748) (xy 282.932012 -31.407616) (xy 282.968446 -31.386018) (xy 283.002302 -31.366983)
			(xy 283.072707 -31.334173) (xy 283.145705 -31.307624) (xy 283.220737 -31.287536) (xy 283.297235 -31.274064)
			(xy 283.374616 -31.267309) (xy 283.413454 -31.266892) (xy 283.455805 -31.267378) (xy 283.540123 -31.275425)
			(xy 283.623294 -31.291451) (xy 283.704565 -31.315311) (xy 283.783201 -31.346788) (xy 283.858487 -31.385598)
			(xy 283.929744 -31.431388) (xy 283.996325 -31.483745) (xy 284.057628 -31.542194) (xy 284.113097 -31.606206)
			(xy 284.16223 -31.6752) (xy 284.204582 -31.748553) (xy 284.239769 -31.8256) (xy 284.267473 -31.905642)
			(xy 284.287443 -31.987956) (xy 284.299498 -32.071795) (xy 284.303528 -32.1564) (xy 284.299498 -32.241005)
			(xy 284.287443 -32.324844) (xy 284.267473 -32.407158) (xy 284.239769 -32.4872) (xy 284.204582 -32.564247)
			(xy 284.16223 -32.6376) (xy 284.113097 -32.706594) (xy 284.057628 -32.770606) (xy 283.996325 -32.829055)
			(xy 283.929744 -32.881412) (xy 283.858487 -32.927202) (xy 283.783201 -32.966012) (xy 283.704565 -32.997489)
			(xy 283.623294 -33.021349) (xy 283.540123 -33.037375) (xy 283.455805 -33.045422) (xy 283.413454 -33.045908)
			(xy 283.374614 -33.045521) (xy 283.297228 -33.038783) (xy 283.220725 -33.025319) (xy 283.145688 -33.005231)
			(xy 283.07269 -32.978672) (xy 283.002287 -32.945846) (xy 282.968446 -32.926782) (xy 282.932012 -32.905184)
			(xy 282.863012 -32.856052) (xy 282.798996 -32.800584) (xy 282.740542 -32.739282) (xy 282.68818 -32.672701)
			(xy 282.642385 -32.601444) (xy 282.60357 -32.526156) (xy 282.572088 -32.447519) (xy 282.548223 -32.366246)
			(xy 282.532193 -32.283073) (xy 282.524141 -32.198752) (xy 275.598955 -32.198752) (xy 275.669367 -32.215834)
			(xy 275.749429 -32.243543) (xy 275.826494 -32.278738) (xy 275.899864 -32.321098) (xy 275.968876 -32.370241)
			(xy 276.032904 -32.425722) (xy 276.091369 -32.487037) (xy 276.14374 -32.553633) (xy 276.189543 -32.624905)
			(xy 276.228365 -32.700208) (xy 276.259853 -32.77886) (xy 276.283721 -32.86015) (xy 276.299755 -32.94334)
			(xy 276.307808 -33.027677) (xy 276.308312 -33.070038) (xy 276.307808 -33.112399) (xy 276.299755 -33.196736)
			(xy 276.283721 -33.279926) (xy 276.259853 -33.361216) (xy 276.228365 -33.439868) (xy 276.189543 -33.515171)
			(xy 276.14374 -33.586443) (xy 276.091369 -33.653039) (xy 276.032904 -33.714354) (xy 275.968876 -33.769835)
			(xy 275.899864 -33.818978) (xy 275.826494 -33.861338) (xy 275.749429 -33.896533) (xy 275.669367 -33.924242)
			(xy 275.587034 -33.944216) (xy 275.503175 -33.956273) (xy 275.41855 -33.960305) (xy 275.333925 -33.956273)
			(xy 275.250066 -33.944216) (xy 275.167733 -33.924242) (xy 275.087671 -33.896533) (xy 275.010606 -33.861338)
			(xy 274.937236 -33.818978) (xy 274.868224 -33.769835) (xy 274.804196 -33.714354) (xy 274.745731 -33.653039)
			(xy 274.69336 -33.586443) (xy 274.647557 -33.515171) (xy 274.608735 -33.439868) (xy 274.577247 -33.361216)
			(xy 274.553379 -33.279926) (xy 274.537345 -33.196736) (xy 274.529292 -33.112399) (xy 202.688184 -33.112399)
			(xy 202.675257 -33.180799) (xy 202.648221 -33.28182) (xy 202.61372 -33.380542) (xy 202.571946 -33.476413)
			(xy 202.523133 -33.568899) (xy 202.467553 -33.657483) (xy 202.405516 -33.741671) (xy 202.337368 -33.820994)
			(xy 202.26349 -33.895009) (xy 202.184293 -33.963304) (xy 202.100219 -34.025496) (xy 202.056238 -34.05378)
			(xy 202.045062 -34.060892) (xy 202.032616 -34.083244) (xy 202.032616 -34.19602) (xy 202.045062 -34.218372)
			(xy 202.056238 -34.225484) (xy 202.100247 -34.253723) (xy 202.184319 -34.315918) (xy 202.263515 -34.384214)
			(xy 202.337391 -34.458231) (xy 202.405537 -34.537556) (xy 202.467572 -34.621746) (xy 202.52315 -34.710331)
			(xy 202.571961 -34.802818) (xy 202.613732 -34.89869) (xy 202.648231 -34.997412) (xy 202.675265 -35.098434)
			(xy 202.694682 -35.201192) (xy 202.706376 -35.305113) (xy 202.710281 -35.409617) (xy 202.706374 -35.514121)
			(xy 202.694677 -35.618041) (xy 202.675257 -35.720799) (xy 202.648221 -35.82182) (xy 202.61372 -35.920542)
			(xy 202.571946 -36.016413) (xy 202.523133 -36.108899) (xy 202.467553 -36.197483) (xy 202.405516 -36.281671)
			(xy 202.337368 -36.360994) (xy 202.26349 -36.435009) (xy 202.184293 -36.503304) (xy 202.100219 -36.565496)
			(xy 202.056238 -36.59378) (xy 202.045062 -36.600892) (xy 202.032616 -36.623244) (xy 202.032616 -36.73602)
			(xy 202.045062 -36.758372) (xy 202.056238 -36.765484) (xy 202.10193 -36.794827) (xy 202.189051 -36.859666)
			(xy 202.270885 -36.931062) (xy 202.346939 -37.008586) (xy 202.416756 -37.091772) (xy 202.479915 -37.180118)
			(xy 202.536037 -37.273094) (xy 202.584783 -37.37014) (xy 202.625861 -37.470673) (xy 202.659024 -37.574087)
			(xy 202.684071 -37.67976) (xy 202.700853 -37.787057) (xy 202.709268 -37.895331) (xy 202.70978 -37.949632)
			(xy 202.709293 -38.001987) (xy 202.706832 -38.03481) (xy 245.302523 -38.03481) (xy 245.302523 -37.864454)
			(xy 245.310508 -37.694286) (xy 245.32646 -37.524679) (xy 245.350345 -37.356007) (xy 245.382109 -37.188639)
			(xy 245.421684 -37.022944) (xy 245.468981 -36.859286) (xy 245.523898 -36.698025) (xy 245.586313 -36.539515)
			(xy 245.656089 -36.384105) (xy 245.733072 -36.232137) (xy 245.817094 -36.083943) (xy 245.90797 -35.939851)
			(xy 246.0055 -35.800177) (xy 246.10947 -35.665228) (xy 246.219651 -35.5353) (xy 246.3358 -35.41068)
			(xy 246.457664 -35.291641) (xy 246.584972 -35.178445) (xy 246.717447 -35.07134) (xy 246.854797 -34.970563)
			(xy 246.996719 -34.876334) (xy 247.142901 -34.788861) (xy 247.293024 -34.708336) (xy 247.446755 -34.634936)
			(xy 247.603758 -34.568822) (xy 247.763688 -34.51014) (xy 247.926192 -34.459019) (xy 248.090913 -34.415571)
			(xy 248.257491 -34.379892) (xy 248.425557 -34.35206) (xy 248.594743 -34.332136) (xy 248.764677 -34.320164)
			(xy 248.934986 -34.316171) (xy 249.105295 -34.320164) (xy 249.275229 -34.332136) (xy 249.444415 -34.35206)
			(xy 249.612481 -34.379892) (xy 249.779059 -34.415571) (xy 249.94378 -34.459019) (xy 250.106284 -34.51014)
			(xy 250.266214 -34.568822) (xy 250.423217 -34.634936) (xy 250.576948 -34.708336) (xy 250.727071 -34.788861)
			(xy 250.873253 -34.876334) (xy 251.015175 -34.970563) (xy 251.080047 -35.018161) (xy 293.293542 -35.018161)
			(xy 293.293542 -34.933439) (xy 293.301595 -34.849102) (xy 293.317629 -34.765912) (xy 293.341497 -34.684622)
			(xy 293.372985 -34.60597) (xy 293.411807 -34.530667) (xy 293.45761 -34.459395) (xy 293.509981 -34.392799)
			(xy 293.568446 -34.331484) (xy 293.632474 -34.276003) (xy 293.701486 -34.22686) (xy 293.774856 -34.1845)
			(xy 293.851921 -34.149305) (xy 293.931983 -34.121596) (xy 294.014316 -34.101622) (xy 294.098175 -34.089565)
			(xy 294.1828 -34.085534) (xy 294.267425 -34.089565) (xy 294.351284 -34.101622) (xy 294.433617 -34.121596)
			(xy 294.513679 -34.149305) (xy 294.590744 -34.1845) (xy 294.664114 -34.22686) (xy 294.733126 -34.276003)
			(xy 294.797154 -34.331484) (xy 294.855619 -34.392799) (xy 294.90799 -34.459395) (xy 294.953793 -34.530667)
			(xy 294.992615 -34.60597) (xy 295.024103 -34.684622) (xy 295.047971 -34.765912) (xy 295.064005 -34.849102)
			(xy 295.072058 -34.933439) (xy 295.072562 -34.9758) (xy 295.072058 -35.018161) (xy 295.064005 -35.102498)
			(xy 295.047971 -35.185688) (xy 295.024103 -35.266978) (xy 294.992615 -35.34563) (xy 294.953793 -35.420933)
			(xy 294.90799 -35.492205) (xy 294.855619 -35.558801) (xy 294.797154 -35.620116) (xy 294.733126 -35.675597)
			(xy 294.664114 -35.72474) (xy 294.590744 -35.7671) (xy 294.513679 -35.802295) (xy 294.433617 -35.830004)
			(xy 294.351284 -35.849978) (xy 294.267425 -35.862035) (xy 294.1828 -35.866067) (xy 294.098175 -35.862035)
			(xy 294.014316 -35.849978) (xy 293.931983 -35.830004) (xy 293.851921 -35.802295) (xy 293.774856 -35.7671)
			(xy 293.701486 -35.72474) (xy 293.632474 -35.675597) (xy 293.568446 -35.620116) (xy 293.509981 -35.558801)
			(xy 293.45761 -35.492205) (xy 293.411807 -35.420933) (xy 293.372985 -35.34563) (xy 293.341497 -35.266978)
			(xy 293.317629 -35.185688) (xy 293.301595 -35.102498) (xy 293.293542 -35.018161) (xy 251.080047 -35.018161)
			(xy 251.152525 -35.07134) (xy 251.285 -35.178445) (xy 251.412308 -35.291641) (xy 251.534172 -35.41068)
			(xy 251.650321 -35.5353) (xy 251.760502 -35.665228) (xy 251.864472 -35.800177) (xy 251.962002 -35.939851)
			(xy 252.052878 -36.083943) (xy 252.1369 -36.232137) (xy 252.213883 -36.384105) (xy 252.283659 -36.539515)
			(xy 252.346074 -36.698025) (xy 252.400991 -36.859286) (xy 252.448288 -37.022944) (xy 252.487863 -37.188639)
			(xy 252.504967 -37.278761) (xy 259.293102 -37.278761) (xy 259.293102 -37.194039) (xy 259.301155 -37.109702)
			(xy 259.317189 -37.026512) (xy 259.341057 -36.945222) (xy 259.372545 -36.86657) (xy 259.411367 -36.791267)
			(xy 259.45717 -36.719995) (xy 259.509541 -36.653399) (xy 259.568006 -36.592084) (xy 259.632034 -36.536603)
			(xy 259.701046 -36.48746) (xy 259.774416 -36.4451) (xy 259.851481 -36.409905) (xy 259.931543 -36.382196)
			(xy 260.013876 -36.362222) (xy 260.097735 -36.350165) (xy 260.18236 -36.346134) (xy 260.266985 -36.350165)
			(xy 260.350844 -36.362222) (xy 260.433177 -36.382196) (xy 260.513239 -36.409905) (xy 260.590304 -36.4451)
			(xy 260.663674 -36.48746) (xy 260.732686 -36.536603) (xy 260.796714 -36.592084) (xy 260.855179 -36.653399)
			(xy 260.90755 -36.719995) (xy 260.953353 -36.791267) (xy 260.992175 -36.86657) (xy 261.023663 -36.945222)
			(xy 261.047531 -37.026512) (xy 261.063565 -37.109702) (xy 261.071618 -37.194039) (xy 261.072122 -37.2364)
			(xy 261.071618 -37.278761) (xy 261.063565 -37.363098) (xy 261.047531 -37.446288) (xy 261.023663 -37.527578)
			(xy 260.992175 -37.60623) (xy 260.953353 -37.681533) (xy 260.90755 -37.752805) (xy 260.855179 -37.819401)
			(xy 260.796714 -37.880716) (xy 260.732686 -37.936197) (xy 260.663674 -37.98534) (xy 260.590304 -38.0277)
			(xy 260.513239 -38.062895) (xy 260.433177 -38.090604) (xy 260.350844 -38.110578) (xy 260.266985 -38.122635)
			(xy 260.18236 -38.126667) (xy 260.097735 -38.122635) (xy 260.013876 -38.110578) (xy 259.931543 -38.090604)
			(xy 259.851481 -38.062895) (xy 259.774416 -38.0277) (xy 259.701046 -37.98534) (xy 259.632034 -37.936197)
			(xy 259.568006 -37.880716) (xy 259.509541 -37.819401) (xy 259.45717 -37.752805) (xy 259.411367 -37.681533)
			(xy 259.372545 -37.60623) (xy 259.341057 -37.527578) (xy 259.317189 -37.446288) (xy 259.301155 -37.363098)
			(xy 259.293102 -37.278761) (xy 252.504967 -37.278761) (xy 252.519627 -37.356007) (xy 252.543512 -37.524679)
			(xy 252.559464 -37.694286) (xy 252.567449 -37.864454) (xy 252.567948 -37.949632) (xy 252.567449 -38.03481)
			(xy 252.559464 -38.204978) (xy 252.543512 -38.374585) (xy 252.519627 -38.543257) (xy 252.487863 -38.710625)
			(xy 252.448288 -38.87632) (xy 252.400991 -39.039978) (xy 252.350882 -39.18712) (xy 257.640836 -39.18712)
			(xy 257.641465 -39.140264) (xy 257.651373 -39.047077) (xy 257.671018 -38.955447) (xy 257.700183 -38.866389)
			(xy 257.718814 -38.823392) (xy 257.722591 -38.813952) (xy 257.723116 -38.793644) (xy 257.71983 -38.784022)
			(xy 257.705286 -38.745426) (xy 257.682591 -38.666124) (xy 257.667328 -38.585063) (xy 257.659626 -38.502938)
			(xy 257.659124 -38.461696) (xy 257.659628 -38.419335) (xy 257.667681 -38.334998) (xy 257.683715 -38.251808)
			(xy 257.707583 -38.170518) (xy 257.739071 -38.091866) (xy 257.777893 -38.016563) (xy 257.823696 -37.945291)
			(xy 257.876067 -37.878695) (xy 257.934532 -37.81738) (xy 257.99856 -37.761899) (xy 258.067572 -37.712756)
			(xy 258.140942 -37.670396) (xy 258.218007 -37.635201) (xy 258.298069 -37.607492) (xy 258.380402 -37.587518)
			(xy 258.464261 -37.575461) (xy 258.548886 -37.57143) (xy 258.633511 -37.575461) (xy 258.71737 -37.587518)
			(xy 258.799703 -37.607492) (xy 258.879765 -37.635201) (xy 258.95683 -37.670396) (xy 259.0302 -37.712756)
			(xy 259.099212 -37.761899) (xy 259.16324 -37.81738) (xy 259.221705 -37.878695) (xy 259.274076 -37.945291)
			(xy 259.319879 -38.016563) (xy 259.358701 -38.091866) (xy 259.390189 -38.170518) (xy 259.414057 -38.251808)
			(xy 259.430091 -38.334998) (xy 259.438144 -38.419335) (xy 259.438648 -38.461696) (xy 259.438331 -38.49433)
			(xy 259.433502 -38.559421) (xy 259.428996 -38.591744) (xy 259.427218 -38.603682) (xy 259.43433 -38.62578)
			(xy 259.506212 -38.700964) (xy 259.528056 -38.709092) (xy 259.53974 -38.707822) (xy 259.562407 -38.705593)
			(xy 259.607896 -38.703178) (xy 259.630672 -38.702996) (xy 259.671782 -38.703479) (xy 259.753652 -38.711065)
			(xy 259.834473 -38.726173) (xy 259.913554 -38.748676) (xy 259.990221 -38.778381) (xy 260.06382 -38.815034)
			(xy 260.133721 -38.858323) (xy 260.19933 -38.907879) (xy 260.260085 -38.963278) (xy 260.315468 -39.024047)
			(xy 260.365007 -39.089669) (xy 260.408278 -39.159581) (xy 260.444912 -39.233189) (xy 260.474597 -39.309864)
			(xy 260.49708 -39.388951) (xy 260.512167 -39.469776) (xy 260.519731 -39.551648) (xy 260.52018 -39.592758)
			(xy 260.519659 -39.635175) (xy 260.511589 -39.719623) (xy 260.495517 -39.80292) (xy 260.47159 -39.884309)
			(xy 260.440025 -39.963051) (xy 260.401108 -40.038431) (xy 260.355193 -40.109764) (xy 260.302698 -40.176404)
			(xy 260.244097 -40.237744) (xy 260.212332 -40.265858) (xy 260.203696 -40.273224) (xy 260.194806 -40.293036)
			(xy 260.194806 -40.392604) (xy 260.203696 -40.412416) (xy 260.212332 -40.419782) (xy 260.24409 -40.447905)
			(xy 260.302694 -40.509243) (xy 260.355193 -40.575881) (xy 260.401112 -40.647213) (xy 260.440033 -40.722591)
			(xy 260.471603 -40.801332) (xy 260.495535 -40.88272) (xy 260.502615 -40.9194) (xy 287.730188 -40.9194)
			(xy 287.734218 -40.834799) (xy 287.746271 -40.750964) (xy 287.766239 -40.668655) (xy 287.793941 -40.588616)
			(xy 287.829125 -40.511573) (xy 287.871474 -40.438223) (xy 287.920603 -40.369231) (xy 287.976068 -40.305221)
			(xy 288.037366 -40.246773) (xy 288.103942 -40.194417) (xy 288.175194 -40.148627) (xy 288.250475 -40.109816)
			(xy 288.329105 -40.078337) (xy 288.410372 -40.054476) (xy 288.493538 -40.038447) (xy 288.577852 -40.030396)
			(xy 288.6202 -40.029892) (xy 288.658991 -40.030305) (xy 288.736279 -40.037037) (xy 288.812687 -40.050475)
			(xy 288.887634 -40.070517) (xy 288.960551 -40.097012) (xy 289.030883 -40.129757) (xy 289.0647 -40.148764)
			(xy 289.072574 -40.152923) (xy 289.0901 -40.156017) (xy 289.107626 -40.152923) (xy 289.1155 -40.148764)
			(xy 289.149326 -40.129773) (xy 289.219657 -40.097028) (xy 289.292572 -40.070532) (xy 289.367517 -40.050487)
			(xy 289.443923 -40.037043) (xy 289.52121 -40.030305) (xy 289.56 -40.029892) (xy 289.602348 -40.030396)
			(xy 289.686662 -40.038447) (xy 289.769828 -40.054476) (xy 289.851095 -40.078337) (xy 289.929725 -40.109816)
			(xy 290.005006 -40.148627) (xy 290.076258 -40.194417) (xy 290.142834 -40.246773) (xy 290.204132 -40.305221)
			(xy 290.259597 -40.369231) (xy 290.308726 -40.438223) (xy 290.351075 -40.511573) (xy 290.386259 -40.588616)
			(xy 290.413961 -40.668655) (xy 290.433929 -40.750964) (xy 290.445982 -40.834799) (xy 290.450013 -40.9194)
			(xy 290.445982 -41.004001) (xy 290.433929 -41.087836) (xy 290.413961 -41.170145) (xy 290.386259 -41.250184)
			(xy 290.351075 -41.327227) (xy 290.308726 -41.400577) (xy 290.259597 -41.469569) (xy 290.204132 -41.533579)
			(xy 290.142834 -41.592027) (xy 290.076258 -41.644383) (xy 290.005006 -41.690173) (xy 289.929725 -41.728984)
			(xy 289.851095 -41.760463) (xy 289.769828 -41.784324) (xy 289.686662 -41.800353) (xy 289.602348 -41.808404)
			(xy 289.56 -41.808908) (xy 289.521209 -41.808495) (xy 289.443921 -41.801763) (xy 289.367513 -41.788325)
			(xy 289.292566 -41.768283) (xy 289.219649 -41.741788) (xy 289.149317 -41.709043) (xy 289.1155 -41.690036)
			(xy 289.107626 -41.685877) (xy 289.0901 -41.682783) (xy 289.072574 -41.685877) (xy 289.0647 -41.690036)
			(xy 289.030874 -41.709027) (xy 288.960543 -41.741772) (xy 288.887628 -41.768268) (xy 288.812683 -41.788313)
			(xy 288.736277 -41.801757) (xy 288.65899 -41.808495) (xy 288.6202 -41.808908) (xy 288.577852 -41.808404)
			(xy 288.493538 -41.800353) (xy 288.410372 -41.784324) (xy 288.329105 -41.760463) (xy 288.250475 -41.728984)
			(xy 288.175194 -41.690173) (xy 288.103942 -41.644383) (xy 288.037366 -41.592027) (xy 287.976068 -41.533579)
			(xy 287.920603 -41.469569) (xy 287.871474 -41.400577) (xy 287.829125 -41.327227) (xy 287.793941 -41.250184)
			(xy 287.766239 -41.170145) (xy 287.746271 -41.087836) (xy 287.734218 -41.004001) (xy 287.730188 -40.9194)
			(xy 260.502615 -40.9194) (xy 260.511612 -40.966017) (xy 260.519688 -41.050465) (xy 260.52018 -41.092882)
			(xy 260.519705 -41.135309) (xy 260.511626 -41.219777) (xy 260.49554 -41.303091) (xy 260.471593 -41.384495)
			(xy 260.440002 -41.463249) (xy 260.401055 -41.538636) (xy 260.355107 -41.609972) (xy 260.302573 -41.676608)
			(xy 260.243933 -41.737938) (xy 260.179718 -41.793405) (xy 260.110513 -41.842505) (xy 260.036947 -41.884791)
			(xy 259.959689 -41.919879) (xy 259.919724 -41.93413) (xy 259.910326 -41.937432) (xy 259.895594 -41.950132)
			(xy 259.854446 -42.03065) (xy 259.852668 -42.049954) (xy 259.855462 -42.059606) (xy 259.867486 -42.101336)
			(xy 259.874135 -42.134987) (xy 291.917116 -42.134987) (xy 291.917116 -42.050265) (xy 291.925169 -41.965928)
			(xy 291.941203 -41.882738) (xy 291.965071 -41.801448) (xy 291.996559 -41.722796) (xy 292.035381 -41.647493)
			(xy 292.081184 -41.576221) (xy 292.133555 -41.509625) (xy 292.19202 -41.44831) (xy 292.256048 -41.392829)
			(xy 292.32506 -41.343686) (xy 292.39843 -41.301326) (xy 292.475495 -41.266131) (xy 292.555557 -41.238422)
			(xy 292.63789 -41.218448) (xy 292.721749 -41.206391) (xy 292.806374 -41.20236) (xy 292.890999 -41.206391)
			(xy 292.974858 -41.218448) (xy 293.057191 -41.238422) (xy 293.137253 -41.266131) (xy 293.214318 -41.301326)
			(xy 293.287688 -41.343686) (xy 293.3567 -41.392829) (xy 293.420728 -41.44831) (xy 293.479193 -41.509625)
			(xy 293.531564 -41.576221) (xy 293.577367 -41.647493) (xy 293.616189 -41.722796) (xy 293.647677 -41.801448)
			(xy 293.671545 -41.882738) (xy 293.687579 -41.965928) (xy 293.695632 -42.050265) (xy 293.696136 -42.092626)
			(xy 293.695632 -42.134987) (xy 293.694026 -42.151808) (xy 298.200572 -42.151808) (xy 298.201202 -42.105406)
			(xy 298.210891 -42.013109) (xy 298.230144 -41.922323) (xy 298.258751 -41.834038) (xy 298.277026 -41.791382)
			(xy 298.280825 -41.781438) (xy 298.280828 -41.760177) (xy 298.277026 -41.750234) (xy 298.258766 -41.707572)
			(xy 298.230172 -41.619284) (xy 298.210915 -41.528502) (xy 298.201201 -41.436209) (xy 298.200572 -41.389808)
			(xy 298.20106 -41.348698) (xy 298.208647 -41.266829) (xy 298.223757 -41.18601) (xy 298.24626 -41.106929)
			(xy 298.275966 -41.030263) (xy 298.312619 -40.956666) (xy 298.355909 -40.886765) (xy 298.405464 -40.821157)
			(xy 298.460862 -40.760402) (xy 298.521631 -40.705019) (xy 298.587251 -40.655481) (xy 298.657163 -40.612209)
			(xy 298.73077 -40.575574) (xy 298.807444 -40.545888) (xy 298.88653 -40.523405) (xy 298.967353 -40.508316)
			(xy 299.049224 -40.50075) (xy 299.090334 -40.5003) (xy 299.136729 -40.500905) (xy 299.229017 -40.510544)
			(xy 299.319801 -40.529733) (xy 299.408095 -40.558265) (xy 299.45076 -40.5765) (xy 299.460702 -40.580306)
			(xy 299.481966 -40.580306) (xy 299.491908 -40.5765) (xy 299.534566 -40.558244) (xy 299.62286 -40.529703)
			(xy 299.713646 -40.510513) (xy 299.805938 -40.500883) (xy 299.852334 -40.5003) (xy 299.890619 -40.500677)
			(xy 299.966907 -40.507219) (xy 300.04235 -40.520304) (xy 300.116386 -40.539833) (xy 300.152562 -40.55237)
			(xy 300.160999 -40.555021) (xy 300.178669 -40.555021) (xy 300.187106 -40.55237) (xy 300.223291 -40.539863)
			(xy 300.297328 -40.520351) (xy 300.372767 -40.507266) (xy 300.449051 -40.500704) (xy 300.487334 -40.5003)
			(xy 300.525619 -40.500677) (xy 300.601907 -40.507219) (xy 300.67735 -40.520304) (xy 300.751386 -40.539833)
			(xy 300.787562 -40.55237) (xy 300.795999 -40.555021) (xy 300.813669 -40.555021) (xy 300.822106 -40.55237)
			(xy 300.858291 -40.539863) (xy 300.932328 -40.520351) (xy 301.007767 -40.507266) (xy 301.084051 -40.500704)
			(xy 301.122334 -40.5003) (xy 301.164317 -40.500787) (xy 301.247912 -40.508666) (xy 301.330395 -40.524379)
			(xy 301.411032 -40.547787) (xy 301.450248 -40.562784) (xy 301.460692 -40.566294) (xy 301.482669 -40.565127)
			(xy 301.492666 -40.560498) (xy 301.531214 -40.540705) (xy 301.611385 -40.507804) (xy 301.694374 -40.482849)
			(xy 301.779394 -40.466076) (xy 301.865642 -40.457644) (xy 301.908972 -40.45712) (xy 301.950076 -40.457579)
			(xy 302.031932 -40.465162) (xy 302.11274 -40.480265) (xy 302.191809 -40.502761) (xy 302.268465 -40.532456)
			(xy 302.342055 -40.569098) (xy 302.411949 -40.612374) (xy 302.477552 -40.661914) (xy 302.538303 -40.717297)
			(xy 302.593686 -40.778048) (xy 302.643226 -40.843651) (xy 302.686502 -40.913545) (xy 302.723144 -40.987135)
			(xy 302.752839 -41.063791) (xy 302.775335 -41.14286) (xy 302.790438 -41.223668) (xy 302.798021 -41.305524)
			(xy 302.79848 -41.346628) (xy 302.798042 -41.387131) (xy 302.7907 -41.467804) (xy 302.776059 -41.547476)
			(xy 302.754242 -41.625489) (xy 302.725429 -41.701197) (xy 302.708056 -41.737788) (xy 302.703447 -41.748346)
			(xy 302.703335 -41.771364) (xy 302.707802 -41.781984) (xy 302.724373 -41.817832) (xy 302.751818 -41.891892)
			(xy 302.772586 -41.968094) (xy 302.786514 -42.045837) (xy 302.793492 -42.124509) (xy 302.793908 -42.164)
			(xy 302.793433 -42.205102) (xy 302.785848 -42.286957) (xy 302.770743 -42.367762) (xy 302.748247 -42.446829)
			(xy 302.718551 -42.523483) (xy 302.681909 -42.59707) (xy 302.638634 -42.666962) (xy 302.589094 -42.732563)
			(xy 302.533713 -42.793313) (xy 302.472963 -42.848694) (xy 302.407362 -42.898234) (xy 302.33747 -42.941509)
			(xy 302.263883 -42.978151) (xy 302.187229 -43.007847) (xy 302.108162 -43.030343) (xy 302.027357 -43.045448)
			(xy 301.945502 -43.053033) (xy 301.9044 -43.053508) (xy 301.864854 -43.053073) (xy 301.786073 -43.046064)
			(xy 301.708224 -43.032091) (xy 301.631923 -43.011266) (xy 301.55777 -42.983752) (xy 301.521876 -42.967148)
			(xy 301.511763 -42.962977) (xy 301.489915 -42.962698) (xy 301.479712 -42.96664) (xy 301.437359 -42.984532)
			(xy 301.349773 -43.012514) (xy 301.25977 -43.031323) (xy 301.168308 -43.040759) (xy 301.122334 -43.041316)
			(xy 301.084049 -43.040947) (xy 301.00776 -43.034403) (xy 300.932318 -43.021316) (xy 300.858282 -43.001784)
			(xy 300.822106 -42.989246) (xy 300.813669 -42.986595) (xy 300.795999 -42.986595) (xy 300.787562 -42.989246)
			(xy 300.751381 -43.001762) (xy 300.677342 -43.021272) (xy 300.601902 -43.034355) (xy 300.525617 -43.040913)
			(xy 300.487334 -43.041316) (xy 300.449049 -43.040947) (xy 300.37276 -43.034403) (xy 300.297318 -43.021316)
			(xy 300.223282 -43.001784) (xy 300.187106 -42.989246) (xy 300.178669 -42.986595) (xy 300.160999 -42.986595)
			(xy 300.152562 -42.989246) (xy 300.116381 -43.001762) (xy 300.042342 -43.021272) (xy 299.966902 -43.034355)
			(xy 299.890617 -43.040913) (xy 299.852334 -43.041316) (xy 299.805939 -43.04072) (xy 299.713651 -43.031079)
			(xy 299.622867 -43.011887) (xy 299.534573 -42.983352) (xy 299.491908 -42.965116) (xy 299.481966 -42.96131)
			(xy 299.460702 -42.96131) (xy 299.45076 -42.965116) (xy 299.408093 -42.98335) (xy 299.319803 -43.011897)
			(xy 299.229019 -43.031093) (xy 299.13673 -43.040729) (xy 299.090334 -43.041316) (xy 299.049226 -43.040855)
			(xy 298.967362 -43.033273) (xy 298.886546 -43.018171) (xy 298.807467 -42.995678) (xy 298.730802 -42.965985)
			(xy 298.657202 -42.929345) (xy 298.587297 -42.886072) (xy 298.521682 -42.836534) (xy 298.460917 -42.781154)
			(xy 298.40552 -42.720404) (xy 298.355965 -42.654803) (xy 298.312673 -42.584909) (xy 298.276013 -42.51132)
			(xy 298.246299 -42.434662) (xy 298.223784 -42.35559) (xy 298.20866 -42.274778) (xy 298.201056 -42.192915)
			(xy 298.200572 -42.151808) (xy 293.694026 -42.151808) (xy 293.687579 -42.219324) (xy 293.671545 -42.302514)
			(xy 293.647677 -42.383804) (xy 293.616189 -42.462456) (xy 293.577367 -42.537759) (xy 293.531564 -42.609031)
			(xy 293.479193 -42.675627) (xy 293.420728 -42.736942) (xy 293.3567 -42.792423) (xy 293.287688 -42.841566)
			(xy 293.214318 -42.883926) (xy 293.137253 -42.919121) (xy 293.057191 -42.94683) (xy 292.974858 -42.966804)
			(xy 292.890999 -42.978861) (xy 292.806374 -42.982893) (xy 292.721749 -42.978861) (xy 292.63789 -42.966804)
			(xy 292.555557 -42.94683) (xy 292.475495 -42.919121) (xy 292.39843 -42.883926) (xy 292.32506 -42.841566)
			(xy 292.256048 -42.792423) (xy 292.19202 -42.736942) (xy 292.133555 -42.675627) (xy 292.081184 -42.609031)
			(xy 292.035381 -42.537759) (xy 291.996559 -42.462456) (xy 291.965071 -42.383804) (xy 291.941203 -42.302514)
			(xy 291.925169 -42.219324) (xy 291.917116 -42.134987) (xy 259.874135 -42.134987) (xy 259.88432 -42.186539)
			(xy 259.892782 -42.272975) (xy 259.893308 -42.3164) (xy 259.892842 -42.358233) (xy 259.885017 -42.441532)
			(xy 259.869417 -42.523731) (xy 259.858256 -42.56405) (xy 259.85597 -42.573278) (xy 259.857676 -42.592201)
			(xy 259.861558 -42.60088) (xy 259.87502 -42.627804) (xy 259.879656 -42.63618) (xy 259.893889 -42.648965)
			(xy 259.902706 -42.652696) (xy 259.941221 -42.667831) (xy 260.015569 -42.704177) (xy 260.086221 -42.747271)
			(xy 260.152565 -42.79674) (xy 260.214028 -42.852157) (xy 260.270078 -42.913043) (xy 260.320231 -42.978871)
			(xy 260.364054 -43.049073) (xy 260.401167 -43.123041) (xy 260.431251 -43.200137) (xy 260.454044 -43.279693)
			(xy 260.469349 -43.361022) (xy 260.477035 -43.443421) (xy 260.477508 -43.4848) (xy 260.477004 -43.527148)
			(xy 260.468953 -43.611462) (xy 260.452924 -43.694628) (xy 260.432497 -43.7642) (xy 287.730188 -43.7642)
			(xy 287.734218 -43.679599) (xy 287.746271 -43.595764) (xy 287.766239 -43.513455) (xy 287.793941 -43.433416)
			(xy 287.829125 -43.356373) (xy 287.871474 -43.283023) (xy 287.920603 -43.214031) (xy 287.976068 -43.150021)
			(xy 288.037366 -43.091573) (xy 288.103942 -43.039217) (xy 288.175194 -42.993427) (xy 288.250475 -42.954616)
			(xy 288.329105 -42.923137) (xy 288.410372 -42.899276) (xy 288.493538 -42.883247) (xy 288.577852 -42.875196)
			(xy 288.6202 -42.874692) (xy 288.658991 -42.875105) (xy 288.736279 -42.881837) (xy 288.812687 -42.895275)
			(xy 288.887634 -42.915317) (xy 288.960551 -42.941812) (xy 289.030883 -42.974557) (xy 289.0647 -42.993564)
			(xy 289.072574 -42.997723) (xy 289.0901 -43.000817) (xy 289.107626 -42.997723) (xy 289.1155 -42.993564)
			(xy 289.149326 -42.974573) (xy 289.219657 -42.941828) (xy 289.292572 -42.915332) (xy 289.367517 -42.895287)
			(xy 289.443923 -42.881843) (xy 289.52121 -42.875105) (xy 289.56 -42.874692) (xy 289.602348 -42.875196)
			(xy 289.686662 -42.883247) (xy 289.769828 -42.899276) (xy 289.851095 -42.923137) (xy 289.929725 -42.954616)
			(xy 290.005006 -42.993427) (xy 290.076258 -43.039217) (xy 290.142834 -43.091573) (xy 290.204132 -43.150021)
			(xy 290.259597 -43.214031) (xy 290.308726 -43.283023) (xy 290.351075 -43.356373) (xy 290.386259 -43.433416)
			(xy 290.413961 -43.513455) (xy 290.433929 -43.595764) (xy 290.445982 -43.679599) (xy 290.450013 -43.7642)
			(xy 290.445982 -43.848801) (xy 290.433929 -43.932636) (xy 290.413961 -44.014945) (xy 290.386259 -44.094984)
			(xy 290.351075 -44.172027) (xy 290.308726 -44.245377) (xy 290.259597 -44.314369) (xy 290.204132 -44.378379)
			(xy 290.142834 -44.436827) (xy 290.076258 -44.489183) (xy 290.005006 -44.534973) (xy 289.929725 -44.573784)
			(xy 289.851095 -44.605263) (xy 289.769828 -44.629124) (xy 289.686662 -44.645153) (xy 289.602348 -44.653204)
			(xy 289.56 -44.653708) (xy 289.521209 -44.653295) (xy 289.443921 -44.646563) (xy 289.367513 -44.633125)
			(xy 289.292566 -44.613083) (xy 289.219649 -44.586588) (xy 289.149317 -44.553843) (xy 289.1155 -44.534836)
			(xy 289.107626 -44.530677) (xy 289.0901 -44.527583) (xy 289.072574 -44.530677) (xy 289.0647 -44.534836)
			(xy 289.030874 -44.553827) (xy 288.960543 -44.586572) (xy 288.887628 -44.613068) (xy 288.812683 -44.633113)
			(xy 288.736277 -44.646557) (xy 288.65899 -44.653295) (xy 288.6202 -44.653708) (xy 288.577852 -44.653204)
			(xy 288.493538 -44.645153) (xy 288.410372 -44.629124) (xy 288.329105 -44.605263) (xy 288.250475 -44.573784)
			(xy 288.175194 -44.534973) (xy 288.103942 -44.489183) (xy 288.037366 -44.436827) (xy 287.976068 -44.378379)
			(xy 287.920603 -44.314369) (xy 287.871474 -44.245377) (xy 287.829125 -44.172027) (xy 287.793941 -44.094984)
			(xy 287.766239 -44.014945) (xy 287.746271 -43.932636) (xy 287.734218 -43.848801) (xy 287.730188 -43.7642)
			(xy 260.432497 -43.7642) (xy 260.429063 -43.775895) (xy 260.397584 -43.854525) (xy 260.358773 -43.929806)
			(xy 260.312983 -44.001058) (xy 260.260627 -44.067634) (xy 260.202179 -44.128932) (xy 260.138169 -44.184397)
			(xy 260.069177 -44.233526) (xy 259.995827 -44.275875) (xy 259.918784 -44.311059) (xy 259.838745 -44.338761)
			(xy 259.756436 -44.358729) (xy 259.672601 -44.370782) (xy 259.588 -44.374813) (xy 259.503399 -44.370782)
			(xy 259.419564 -44.358729) (xy 259.337255 -44.338761) (xy 259.257216 -44.311059) (xy 259.180173 -44.275875)
			(xy 259.106823 -44.233526) (xy 259.037831 -44.184397) (xy 258.973821 -44.128932) (xy 258.915373 -44.067634)
			(xy 258.863017 -44.001058) (xy 258.817227 -43.929806) (xy 258.778416 -43.854525) (xy 258.746937 -43.775895)
			(xy 258.723076 -43.694628) (xy 258.707047 -43.611462) (xy 258.698996 -43.527148) (xy 258.698492 -43.4848)
			(xy 258.698958 -43.442967) (xy 258.706783 -43.359668) (xy 258.722383 -43.277469) (xy 258.733544 -43.23715)
			(xy 258.73583 -43.227922) (xy 258.734124 -43.208999) (xy 258.730242 -43.20032) (xy 258.71678 -43.173396)
			(xy 258.712144 -43.16502) (xy 258.697911 -43.152235) (xy 258.689094 -43.148504) (xy 258.650579 -43.133369)
			(xy 258.576231 -43.097023) (xy 258.505579 -43.053929) (xy 258.439235 -43.00446) (xy 258.377772 -42.949043)
			(xy 258.321722 -42.888157) (xy 258.271569 -42.822329) (xy 258.227746 -42.752127) (xy 258.190633 -42.678159)
			(xy 258.160549 -42.601063) (xy 258.137756 -42.521507) (xy 258.122451 -42.440178) (xy 258.114765 -42.357779)
			(xy 258.114292 -42.3164) (xy 258.114767 -42.275174) (xy 258.122403 -42.193078) (xy 258.1376 -42.112039)
			(xy 258.160229 -42.032754) (xy 258.190094 -41.955902) (xy 258.226941 -41.882142) (xy 258.270452 -41.812106)
			(xy 258.320255 -41.746396) (xy 258.375923 -41.685574) (xy 258.406138 -41.657524) (xy 258.415282 -41.649142)
			(xy 258.423918 -41.62679) (xy 258.412488 -41.520618) (xy 258.39928 -41.500298) (xy 258.388612 -41.494202)
			(xy 258.352203 -41.47258) (xy 258.283247 -41.423422) (xy 258.219273 -41.367935) (xy 258.16086 -41.306622)
			(xy 258.108535 -41.240036) (xy 258.062773 -41.168781) (xy 258.023988 -41.093501) (xy 257.992529 -41.014876)
			(xy 257.968682 -40.933619) (xy 257.952663 -40.850463) (xy 257.944616 -40.766162) (xy 257.944112 -40.72382)
			(xy 257.944722 -40.676728) (xy 257.954664 -40.583071) (xy 257.974438 -40.490987) (xy 258.003824 -40.401506)
			(xy 258.022598 -40.358314) (xy 258.02655 -40.348334) (xy 258.026555 -40.32689) (xy 258.022598 -40.316912)
			(xy 258.004411 -40.274268) (xy 257.97595 -40.186031) (xy 257.956819 -40.095313) (xy 257.947225 -40.003097)
			(xy 257.946652 -39.95674) (xy 257.946693 -39.939388) (xy 257.947962 -39.904707) (xy 257.949192 -39.887398)
			(xy 257.949484 -39.87578) (xy 257.9409 -39.854212) (xy 257.932682 -39.845996) (xy 257.902445 -39.817967)
			(xy 257.846768 -39.757149) (xy 257.796958 -39.69144) (xy 257.753442 -39.621403) (xy 257.716595 -39.54764)
			(xy 257.686732 -39.470783) (xy 257.664109 -39.391493) (xy 257.648921 -39.310449) (xy 257.641298 -39.228347)
			(xy 257.640836 -39.18712) (xy 252.350882 -39.18712) (xy 252.346074 -39.201239) (xy 252.283659 -39.359749)
			(xy 252.213883 -39.515159) (xy 252.1369 -39.667127) (xy 252.052878 -39.815321) (xy 251.962002 -39.959413)
			(xy 251.864472 -40.099087) (xy 251.760502 -40.234036) (xy 251.650321 -40.363964) (xy 251.534172 -40.488584)
			(xy 251.412308 -40.607623) (xy 251.285 -40.720819) (xy 251.152525 -40.827924) (xy 251.015175 -40.928701)
			(xy 250.873253 -41.02293) (xy 250.727071 -41.110403) (xy 250.576948 -41.190928) (xy 250.423217 -41.264328)
			(xy 250.266214 -41.330442) (xy 250.106284 -41.389124) (xy 249.94378 -41.440245) (xy 249.779059 -41.483693)
			(xy 249.612481 -41.519372) (xy 249.444415 -41.547204) (xy 249.275229 -41.567128) (xy 249.105295 -41.5791)
			(xy 248.934986 -41.583094) (xy 248.764677 -41.5791) (xy 248.594743 -41.567128) (xy 248.425557 -41.547204)
			(xy 248.257491 -41.519372) (xy 248.090913 -41.483693) (xy 247.926192 -41.440245) (xy 247.763688 -41.389124)
			(xy 247.603758 -41.330442) (xy 247.446755 -41.264328) (xy 247.293024 -41.190928) (xy 247.142901 -41.110403)
			(xy 246.996719 -41.02293) (xy 246.854797 -40.928701) (xy 246.717447 -40.827924) (xy 246.584972 -40.720819)
			(xy 246.457664 -40.607623) (xy 246.3358 -40.488584) (xy 246.219651 -40.363964) (xy 246.10947 -40.234036)
			(xy 246.0055 -40.099087) (xy 245.90797 -39.959413) (xy 245.817094 -39.815321) (xy 245.733072 -39.667127)
			(xy 245.656089 -39.515159) (xy 245.586313 -39.359749) (xy 245.523898 -39.201239) (xy 245.468981 -39.039978)
			(xy 245.421684 -38.87632) (xy 245.382109 -38.710625) (xy 245.350345 -38.543257) (xy 245.32646 -38.374585)
			(xy 245.310508 -38.204978) (xy 245.302523 -38.03481) (xy 202.706832 -38.03481) (xy 202.701465 -38.106403)
			(xy 202.685855 -38.209943) (xy 202.662551 -38.312026) (xy 202.631683 -38.412082) (xy 202.593423 -38.509551)
			(xy 202.547985 -38.603889) (xy 202.495624 -38.694566) (xy 202.436633 -38.781077) (xy 202.371342 -38.862937)
			(xy 202.300114 -38.939688) (xy 202.22335 -39.010902) (xy 202.141479 -39.076179) (xy 202.054958 -39.135155)
			(xy 201.964271 -39.1875) (xy 201.869926 -39.232921) (xy 201.77245 -39.271164) (xy 201.672388 -39.302015)
			(xy 201.570301 -39.325301) (xy 201.466759 -39.340893) (xy 201.362341 -39.348702) (xy 201.309986 -39.349172)
			(xy 201.255694 -39.348606) (xy 201.147435 -39.340199) (xy 201.040154 -39.323428) (xy 200.934494 -39.298394)
			(xy 200.831092 -39.265249) (xy 200.730569 -39.224191) (xy 200.63353 -39.175467) (xy 200.540559 -39.11937)
			(xy 200.452213 -39.056237) (xy 200.369026 -38.986449) (xy 200.291496 -38.910425) (xy 200.22009 -38.828621)
			(xy 200.155238 -38.74153) (xy 200.125838 -38.695884) (xy 200.118726 -38.684708) (xy 200.096374 -38.672262)
			(xy 199.983598 -38.672262) (xy 199.961246 -38.684708) (xy 199.954134 -38.695884) (xy 199.924757 -38.741546)
			(xy 199.859901 -38.828636) (xy 199.788493 -38.91044) (xy 199.71096 -38.986465) (xy 199.62777 -39.056254)
			(xy 199.539423 -39.119388) (xy 199.44645 -39.175486) (xy 199.34941 -39.224212) (xy 199.248886 -39.265273)
			(xy 199.145483 -39.298422) (xy 199.039822 -39.323459) (xy 198.93254 -39.340234) (xy 198.824279 -39.348647)
			(xy 198.769986 -39.349172) (xy 198.717633 -39.348718) (xy 198.61322 -39.340894) (xy 198.509683 -39.325289)
			(xy 198.407602 -39.301991) (xy 198.307547 -39.271131) (xy 198.210078 -39.23288) (xy 198.11574 -39.187454)
			(xy 198.025059 -39.135106) (xy 197.938544 -39.076128) (xy 197.856677 -39.01085) (xy 197.779917 -38.939637)
			(xy 197.708692 -38.862888) (xy 197.643402 -38.781032) (xy 197.584411 -38.694526) (xy 197.532048 -38.603853)
			(xy 197.486607 -38.509522) (xy 197.448341 -38.412058) (xy 197.417465 -38.312008) (xy 197.394152 -38.209931)
			(xy 197.378531 -38.106397) (xy 197.37069 -38.001985) (xy 197.370192 -37.949632) (xy 197.370714 -37.895332)
			(xy 197.379129 -37.787059) (xy 197.395911 -37.679764) (xy 197.420959 -37.574093) (xy 197.454122 -37.470681)
			(xy 197.495202 -37.370151) (xy 197.543949 -37.273107) (xy 197.600072 -37.180134) (xy 197.663233 -37.09179)
			(xy 197.733051 -37.008608) (xy 197.809106 -36.931087) (xy 197.890942 -36.859696) (xy 197.978065 -36.794861)
			(xy 198.023734 -36.765484) (xy 198.03491 -36.758372) (xy 198.047356 -36.73602) (xy 198.047356 -36.623244)
			(xy 198.03491 -36.600892) (xy 198.023734 -36.59378) (xy 197.979782 -36.565453) (xy 197.895707 -36.503265)
			(xy 197.81651 -36.434975) (xy 197.74263 -36.360964) (xy 197.674482 -36.281645) (xy 197.612444 -36.19746)
			(xy 197.556863 -36.10888) (xy 197.508049 -36.016397) (xy 197.466275 -35.920529) (xy 197.431773 -35.82181)
			(xy 197.404736 -35.720792) (xy 197.385315 -35.618036) (xy 197.373619 -35.514118) (xy 197.369712 -35.409617)
			(xy 193.820281 -35.409617) (xy 193.816374 -35.514121) (xy 193.804677 -35.618041) (xy 193.785257 -35.720799)
			(xy 193.758221 -35.82182) (xy 193.72372 -35.920542) (xy 193.681946 -36.016413) (xy 193.633133 -36.108899)
			(xy 193.577553 -36.197483) (xy 193.515516 -36.281671) (xy 193.447368 -36.360994) (xy 193.37349 -36.435009)
			(xy 193.294293 -36.503304) (xy 193.210219 -36.565496) (xy 193.166238 -36.59378) (xy 193.155062 -36.600892)
			(xy 193.142616 -36.623244) (xy 193.142616 -36.73602) (xy 193.155062 -36.758372) (xy 193.166238 -36.765484)
			(xy 193.21193 -36.794827) (xy 193.299051 -36.859666) (xy 193.380885 -36.931062) (xy 193.456939 -37.008586)
			(xy 193.526756 -37.091772) (xy 193.589915 -37.180118) (xy 193.646037 -37.273094) (xy 193.694783 -37.37014)
			(xy 193.735861 -37.470673) (xy 193.769024 -37.574087) (xy 193.794071 -37.67976) (xy 193.810853 -37.787057)
			(xy 193.819268 -37.895331) (xy 193.81978 -37.949632) (xy 193.819293 -38.001987) (xy 193.811465 -38.106403)
			(xy 193.795855 -38.209943) (xy 193.772551 -38.312026) (xy 193.741683 -38.412082) (xy 193.703423 -38.509551)
			(xy 193.657985 -38.603889) (xy 193.605624 -38.694566) (xy 193.546633 -38.781077) (xy 193.481342 -38.862937)
			(xy 193.410114 -38.939688) (xy 193.33335 -39.010902) (xy 193.251479 -39.076179) (xy 193.164958 -39.135155)
			(xy 193.074271 -39.1875) (xy 192.979926 -39.232921) (xy 192.88245 -39.271164) (xy 192.782388 -39.302015)
			(xy 192.680301 -39.325301) (xy 192.576759 -39.340893) (xy 192.472341 -39.348702) (xy 192.419986 -39.349172)
			(xy 192.365694 -39.348606) (xy 192.257435 -39.340199) (xy 192.150154 -39.323428) (xy 192.044494 -39.298394)
			(xy 191.941092 -39.265249) (xy 191.840569 -39.224191) (xy 191.74353 -39.175467) (xy 191.650559 -39.11937)
			(xy 191.562213 -39.056237) (xy 191.479026 -38.986449) (xy 191.401496 -38.910425) (xy 191.33009 -38.828621)
			(xy 191.265238 -38.74153) (xy 191.235838 -38.695884) (xy 191.228726 -38.684708) (xy 191.206374 -38.672262)
			(xy 191.093598 -38.672262) (xy 191.071246 -38.684708) (xy 191.064134 -38.695884) (xy 191.034757 -38.741546)
			(xy 190.969901 -38.828636) (xy 190.898493 -38.91044) (xy 190.82096 -38.986465) (xy 190.73777 -39.056254)
			(xy 190.649423 -39.119388) (xy 190.55645 -39.175486) (xy 190.45941 -39.224212) (xy 190.358886 -39.265273)
			(xy 190.255483 -39.298422) (xy 190.149822 -39.323459) (xy 190.04254 -39.340234) (xy 189.934279 -39.348647)
			(xy 189.879986 -39.349172) (xy 189.827633 -39.348718) (xy 189.72322 -39.340894) (xy 189.619683 -39.325289)
			(xy 189.517602 -39.301991) (xy 189.417547 -39.271131) (xy 189.320078 -39.23288) (xy 189.22574 -39.187454)
			(xy 189.135059 -39.135106) (xy 189.048544 -39.076128) (xy 188.966677 -39.01085) (xy 188.889917 -38.939637)
			(xy 188.818692 -38.862888) (xy 188.753402 -38.781032) (xy 188.694411 -38.694526) (xy 188.642048 -38.603853)
			(xy 188.596607 -38.509522) (xy 188.558341 -38.412058) (xy 188.527465 -38.312008) (xy 188.504152 -38.209931)
			(xy 188.488531 -38.106397) (xy 188.48069 -38.001985) (xy 188.480192 -37.949632) (xy 188.480714 -37.895332)
			(xy 188.489129 -37.787059) (xy 188.505911 -37.679764) (xy 188.530959 -37.574093) (xy 188.564122 -37.470681)
			(xy 188.605202 -37.370151) (xy 188.653949 -37.273107) (xy 188.710072 -37.180134) (xy 188.773233 -37.09179)
			(xy 188.843051 -37.008608) (xy 188.919106 -36.931087) (xy 189.000942 -36.859696) (xy 189.088065 -36.794861)
			(xy 189.133734 -36.765484) (xy 189.14491 -36.758372) (xy 189.157356 -36.73602) (xy 189.157356 -36.623244)
			(xy 189.14491 -36.600892) (xy 189.133734 -36.59378) (xy 189.089782 -36.565453) (xy 189.005707 -36.503265)
			(xy 188.92651 -36.434975) (xy 188.85263 -36.360964) (xy 188.784482 -36.281645) (xy 188.722444 -36.19746)
			(xy 188.666863 -36.10888) (xy 188.618049 -36.016397) (xy 188.576275 -35.920529) (xy 188.541773 -35.82181)
			(xy 188.514736 -35.720792) (xy 188.495315 -35.618036) (xy 188.483619 -35.514118) (xy 188.479712 -35.409617)
			(xy 184.930281 -35.409617) (xy 184.926374 -35.514121) (xy 184.914677 -35.618041) (xy 184.895257 -35.720799)
			(xy 184.868221 -35.82182) (xy 184.83372 -35.920542) (xy 184.791946 -36.016413) (xy 184.743133 -36.108899)
			(xy 184.687553 -36.197483) (xy 184.625516 -36.281671) (xy 184.557368 -36.360994) (xy 184.48349 -36.435009)
			(xy 184.404293 -36.503304) (xy 184.320219 -36.565496) (xy 184.276238 -36.59378) (xy 184.265062 -36.600892)
			(xy 184.252616 -36.623244) (xy 184.252616 -36.73602) (xy 184.265062 -36.758372) (xy 184.276238 -36.765484)
			(xy 184.32193 -36.794827) (xy 184.409051 -36.859666) (xy 184.490885 -36.931062) (xy 184.566939 -37.008586)
			(xy 184.636756 -37.091772) (xy 184.699915 -37.180118) (xy 184.756037 -37.273094) (xy 184.804783 -37.37014)
			(xy 184.845861 -37.470673) (xy 184.879024 -37.574087) (xy 184.904071 -37.67976) (xy 184.920853 -37.787057)
			(xy 184.929268 -37.895331) (xy 184.92978 -37.949632) (xy 184.929293 -38.001987) (xy 184.921465 -38.106403)
			(xy 184.905855 -38.209943) (xy 184.882551 -38.312026) (xy 184.851683 -38.412082) (xy 184.813423 -38.509551)
			(xy 184.767985 -38.603889) (xy 184.715624 -38.694566) (xy 184.656633 -38.781077) (xy 184.591342 -38.862937)
			(xy 184.520114 -38.939688) (xy 184.44335 -39.010902) (xy 184.361479 -39.076179) (xy 184.274958 -39.135155)
			(xy 184.184271 -39.1875) (xy 184.089926 -39.232921) (xy 183.99245 -39.271164) (xy 183.892388 -39.302015)
			(xy 183.790301 -39.325301) (xy 183.686759 -39.340893) (xy 183.582341 -39.348702) (xy 183.529986 -39.349172)
			(xy 183.475694 -39.348606) (xy 183.367435 -39.340199) (xy 183.260154 -39.323428) (xy 183.154494 -39.298394)
			(xy 183.051092 -39.265249) (xy 182.950569 -39.224191) (xy 182.85353 -39.175467) (xy 182.760559 -39.11937)
			(xy 182.672213 -39.056237) (xy 182.589026 -38.986449) (xy 182.511496 -38.910425) (xy 182.44009 -38.828621)
			(xy 182.375238 -38.74153) (xy 182.345838 -38.695884) (xy 182.338726 -38.684708) (xy 182.316374 -38.672262)
			(xy 182.203598 -38.672262) (xy 182.181246 -38.684708) (xy 182.174134 -38.695884) (xy 182.144757 -38.741546)
			(xy 182.079901 -38.828636) (xy 182.008493 -38.91044) (xy 181.93096 -38.986465) (xy 181.84777 -39.056254)
			(xy 181.759423 -39.119388) (xy 181.66645 -39.175486) (xy 181.56941 -39.224212) (xy 181.468886 -39.265273)
			(xy 181.365483 -39.298422) (xy 181.259822 -39.323459) (xy 181.15254 -39.340234) (xy 181.044279 -39.348647)
			(xy 180.989986 -39.349172) (xy 180.937633 -39.348718) (xy 180.83322 -39.340894) (xy 180.729683 -39.325289)
			(xy 180.627602 -39.301991) (xy 180.527547 -39.271131) (xy 180.430078 -39.23288) (xy 180.33574 -39.187454)
			(xy 180.245059 -39.135106) (xy 180.158544 -39.076128) (xy 180.076677 -39.01085) (xy 179.999917 -38.939637)
			(xy 179.928692 -38.862888) (xy 179.863402 -38.781032) (xy 179.804411 -38.694526) (xy 179.752048 -38.603853)
			(xy 179.706607 -38.509522) (xy 179.668341 -38.412058) (xy 179.637465 -38.312008) (xy 179.614152 -38.209931)
			(xy 179.598531 -38.106397) (xy 179.59069 -38.001985) (xy 179.590192 -37.949632) (xy 179.590714 -37.895332)
			(xy 179.599129 -37.787059) (xy 179.615911 -37.679764) (xy 179.640959 -37.574093) (xy 179.674122 -37.470681)
			(xy 179.715202 -37.370151) (xy 179.763949 -37.273107) (xy 179.820072 -37.180134) (xy 179.883233 -37.09179)
			(xy 179.953051 -37.008608) (xy 180.029106 -36.931087) (xy 180.110942 -36.859696) (xy 180.198065 -36.794861)
			(xy 180.243734 -36.765484) (xy 180.25491 -36.758372) (xy 180.267356 -36.73602) (xy 180.267356 -36.623244)
			(xy 180.25491 -36.600892) (xy 180.243734 -36.59378) (xy 180.199782 -36.565453) (xy 180.115707 -36.503265)
			(xy 180.03651 -36.434975) (xy 179.96263 -36.360964) (xy 179.894482 -36.281645) (xy 179.832444 -36.19746)
			(xy 179.776863 -36.10888) (xy 179.728049 -36.016397) (xy 179.686275 -35.920529) (xy 179.651773 -35.82181)
			(xy 179.624736 -35.720792) (xy 179.605315 -35.618036) (xy 179.593619 -35.514118) (xy 179.589712 -35.409617)
			(xy 171.523084 -35.409617) (xy 171.524172 -35.41068) (xy 171.640321 -35.5353) (xy 171.750502 -35.665228)
			(xy 171.854472 -35.800177) (xy 171.952002 -35.939851) (xy 172.042878 -36.083943) (xy 172.1269 -36.232137)
			(xy 172.203883 -36.384105) (xy 172.273659 -36.539515) (xy 172.336074 -36.698025) (xy 172.390991 -36.859286)
			(xy 172.438288 -37.022944) (xy 172.477863 -37.188639) (xy 172.509627 -37.356007) (xy 172.533512 -37.524679)
			(xy 172.549464 -37.694286) (xy 172.557449 -37.864454) (xy 172.557948 -37.949632) (xy 172.557449 -38.03481)
			(xy 172.549464 -38.204978) (xy 172.533512 -38.374585) (xy 172.509627 -38.543257) (xy 172.477863 -38.710625)
			(xy 172.438288 -38.87632) (xy 172.390991 -39.039978) (xy 172.336074 -39.201239) (xy 172.273659 -39.359749)
			(xy 172.203883 -39.515159) (xy 172.1269 -39.667127) (xy 172.042878 -39.815321) (xy 171.952002 -39.959413)
			(xy 171.854472 -40.099087) (xy 171.750502 -40.234036) (xy 171.640321 -40.363964) (xy 171.524172 -40.488584)
			(xy 171.402308 -40.607623) (xy 171.275 -40.720819) (xy 171.142525 -40.827924) (xy 171.005175 -40.928701)
			(xy 170.863253 -41.02293) (xy 170.717071 -41.110403) (xy 170.566948 -41.190928) (xy 170.413217 -41.264328)
			(xy 170.256214 -41.330442) (xy 170.096284 -41.389124) (xy 169.93378 -41.440245) (xy 169.769059 -41.483693)
			(xy 169.602481 -41.519372) (xy 169.434415 -41.547204) (xy 169.265229 -41.567128) (xy 169.095295 -41.5791)
			(xy 168.924986 -41.583094) (xy 168.754677 -41.5791) (xy 168.584743 -41.567128) (xy 168.415557 -41.547204)
			(xy 168.247491 -41.519372) (xy 168.080913 -41.483693) (xy 167.916192 -41.440245) (xy 167.753688 -41.389124)
			(xy 167.593758 -41.330442) (xy 167.436755 -41.264328) (xy 167.283024 -41.190928) (xy 167.132901 -41.110403)
			(xy 166.986719 -41.02293) (xy 166.844797 -40.928701) (xy 166.707447 -40.827924) (xy 166.574972 -40.720819)
			(xy 166.447664 -40.607623) (xy 166.3258 -40.488584) (xy 166.209651 -40.363964) (xy 166.09947 -40.234036)
			(xy 165.9955 -40.099087) (xy 165.89797 -39.959413) (xy 165.807094 -39.815321) (xy 165.723072 -39.667127)
			(xy 165.646089 -39.515159) (xy 165.576313 -39.359749) (xy 165.513898 -39.201239) (xy 165.458981 -39.039978)
			(xy 165.411684 -38.87632) (xy 165.372109 -38.710625) (xy 165.340345 -38.543257) (xy 165.31646 -38.374585)
			(xy 165.300508 -38.204978) (xy 165.292523 -38.03481) (xy 123.764517 -38.03481) (xy 123.761167 -38.124486)
			(xy 123.749476 -38.228395) (xy 123.730065 -38.331142) (xy 123.70304 -38.432154) (xy 123.668553 -38.530867)
			(xy 123.626796 -38.626732) (xy 123.578001 -38.719214) (xy 123.522442 -38.807796) (xy 123.460427 -38.891986)
			(xy 123.392303 -38.971313) (xy 123.318449 -39.045335) (xy 123.239277 -39.11364) (xy 123.155229 -39.175846)
			(xy 123.11126 -39.204138) (xy 123.100084 -39.21125) (xy 123.087638 -39.233602) (xy 123.087638 -39.346378)
			(xy 123.100084 -39.36873) (xy 123.11126 -39.375842) (xy 123.156905 -39.405244) (xy 123.243996 -39.470097)
			(xy 123.325801 -39.541503) (xy 123.401827 -39.619033) (xy 123.471617 -39.702221) (xy 123.534751 -39.790565)
			(xy 123.590851 -39.883536) (xy 123.639579 -39.980574) (xy 123.680641 -40.081096) (xy 123.713792 -40.184498)
			(xy 123.738831 -40.290157) (xy 123.755608 -40.397438) (xy 123.764022 -40.505697) (xy 123.764548 -40.55999)
			(xy 123.764095 -40.612343) (xy 123.756272 -40.716757) (xy 123.740669 -40.820294) (xy 123.717372 -40.922376)
			(xy 123.686513 -41.022432) (xy 123.648263 -41.119902) (xy 123.602837 -41.214241) (xy 123.550489 -41.304922)
			(xy 123.491511 -41.391438) (xy 123.426233 -41.473306) (xy 123.35502 -41.550066) (xy 123.278271 -41.621291)
			(xy 123.196414 -41.686581) (xy 123.109907 -41.745573) (xy 123.019234 -41.797935) (xy 122.924902 -41.843376)
			(xy 122.827438 -41.881641) (xy 122.727387 -41.912516) (xy 122.625308 -41.935828) (xy 122.521774 -41.951448)
			(xy 122.417361 -41.959287) (xy 122.365008 -41.959784) (xy 122.310709 -41.959246) (xy 122.202437 -41.95083)
			(xy 122.095143 -41.934047) (xy 121.989473 -41.908999) (xy 121.886062 -41.875835) (xy 121.785533 -41.834757)
			(xy 121.68849 -41.786011) (xy 121.595516 -41.729889) (xy 121.507173 -41.666731) (xy 121.42399 -41.596915)
			(xy 121.346469 -41.520862) (xy 121.275075 -41.43903) (xy 121.210239 -41.35191) (xy 121.18086 -41.306242)
			(xy 121.173748 -41.295066) (xy 121.151396 -41.28262) (xy 121.03862 -41.28262) (xy 121.016268 -41.295066)
			(xy 121.009156 -41.306242) (xy 120.979787 -41.351917) (xy 120.91495 -41.439038) (xy 120.843556 -41.520872)
			(xy 120.766034 -41.596926) (xy 120.682851 -41.666744) (xy 120.594507 -41.729904) (xy 120.501533 -41.786026)
			(xy 120.404489 -41.834774) (xy 120.303959 -41.875854) (xy 120.200547 -41.909019) (xy 120.094876 -41.934068)
			(xy 119.987581 -41.950853) (xy 119.879308 -41.95927) (xy 119.825008 -41.959784) (xy 119.772654 -41.959255)
			(xy 119.668238 -41.95143) (xy 119.5647 -41.935823) (xy 119.462617 -41.912521) (xy 119.362562 -41.881656)
			(xy 119.265093 -41.843398) (xy 119.170756 -41.797963) (xy 119.080078 -41.745605) (xy 118.993567 -41.686616)
			(xy 118.911707 -41.621327) (xy 118.834955 -41.550102) (xy 118.763742 -41.47334) (xy 118.698464 -41.39147)
			(xy 118.639487 -41.304951) (xy 118.587142 -41.214266) (xy 118.541721 -41.119922) (xy 118.503478 -41.022448)
			(xy 118.472627 -40.922388) (xy 118.44934 -40.820302) (xy 118.433748 -40.716761) (xy 118.425938 -40.612344)
			(xy 118.425468 -40.55999) (xy 118.426019 -40.505697) (xy 118.434426 -40.397438) (xy 118.451197 -40.290155)
			(xy 118.476231 -40.184495) (xy 118.509377 -40.081093) (xy 118.550436 -39.980569) (xy 118.599162 -39.88353)
			(xy 118.65526 -39.790558) (xy 118.718394 -39.702213) (xy 118.788184 -39.619026) (xy 118.864211 -39.541497)
			(xy 118.946016 -39.470092) (xy 119.033109 -39.405241) (xy 119.078756 -39.375842) (xy 119.089932 -39.36873)
			(xy 119.102378 -39.346378) (xy 119.102378 -39.233602) (xy 119.089932 -39.21125) (xy 119.078756 -39.204138)
			(xy 119.03478 -39.175858) (xy 118.950735 -39.113648) (xy 118.871567 -39.045341) (xy 118.797716 -38.971316)
			(xy 118.729595 -38.891987) (xy 118.667583 -38.807796) (xy 118.612027 -38.719212) (xy 118.563235 -38.62673)
			(xy 118.52148 -38.530865) (xy 118.486995 -38.432152) (xy 118.459971 -38.33114) (xy 118.440561 -38.228394)
			(xy 118.428871 -38.124486) (xy 118.424968 -38.019995) (xy 114.87507 -38.019995) (xy 114.871167 -38.124486)
			(xy 114.859476 -38.228395) (xy 114.840065 -38.331142) (xy 114.81304 -38.432154) (xy 114.778553 -38.530867)
			(xy 114.736796 -38.626732) (xy 114.688001 -38.719214) (xy 114.632442 -38.807796) (xy 114.570427 -38.891986)
			(xy 114.502303 -38.971313) (xy 114.428449 -39.045335) (xy 114.349277 -39.11364) (xy 114.265229 -39.175846)
			(xy 114.22126 -39.204138) (xy 114.210084 -39.21125) (xy 114.197638 -39.233602) (xy 114.197638 -39.346378)
			(xy 114.210084 -39.36873) (xy 114.22126 -39.375842) (xy 114.266905 -39.405244) (xy 114.353996 -39.470097)
			(xy 114.435801 -39.541503) (xy 114.511827 -39.619033) (xy 114.581617 -39.702221) (xy 114.644751 -39.790565)
			(xy 114.700851 -39.883536) (xy 114.749579 -39.980574) (xy 114.790641 -40.081096) (xy 114.823792 -40.184498)
			(xy 114.848831 -40.290157) (xy 114.865608 -40.397438) (xy 114.874022 -40.505697) (xy 114.874548 -40.55999)
			(xy 114.874095 -40.612343) (xy 114.866272 -40.716757) (xy 114.850669 -40.820294) (xy 114.827372 -40.922376)
			(xy 114.796513 -41.022432) (xy 114.758263 -41.119902) (xy 114.712837 -41.214241) (xy 114.660489 -41.304922)
			(xy 114.601511 -41.391438) (xy 114.536233 -41.473306) (xy 114.46502 -41.550066) (xy 114.388271 -41.621291)
			(xy 114.306414 -41.686581) (xy 114.219907 -41.745573) (xy 114.129234 -41.797935) (xy 114.034902 -41.843376)
			(xy 113.937438 -41.881641) (xy 113.837387 -41.912516) (xy 113.735308 -41.935828) (xy 113.631774 -41.951448)
			(xy 113.527361 -41.959287) (xy 113.475008 -41.959784) (xy 113.420709 -41.959246) (xy 113.312437 -41.95083)
			(xy 113.205143 -41.934047) (xy 113.099473 -41.908999) (xy 112.996062 -41.875835) (xy 112.895533 -41.834757)
			(xy 112.79849 -41.786011) (xy 112.705516 -41.729889) (xy 112.617173 -41.666731) (xy 112.53399 -41.596915)
			(xy 112.456469 -41.520862) (xy 112.385075 -41.43903) (xy 112.320239 -41.35191) (xy 112.29086 -41.306242)
			(xy 112.283748 -41.295066) (xy 112.261396 -41.28262) (xy 112.14862 -41.28262) (xy 112.126268 -41.295066)
			(xy 112.119156 -41.306242) (xy 112.089787 -41.351917) (xy 112.02495 -41.439038) (xy 111.953556 -41.520872)
			(xy 111.876034 -41.596926) (xy 111.792851 -41.666744) (xy 111.704507 -41.729904) (xy 111.611533 -41.786026)
			(xy 111.514489 -41.834774) (xy 111.413959 -41.875854) (xy 111.310547 -41.909019) (xy 111.204876 -41.934068)
			(xy 111.097581 -41.950853) (xy 110.989308 -41.95927) (xy 110.935008 -41.959784) (xy 110.882654 -41.959255)
			(xy 110.778238 -41.95143) (xy 110.6747 -41.935823) (xy 110.572617 -41.912521) (xy 110.472562 -41.881656)
			(xy 110.375093 -41.843398) (xy 110.280756 -41.797963) (xy 110.190078 -41.745605) (xy 110.103567 -41.686616)
			(xy 110.021707 -41.621327) (xy 109.944955 -41.550102) (xy 109.873742 -41.47334) (xy 109.808464 -41.39147)
			(xy 109.749487 -41.304951) (xy 109.697142 -41.214266) (xy 109.651721 -41.119922) (xy 109.613478 -41.022448)
			(xy 109.582627 -40.922388) (xy 109.55934 -40.820302) (xy 109.543748 -40.716761) (xy 109.535938 -40.612344)
			(xy 109.535468 -40.55999) (xy 109.536019 -40.505697) (xy 109.544426 -40.397438) (xy 109.561197 -40.290155)
			(xy 109.586231 -40.184495) (xy 109.619377 -40.081093) (xy 109.660436 -39.980569) (xy 109.709162 -39.88353)
			(xy 109.76526 -39.790558) (xy 109.828394 -39.702213) (xy 109.898184 -39.619026) (xy 109.974211 -39.541497)
			(xy 110.056016 -39.470092) (xy 110.143109 -39.405241) (xy 110.188756 -39.375842) (xy 110.199932 -39.36873)
			(xy 110.212378 -39.346378) (xy 110.212378 -39.233602) (xy 110.199932 -39.21125) (xy 110.188756 -39.204138)
			(xy 110.14478 -39.175858) (xy 110.060735 -39.113648) (xy 109.981567 -39.045341) (xy 109.907716 -38.971316)
			(xy 109.839595 -38.891987) (xy 109.777583 -38.807796) (xy 109.722027 -38.719212) (xy 109.673235 -38.62673)
			(xy 109.63148 -38.530865) (xy 109.596995 -38.432152) (xy 109.569971 -38.33114) (xy 109.550561 -38.228394)
			(xy 109.538871 -38.124486) (xy 109.534968 -38.019995) (xy 105.98507 -38.019995) (xy 105.981167 -38.124486)
			(xy 105.969476 -38.228395) (xy 105.950065 -38.331142) (xy 105.92304 -38.432154) (xy 105.888553 -38.530867)
			(xy 105.846796 -38.626732) (xy 105.798001 -38.719214) (xy 105.742442 -38.807796) (xy 105.680427 -38.891986)
			(xy 105.612303 -38.971313) (xy 105.538449 -39.045335) (xy 105.459277 -39.11364) (xy 105.375229 -39.175846)
			(xy 105.33126 -39.204138) (xy 105.320084 -39.21125) (xy 105.307638 -39.233602) (xy 105.307638 -39.346378)
			(xy 105.320084 -39.36873) (xy 105.33126 -39.375842) (xy 105.376905 -39.405244) (xy 105.463996 -39.470097)
			(xy 105.545801 -39.541503) (xy 105.621827 -39.619033) (xy 105.691617 -39.702221) (xy 105.754751 -39.790565)
			(xy 105.810851 -39.883536) (xy 105.859579 -39.980574) (xy 105.900641 -40.081096) (xy 105.933792 -40.184498)
			(xy 105.958831 -40.290157) (xy 105.975608 -40.397438) (xy 105.984022 -40.505697) (xy 105.984548 -40.55999)
			(xy 105.984095 -40.612343) (xy 105.976272 -40.716757) (xy 105.960669 -40.820294) (xy 105.937372 -40.922376)
			(xy 105.906513 -41.022432) (xy 105.868263 -41.119902) (xy 105.822837 -41.214241) (xy 105.770489 -41.304922)
			(xy 105.711511 -41.391438) (xy 105.646233 -41.473306) (xy 105.57502 -41.550066) (xy 105.498271 -41.621291)
			(xy 105.416414 -41.686581) (xy 105.329907 -41.745573) (xy 105.239234 -41.797935) (xy 105.144902 -41.843376)
			(xy 105.047438 -41.881641) (xy 104.947387 -41.912516) (xy 104.845308 -41.935828) (xy 104.741774 -41.951448)
			(xy 104.637361 -41.959287) (xy 104.585008 -41.959784) (xy 104.530709 -41.959246) (xy 104.422437 -41.95083)
			(xy 104.315143 -41.934047) (xy 104.209473 -41.908999) (xy 104.106062 -41.875835) (xy 104.005533 -41.834757)
			(xy 103.90849 -41.786011) (xy 103.815516 -41.729889) (xy 103.727173 -41.666731) (xy 103.64399 -41.596915)
			(xy 103.566469 -41.520862) (xy 103.495075 -41.43903) (xy 103.430239 -41.35191) (xy 103.40086 -41.306242)
			(xy 103.393748 -41.295066) (xy 103.371396 -41.28262) (xy 103.25862 -41.28262) (xy 103.236268 -41.295066)
			(xy 103.229156 -41.306242) (xy 103.199787 -41.351917) (xy 103.13495 -41.439038) (xy 103.063556 -41.520872)
			(xy 102.986034 -41.596926) (xy 102.902851 -41.666744) (xy 102.814507 -41.729904) (xy 102.721533 -41.786026)
			(xy 102.624489 -41.834774) (xy 102.523959 -41.875854) (xy 102.420547 -41.909019) (xy 102.314876 -41.934068)
			(xy 102.207581 -41.950853) (xy 102.099308 -41.95927) (xy 102.045008 -41.959784) (xy 101.992654 -41.959255)
			(xy 101.888238 -41.95143) (xy 101.7847 -41.935823) (xy 101.682617 -41.912521) (xy 101.582562 -41.881656)
			(xy 101.485093 -41.843398) (xy 101.390756 -41.797963) (xy 101.300078 -41.745605) (xy 101.213567 -41.686616)
			(xy 101.131707 -41.621327) (xy 101.054955 -41.550102) (xy 100.983742 -41.47334) (xy 100.918464 -41.39147)
			(xy 100.859487 -41.304951) (xy 100.807142 -41.214266) (xy 100.761721 -41.119922) (xy 100.723478 -41.022448)
			(xy 100.692627 -40.922388) (xy 100.66934 -40.820302) (xy 100.653748 -40.716761) (xy 100.645938 -40.612344)
			(xy 100.645468 -40.55999) (xy 100.646019 -40.505697) (xy 100.654426 -40.397438) (xy 100.671197 -40.290155)
			(xy 100.696231 -40.184495) (xy 100.729377 -40.081093) (xy 100.770436 -39.980569) (xy 100.819162 -39.88353)
			(xy 100.87526 -39.790558) (xy 100.938394 -39.702213) (xy 101.008184 -39.619026) (xy 101.084211 -39.541497)
			(xy 101.166016 -39.470092) (xy 101.253109 -39.405241) (xy 101.298756 -39.375842) (xy 101.309932 -39.36873)
			(xy 101.322378 -39.346378) (xy 101.322378 -39.233602) (xy 101.309932 -39.21125) (xy 101.298756 -39.204138)
			(xy 101.25478 -39.175858) (xy 101.170735 -39.113648) (xy 101.091567 -39.045341) (xy 101.017716 -38.971316)
			(xy 100.949595 -38.891987) (xy 100.887583 -38.807796) (xy 100.832027 -38.719212) (xy 100.783235 -38.62673)
			(xy 100.74148 -38.530865) (xy 100.706995 -38.432152) (xy 100.679971 -38.33114) (xy 100.660561 -38.228394)
			(xy 100.648871 -38.124486) (xy 100.644968 -38.019995) (xy 0.509016 -38.019995) (xy 0.509016 -45.466)
			(xy 293.242492 -45.466) (xy 293.242987 -45.423046) (xy 293.251252 -45.337536) (xy 293.267725 -45.253222)
			(xy 293.292251 -45.170889) (xy 293.324602 -45.091305) (xy 293.364476 -45.015211) (xy 293.411503 -44.943317)
			(xy 293.465243 -44.876293) (xy 293.525197 -44.814764) (xy 293.590803 -44.759303) (xy 293.661453 -44.710426)
			(xy 293.736486 -44.668591) (xy 293.775638 -44.650914) (xy 293.783674 -44.646948) (xy 293.796551 -44.634501)
			(xy 293.804365 -44.618386) (xy 293.80561 -44.609512) (xy 293.810549 -44.566203) (xy 293.827823 -44.48076)
			(xy 293.853371 -44.397415) (xy 293.886947 -44.316968) (xy 293.928229 -44.240191) (xy 293.976821 -44.167818)
			(xy 294.032259 -44.100545) (xy 294.094009 -44.039015) (xy 294.161481 -43.98382) (xy 294.234027 -43.935487)
			(xy 294.310952 -43.89448) (xy 294.391519 -43.861193) (xy 294.474954 -43.835944) (xy 294.560459 -43.818976)
			(xy 294.647214 -43.810451) (xy 294.6908 -43.80992) (xy 294.72807 -43.810301) (xy 294.802353 -43.816489)
			(xy 294.875858 -43.828865) (xy 294.948072 -43.84734) (xy 294.983408 -43.859196) (xy 294.991804 -43.861751)
			(xy 295.009341 -43.861622) (xy 295.017698 -43.858942) (xy 295.054748 -43.845723) (xy 295.130664 -43.825091)
			(xy 295.208104 -43.811237) (xy 295.286465 -43.80427) (xy 295.3258 -43.803824) (xy 295.366912 -43.804252)
			(xy 295.448784 -43.811841) (xy 295.529606 -43.826952) (xy 295.608689 -43.849458) (xy 295.685358 -43.879166)
			(xy 295.758958 -43.915823) (xy 295.82886 -43.959116) (xy 295.894469 -44.008675) (xy 295.955224 -44.064078)
			(xy 296.010607 -44.124851) (xy 296.060146 -44.190476) (xy 296.103416 -44.260392) (xy 296.140049 -44.334004)
			(xy 296.161782 -44.390144) (xy 307.777633 -44.390144) (xy 307.777633 -44.219788) (xy 307.785618 -44.04962)
			(xy 307.80157 -43.880013) (xy 307.825455 -43.711341) (xy 307.857219 -43.543973) (xy 307.896794 -43.378278)
			(xy 307.944091 -43.21462) (xy 307.999008 -43.053359) (xy 308.061423 -42.894849) (xy 308.131199 -42.739439)
			(xy 308.208182 -42.587471) (xy 308.292204 -42.439277) (xy 308.38308 -42.295185) (xy 308.48061 -42.155511)
			(xy 308.58458 -42.020562) (xy 308.694761 -41.890634) (xy 308.81091 -41.766014) (xy 308.932774 -41.646975)
			(xy 309.060082 -41.533779) (xy 309.192557 -41.426674) (xy 309.329907 -41.325897) (xy 309.471829 -41.231668)
			(xy 309.618011 -41.144195) (xy 309.768134 -41.06367) (xy 309.921865 -40.99027) (xy 310.078868 -40.924156)
			(xy 310.238798 -40.865474) (xy 310.401302 -40.814353) (xy 310.566023 -40.770905) (xy 310.732601 -40.735226)
			(xy 310.900667 -40.707394) (xy 311.069853 -40.68747) (xy 311.239787 -40.675498) (xy 311.410096 -40.671505)
			(xy 311.580405 -40.675498) (xy 311.750339 -40.68747) (xy 311.919525 -40.707394) (xy 312.087591 -40.735226)
			(xy 312.254169 -40.770905) (xy 312.41889 -40.814353) (xy 312.581394 -40.865474) (xy 312.741324 -40.924156)
			(xy 312.898327 -40.99027) (xy 313.052058 -41.06367) (xy 313.202181 -41.144195) (xy 313.348363 -41.231668)
			(xy 313.490285 -41.325897) (xy 313.627635 -41.426674) (xy 313.76011 -41.533779) (xy 313.887418 -41.646975)
			(xy 314.009282 -41.766014) (xy 314.125431 -41.890634) (xy 314.235612 -42.020562) (xy 314.339582 -42.155511)
			(xy 314.437112 -42.295185) (xy 314.527988 -42.439277) (xy 314.61201 -42.587471) (xy 314.688993 -42.739439)
			(xy 314.758769 -42.894849) (xy 314.821184 -43.053359) (xy 314.876101 -43.21462) (xy 314.923398 -43.378278)
			(xy 314.962973 -43.543973) (xy 314.994737 -43.711341) (xy 315.018622 -43.880013) (xy 315.034574 -44.04962)
			(xy 315.042559 -44.219788) (xy 315.043058 -44.304966) (xy 315.042559 -44.390144) (xy 315.034574 -44.560312)
			(xy 315.018622 -44.729919) (xy 314.994737 -44.898591) (xy 314.962973 -45.065959) (xy 314.923398 -45.231654)
			(xy 314.876101 -45.395312) (xy 314.821184 -45.556573) (xy 314.758769 -45.715083) (xy 314.688993 -45.870493)
			(xy 314.61201 -46.022461) (xy 314.527988 -46.170655) (xy 314.437112 -46.314747) (xy 314.339582 -46.454421)
			(xy 314.235612 -46.58937) (xy 314.125431 -46.719298) (xy 314.009282 -46.843918) (xy 313.887418 -46.962957)
			(xy 313.76011 -47.076153) (xy 313.627635 -47.183258) (xy 313.490285 -47.284035) (xy 313.348363 -47.378264)
			(xy 313.202181 -47.465737) (xy 313.052058 -47.546262) (xy 312.898327 -47.619662) (xy 312.741324 -47.685776)
			(xy 312.581394 -47.744458) (xy 312.41889 -47.795579) (xy 312.254169 -47.839027) (xy 312.087591 -47.874706)
			(xy 311.919525 -47.902538) (xy 311.750339 -47.922462) (xy 311.580405 -47.934434) (xy 311.410096 -47.938428)
			(xy 311.239787 -47.934434) (xy 311.069853 -47.922462) (xy 310.900667 -47.902538) (xy 310.732601 -47.874706)
			(xy 310.566023 -47.839027) (xy 310.401302 -47.795579) (xy 310.238798 -47.744458) (xy 310.078868 -47.685776)
			(xy 309.921865 -47.619662) (xy 309.768134 -47.546262) (xy 309.618011 -47.465737) (xy 309.471829 -47.378264)
			(xy 309.329907 -47.284035) (xy 309.192557 -47.183258) (xy 309.060082 -47.076153) (xy 308.932774 -46.962957)
			(xy 308.81091 -46.843918) (xy 308.694761 -46.719298) (xy 308.58458 -46.58937) (xy 308.48061 -46.454421)
			(xy 308.38308 -46.314747) (xy 308.292204 -46.170655) (xy 308.208182 -46.022461) (xy 308.131199 -45.870493)
			(xy 308.061423 -45.715083) (xy 307.999008 -45.556573) (xy 307.944091 -45.395312) (xy 307.896794 -45.231654)
			(xy 307.857219 -45.065959) (xy 307.825455 -44.898591) (xy 307.80157 -44.729919) (xy 307.785618 -44.560312)
			(xy 307.777633 -44.390144) (xy 296.161782 -44.390144) (xy 296.169733 -44.410682) (xy 296.192213 -44.489772)
			(xy 296.207299 -44.5706) (xy 296.214861 -44.652474) (xy 296.215308 -44.693586) (xy 296.214781 -44.738929)
			(xy 296.205621 -44.829149) (xy 296.19702 -44.873672) (xy 296.194226 -44.88688) (xy 296.202354 -44.91228)
			(xy 296.28592 -44.989496) (xy 296.311574 -44.995592) (xy 296.324528 -44.992036) (xy 296.364572 -44.981036)
			(xy 296.446183 -44.965647) (xy 296.528875 -44.957947) (xy 296.5704 -44.957492) (xy 296.611502 -44.957967)
			(xy 296.693357 -44.965552) (xy 296.774162 -44.980657) (xy 296.853229 -45.003153) (xy 296.929883 -45.032849)
			(xy 297.00347 -45.069491) (xy 297.073362 -45.112766) (xy 297.138963 -45.162306) (xy 297.199713 -45.217687)
			(xy 297.255094 -45.278437) (xy 297.304634 -45.344038) (xy 297.347909 -45.41393) (xy 297.384551 -45.487517)
			(xy 297.414247 -45.564171) (xy 297.436743 -45.643238) (xy 297.451848 -45.724043) (xy 297.459433 -45.805898)
			(xy 297.459908 -45.847) (xy 297.459411 -45.889308) (xy 297.451408 -45.973544) (xy 297.435447 -46.05664)
			(xy 297.41167 -46.137846) (xy 297.380294 -46.216429) (xy 297.341601 -46.291679) (xy 297.319192 -46.327568)
			(xy 297.314312 -46.335958) (xy 297.310644 -46.355) (xy 297.314312 -46.374042) (xy 297.319192 -46.382432)
			(xy 297.341624 -46.418309) (xy 297.380335 -46.493554) (xy 297.411721 -46.572137) (xy 297.435497 -46.653347)
			(xy 297.45145 -46.736449) (xy 297.459434 -46.82069) (xy 297.459908 -46.863) (xy 297.459446 -46.903899)
			(xy 297.451939 -46.985353) (xy 297.436989 -47.065774) (xy 297.414721 -47.144483) (xy 297.385324 -47.220817)
			(xy 297.349046 -47.29413) (xy 297.306193 -47.363806) (xy 297.257126 -47.429254) (xy 297.230038 -47.4599)
			(xy 297.222926 -47.467774) (xy 297.216068 -47.488094) (xy 297.225212 -47.584106) (xy 297.235626 -47.602648)
			(xy 297.244262 -47.609252) (xy 297.255779 -47.618387) (xy 297.274571 -47.640984) (xy 297.287678 -47.667291)
			(xy 297.294399 -47.695902) (xy 297.294808 -47.710598) (xy 297.294808 -50.488088) (xy 297.294295 -50.504742)
			(xy 297.285677 -50.536914) (xy 297.269026 -50.565761) (xy 297.245477 -50.589314) (xy 297.216633 -50.60597)
			(xy 297.184461 -50.614592) (xy 297.167808 -50.615088) (xy 295.953434 -50.615088) (xy 295.93678 -50.614576)
			(xy 295.904605 -50.605961) (xy 295.875756 -50.589312) (xy 295.852202 -50.565761) (xy 295.835547 -50.536916)
			(xy 295.826927 -50.504742) (xy 295.826434 -50.488088) (xy 295.826434 -47.710598) (xy 295.826902 -47.694875)
			(xy 295.834601 -47.664385) (xy 295.849508 -47.636695) (xy 295.870721 -47.613481) (xy 295.883584 -47.604426)
			(xy 295.892982 -47.59833) (xy 295.904666 -47.579788) (xy 295.91762 -47.48149) (xy 295.91127 -47.460662)
			(xy 295.903904 -47.45228) (xy 295.877568 -47.421825) (xy 295.829911 -47.356921) (xy 295.788317 -47.287975)
			(xy 295.753126 -47.215551) (xy 295.724627 -47.140242) (xy 295.703053 -47.062664) (xy 295.688581 -46.983455)
			(xy 295.681328 -46.903261) (xy 295.680892 -46.863) (xy 295.681389 -46.820692) (xy 295.689392 -46.736456)
			(xy 295.705353 -46.65336) (xy 295.72913 -46.572154) (xy 295.760506 -46.493571) (xy 295.799199 -46.418321)
			(xy 295.821608 -46.382432) (xy 295.826488 -46.374042) (xy 295.830156 -46.355) (xy 295.826488 -46.335958)
			(xy 295.821608 -46.327568) (xy 295.799176 -46.291691) (xy 295.760465 -46.216446) (xy 295.729079 -46.137863)
			(xy 295.705303 -46.056653) (xy 295.68935 -45.973551) (xy 295.681366 -45.88931) (xy 295.680892 -45.847)
			(xy 295.681417 -45.801657) (xy 295.690578 -45.711437) (xy 295.69918 -45.666914) (xy 295.701974 -45.653706)
			(xy 295.693846 -45.628306) (xy 295.61028 -45.55109) (xy 295.584626 -45.544994) (xy 295.571672 -45.54855)
			(xy 295.531633 -45.559591) (xy 295.450025 -45.575055) (xy 295.36733 -45.582845) (xy 295.3258 -45.583348)
			(xy 295.275639 -45.58264) (xy 295.175958 -45.571313) (xy 295.126918 -45.560742) (xy 295.116758 -45.558456)
			(xy 295.096438 -45.562012) (xy 295.017952 -45.612812) (xy 295.006522 -45.62983) (xy 295.00449 -45.639736)
			(xy 294.995423 -45.682457) (xy 294.970051 -45.766028) (xy 294.936612 -45.84671) (xy 294.895425 -45.923726)
			(xy 294.846889 -45.996335) (xy 294.79147 -46.063838) (xy 294.729702 -46.125584) (xy 294.66218 -46.180979)
			(xy 294.589554 -46.229489) (xy 294.512523 -46.270648) (xy 294.431829 -46.304058) (xy 294.348248 -46.3294)
			(xy 294.262587 -46.346427) (xy 294.175669 -46.354977) (xy 294.132 -46.355508) (xy 294.090898 -46.355033)
			(xy 294.009043 -46.347448) (xy 293.928238 -46.332343) (xy 293.849171 -46.309847) (xy 293.772517 -46.280151)
			(xy 293.69893 -46.243509) (xy 293.629038 -46.200234) (xy 293.563437 -46.150694) (xy 293.502687 -46.095313)
			(xy 293.447306 -46.034563) (xy 293.397766 -45.968962) (xy 293.354491 -45.89907) (xy 293.317849 -45.825483)
			(xy 293.288153 -45.748829) (xy 293.265657 -45.669762) (xy 293.250552 -45.588957) (xy 293.242967 -45.507102)
			(xy 293.242492 -45.466) (xy 0.509016 -45.466) (xy 0.509016 -46.6242) (xy 288.755312 -46.6242) (xy 288.759342 -46.539599)
			(xy 288.771396 -46.455763) (xy 288.791365 -46.373454) (xy 288.819068 -46.293415) (xy 288.854253 -46.216372)
			(xy 288.896603 -46.143023) (xy 288.945734 -46.074031) (xy 289.0012 -46.010023) (xy 289.0625 -45.951576)
			(xy 289.129078 -45.899222) (xy 289.200331 -45.853433) (xy 289.275615 -45.814625) (xy 289.354246 -45.783149)
			(xy 289.435514 -45.759291) (xy 289.518681 -45.743265) (xy 289.602995 -45.735218) (xy 289.645344 -45.734732)
			(xy 289.684496 -45.735134) (xy 289.7625 -45.741969) (xy 289.8396 -45.755642) (xy 289.915198 -45.776048)
			(xy 289.988706 -45.803028) (xy 290.024312 -45.819314) (xy 290.034699 -45.823549) (xy 290.057105 -45.823549)
			(xy 290.067492 -45.819314) (xy 290.103097 -45.80303) (xy 290.176614 -45.77608) (xy 290.252213 -45.755686)
			(xy 290.32931 -45.742008) (xy 290.407309 -45.735149) (xy 290.44646 -45.734732) (xy 290.488812 -45.735138)
			(xy 290.573134 -45.743186) (xy 290.656308 -45.759214) (xy 290.737583 -45.783075) (xy 290.816221 -45.814554)
			(xy 290.891511 -45.853365) (xy 290.96277 -45.899158) (xy 291.029354 -45.951517) (xy 291.090659 -46.009969)
			(xy 291.14613 -46.073983) (xy 291.195265 -46.142981) (xy 291.237618 -46.216336) (xy 291.272807 -46.293386)
			(xy 291.300512 -46.373432) (xy 291.320482 -46.455749) (xy 291.332537 -46.539591) (xy 291.336568 -46.6242)
			(xy 291.332537 -46.708809) (xy 291.320482 -46.792651) (xy 291.300512 -46.874968) (xy 291.272807 -46.955014)
			(xy 291.237618 -47.032064) (xy 291.195265 -47.105419) (xy 291.14613 -47.174417) (xy 291.090659 -47.238431)
			(xy 291.029354 -47.296883) (xy 290.96277 -47.349242) (xy 290.891511 -47.395035) (xy 290.85596 -47.413361)
			(xy 291.845742 -47.413361) (xy 291.845742 -47.328639) (xy 291.853795 -47.244302) (xy 291.869829 -47.161112)
			(xy 291.893697 -47.079822) (xy 291.925185 -47.00117) (xy 291.964007 -46.925867) (xy 292.00981 -46.854595)
			(xy 292.062181 -46.787999) (xy 292.120646 -46.726684) (xy 292.184674 -46.671203) (xy 292.253686 -46.62206)
			(xy 292.327056 -46.5797) (xy 292.404121 -46.544505) (xy 292.484183 -46.516796) (xy 292.566516 -46.496822)
			(xy 292.650375 -46.484765) (xy 292.735 -46.480734) (xy 292.819625 -46.484765) (xy 292.903484 -46.496822)
			(xy 292.985817 -46.516796) (xy 293.065879 -46.544505) (xy 293.142944 -46.5797) (xy 293.216314 -46.62206)
			(xy 293.285326 -46.671203) (xy 293.349354 -46.726684) (xy 293.407819 -46.787999) (xy 293.46019 -46.854595)
			(xy 293.505993 -46.925867) (xy 293.544815 -47.00117) (xy 293.576303 -47.079822) (xy 293.600171 -47.161112)
			(xy 293.616205 -47.244302) (xy 293.624258 -47.328639) (xy 293.624762 -47.371) (xy 293.624258 -47.413361)
			(xy 293.616205 -47.497698) (xy 293.600171 -47.580888) (xy 293.576303 -47.662178) (xy 293.544815 -47.74083)
			(xy 293.505993 -47.816133) (xy 293.46019 -47.887405) (xy 293.407819 -47.954001) (xy 293.349354 -48.015316)
			(xy 293.285326 -48.070797) (xy 293.216314 -48.11994) (xy 293.142944 -48.1623) (xy 293.065879 -48.197495)
			(xy 292.985817 -48.225204) (xy 292.903484 -48.245178) (xy 292.819625 -48.257235) (xy 292.735 -48.261267)
			(xy 292.650375 -48.257235) (xy 292.566516 -48.245178) (xy 292.484183 -48.225204) (xy 292.404121 -48.197495)
			(xy 292.327056 -48.1623) (xy 292.253686 -48.11994) (xy 292.184674 -48.070797) (xy 292.120646 -48.015316)
			(xy 292.062181 -47.954001) (xy 292.00981 -47.887405) (xy 291.964007 -47.816133) (xy 291.925185 -47.74083)
			(xy 291.893697 -47.662178) (xy 291.869829 -47.580888) (xy 291.853795 -47.497698) (xy 291.845742 -47.413361)
			(xy 290.85596 -47.413361) (xy 290.816221 -47.433846) (xy 290.737583 -47.465325) (xy 290.656308 -47.489186)
			(xy 290.573134 -47.505214) (xy 290.488812 -47.513262) (xy 290.44646 -47.513748) (xy 290.407308 -47.513346)
			(xy 290.329304 -47.506512) (xy 290.252204 -47.492839) (xy 290.176606 -47.472433) (xy 290.103098 -47.445452)
			(xy 290.067492 -47.429166) (xy 290.057105 -47.424931) (xy 290.034699 -47.424931) (xy 290.024312 -47.429166)
			(xy 289.988705 -47.445448) (xy 289.915189 -47.472398) (xy 289.839591 -47.492792) (xy 289.762494 -47.506472)
			(xy 289.684494 -47.513331) (xy 289.645344 -47.513748) (xy 289.602995 -47.513182) (xy 289.518681 -47.505135)
			(xy 289.435514 -47.489109) (xy 289.354246 -47.465251) (xy 289.275615 -47.433775) (xy 289.200331 -47.394967)
			(xy 289.129078 -47.349178) (xy 289.0625 -47.296824) (xy 289.0012 -47.238377) (xy 288.945734 -47.174369)
			(xy 288.896603 -47.105377) (xy 288.854253 -47.032028) (xy 288.819068 -46.954985) (xy 288.791365 -46.874946)
			(xy 288.771396 -46.792637) (xy 288.759342 -46.708801) (xy 288.755312 -46.6242) (xy 0.509016 -46.6242)
			(xy 0.509016 -48.327818) (xy 257.330448 -48.327818) (xy 257.331032 -48.281422) (xy 257.340676 -48.189134)
			(xy 257.359872 -48.09835) (xy 257.38841 -48.010057) (xy 257.406648 -47.967392) (xy 257.410445 -47.957447)
			(xy 257.410452 -47.936186) (xy 257.406648 -47.926244) (xy 257.388413 -47.883578) (xy 257.359865 -47.795287)
			(xy 257.340669 -47.704503) (xy 257.331034 -47.612214) (xy 257.330448 -47.565818) (xy 257.330952 -47.52347)
			(xy 257.339003 -47.439156) (xy 257.355032 -47.35599) (xy 257.378893 -47.274723) (xy 257.410372 -47.196093)
			(xy 257.449183 -47.120812) (xy 257.494973 -47.04956) (xy 257.547329 -46.982984) (xy 257.605777 -46.921686)
			(xy 257.669787 -46.866221) (xy 257.738779 -46.817092) (xy 257.812129 -46.774743) (xy 257.889172 -46.739559)
			(xy 257.969211 -46.711857) (xy 258.05152 -46.691889) (xy 258.135355 -46.679836) (xy 258.219956 -46.675806)
			(xy 258.304557 -46.679836) (xy 258.388392 -46.691889) (xy 258.470701 -46.711857) (xy 258.55074 -46.739559)
			(xy 258.627783 -46.774743) (xy 258.701133 -46.817092) (xy 258.770125 -46.866221) (xy 258.834135 -46.921686)
			(xy 258.892583 -46.982984) (xy 258.944939 -47.04956) (xy 258.990729 -47.120812) (xy 259.02954 -47.196093)
			(xy 259.061019 -47.274723) (xy 259.08488 -47.35599) (xy 259.100909 -47.439156) (xy 259.10896 -47.52347)
			(xy 259.109464 -47.565818) (xy 259.108891 -47.612214) (xy 259.099244 -47.704503) (xy 259.080045 -47.795286)
			(xy 259.051504 -47.88358) (xy 259.033264 -47.926244) (xy 259.029445 -47.936182) (xy 259.029452 -47.95745)
			(xy 259.033264 -47.967392) (xy 259.051512 -48.010053) (xy 259.080056 -48.098346) (xy 259.099248 -48.189131)
			(xy 259.10888 -48.281422) (xy 259.109464 -48.327818) (xy 259.10896 -48.370166) (xy 259.100909 -48.45448)
			(xy 259.08488 -48.537646) (xy 259.061019 -48.618913) (xy 259.02954 -48.697543) (xy 258.990729 -48.772824)
			(xy 258.944939 -48.844076) (xy 258.892583 -48.910652) (xy 258.834135 -48.97195) (xy 258.770125 -49.027415)
			(xy 258.701133 -49.076544) (xy 258.627783 -49.118893) (xy 258.55074 -49.154077) (xy 258.470701 -49.181779)
			(xy 258.388392 -49.201747) (xy 258.304557 -49.2138) (xy 258.219956 -49.217831) (xy 258.135355 -49.2138)
			(xy 258.05152 -49.201747) (xy 257.969211 -49.181779) (xy 257.889172 -49.154077) (xy 257.812129 -49.118893)
			(xy 257.738779 -49.076544) (xy 257.669787 -49.027415) (xy 257.605777 -48.97195) (xy 257.547329 -48.910652)
			(xy 257.494973 -48.844076) (xy 257.449183 -48.772824) (xy 257.410372 -48.697543) (xy 257.378893 -48.618913)
			(xy 257.355032 -48.537646) (xy 257.339003 -48.45448) (xy 257.330952 -48.370166) (xy 257.330448 -48.327818)
			(xy 0.509016 -48.327818) (xy 0.509016 -52.2859) (xy 43.474132 -52.2859) (xy 43.47455 -52.246133)
			(xy 43.48159 -52.166911) (xy 43.495677 -52.088634) (xy 43.516699 -52.011928) (xy 43.544486 -51.937406)
			(xy 43.561254 -51.901344) (xy 43.565585 -51.890843) (xy 43.565585 -51.868157) (xy 43.561254 -51.857656)
			(xy 43.544513 -51.821583) (xy 43.516732 -51.74706) (xy 43.495709 -51.670357) (xy 43.481612 -51.592084)
			(xy 43.474554 -51.512866) (xy 43.474132 -51.4731) (xy 43.474546 -51.432489) (xy 43.481951 -51.351605)
			(xy 43.496699 -51.271733) (xy 43.518668 -51.193537) (xy 43.547674 -51.117671) (xy 43.583475 -51.044765)
			(xy 43.625775 -50.975426) (xy 43.674219 -50.910233) (xy 43.728406 -50.849727) (xy 43.787882 -50.794414)
			(xy 43.852155 -50.744753) (xy 43.920686 -50.701159) (xy 43.992907 -50.663994) (xy 44.030392 -50.648362)
			(xy 44.040552 -50.644044) (xy 44.055792 -50.628042) (xy 44.087796 -50.534062) (xy 44.08551 -50.511964)
			(xy 44.079922 -50.502566) (xy 44.060228 -50.46832) (xy 44.026305 -50.396969) (xy 43.998845 -50.322889)
			(xy 43.978066 -50.246665) (xy 43.96413 -50.168899) (xy 43.957148 -50.090203) (xy 43.956732 -50.0507)
			(xy 43.957152 -50.009596) (xy 43.964738 -49.927738) (xy 43.979844 -49.846929) (xy 44.002342 -49.767859)
			(xy 44.03204 -49.691202) (xy 44.068685 -49.617612) (xy 44.111963 -49.547717) (xy 44.161506 -49.482114)
			(xy 44.216891 -49.421363) (xy 44.277645 -49.36598) (xy 44.34325 -49.31644) (xy 44.413147 -49.273165)
			(xy 44.486738 -49.236524) (xy 44.563397 -49.206829) (xy 44.642468 -49.184335) (xy 44.723277 -49.169232)
			(xy 44.805136 -49.16165) (xy 44.84624 -49.161192) (xy 44.891005 -49.161711) (xy 44.980087 -49.170644)
			(xy 45.06782 -49.188486) (xy 45.153315 -49.215055) (xy 45.194728 -49.232058) (xy 45.204319 -49.235623)
			(xy 45.224761 -49.235623) (xy 45.234352 -49.232058) (xy 45.275769 -49.215065) (xy 45.361266 -49.188508)
			(xy 45.448997 -49.170667) (xy 45.538076 -49.161723) (xy 45.58284 -49.161192) (xy 45.625958 -49.161716)
			(xy 45.71179 -49.170059) (xy 45.796411 -49.186672) (xy 45.879027 -49.211399) (xy 45.919136 -49.227232)
			(xy 45.928507 -49.230558) (xy 45.948373 -49.230558) (xy 45.957744 -49.227232) (xy 45.997848 -49.211383)
			(xy 46.080465 -49.186656) (xy 46.165087 -49.170043) (xy 46.250921 -49.161699) (xy 46.29404 -49.161192)
			(xy 46.336388 -49.161696) (xy 46.420702 -49.169747) (xy 46.503868 -49.185776) (xy 46.585135 -49.209637)
			(xy 46.663765 -49.241116) (xy 46.739046 -49.279927) (xy 46.810298 -49.325717) (xy 46.876874 -49.378073)
			(xy 46.938172 -49.436521) (xy 46.993637 -49.500531) (xy 47.042766 -49.569523) (xy 47.085115 -49.642873)
			(xy 47.120299 -49.719916) (xy 47.148001 -49.799955) (xy 47.167969 -49.882264) (xy 47.180022 -49.966099)
			(xy 47.184053 -50.0507) (xy 47.180022 -50.135301) (xy 47.167969 -50.219136) (xy 47.148001 -50.301445)
			(xy 47.120299 -50.381484) (xy 47.085115 -50.458527) (xy 47.042766 -50.531877) (xy 46.993637 -50.600869)
			(xy 46.938172 -50.664879) (xy 46.876874 -50.723327) (xy 46.810298 -50.775683) (xy 46.739046 -50.821473)
			(xy 46.663765 -50.860284) (xy 46.585135 -50.891763) (xy 46.503868 -50.915624) (xy 46.420702 -50.931653)
			(xy 46.336388 -50.939704) (xy 46.29404 -50.940208) (xy 46.250922 -50.939691) (xy 46.165089 -50.931346)
			(xy 46.080468 -50.914731) (xy 45.997853 -50.890002) (xy 45.957744 -50.874168) (xy 45.948373 -50.870842)
			(xy 45.928507 -50.870842) (xy 45.919136 -50.874168) (xy 45.879023 -50.889992) (xy 45.796409 -50.914725)
			(xy 45.71179 -50.931346) (xy 45.625958 -50.939697) (xy 45.58284 -50.940208) (xy 45.538075 -50.939695)
			(xy 45.448993 -50.930761) (xy 45.36126 -50.912917) (xy 45.275765 -50.886346) (xy 45.234352 -50.869342)
			(xy 45.224761 -50.865777) (xy 45.204319 -50.865777) (xy 45.194728 -50.869342) (xy 45.179488 -50.875438)
			(xy 45.169328 -50.879756) (xy 45.154088 -50.895758) (xy 45.122084 -50.989738) (xy 45.12437 -51.011836)
			(xy 45.129958 -51.021234) (xy 45.14965 -51.055481) (xy 45.183574 -51.126832) (xy 45.211034 -51.200912)
			(xy 45.231814 -51.277135) (xy 45.24575 -51.354901) (xy 45.252732 -51.433597) (xy 45.253148 -51.4731)
			(xy 45.252732 -51.512867) (xy 45.245691 -51.59209) (xy 45.231604 -51.670366) (xy 45.210582 -51.747072)
			(xy 45.182794 -51.821594) (xy 45.166026 -51.857656) (xy 45.161691 -51.868157) (xy 45.161691 -51.890843)
			(xy 45.166026 -51.901344) (xy 45.182773 -51.937415) (xy 45.210551 -52.011938) (xy 45.231572 -52.088642)
			(xy 45.245668 -52.166915) (xy 45.252726 -52.246134) (xy 45.253148 -52.2859) (xy 45.252644 -52.328248)
			(xy 45.244593 -52.412562) (xy 45.228564 -52.495728) (xy 45.204703 -52.576995) (xy 45.173224 -52.655625)
			(xy 45.134413 -52.730906) (xy 45.088623 -52.802158) (xy 45.036267 -52.868734) (xy 44.986526 -52.9209)
			(xy 46.166532 -52.9209) (xy 46.167111 -52.874504) (xy 46.176757 -52.782216) (xy 46.195954 -52.691432)
			(xy 46.224493 -52.603139) (xy 46.242732 -52.560474) (xy 46.246541 -52.550532) (xy 46.246541 -52.529268)
			(xy 46.242732 -52.519326) (xy 46.22449 -52.476663) (xy 46.195944 -52.388371) (xy 46.176751 -52.297586)
			(xy 46.167117 -52.205296) (xy 46.166532 -52.1589) (xy 46.167036 -52.116552) (xy 46.175087 -52.032238)
			(xy 46.191116 -51.949072) (xy 46.214977 -51.867805) (xy 46.246456 -51.789175) (xy 46.285267 -51.713894)
			(xy 46.331057 -51.642642) (xy 46.383413 -51.576066) (xy 46.441861 -51.514768) (xy 46.505871 -51.459303)
			(xy 46.574863 -51.410174) (xy 46.648213 -51.367825) (xy 46.725256 -51.332641) (xy 46.805295 -51.304939)
			(xy 46.887604 -51.284971) (xy 46.971439 -51.272918) (xy 47.05604 -51.268888) (xy 47.140641 -51.272918)
			(xy 47.224476 -51.284971) (xy 47.306785 -51.304939) (xy 47.386824 -51.332641) (xy 47.463867 -51.367825)
			(xy 47.537217 -51.410174) (xy 47.606209 -51.459303) (xy 47.670219 -51.514768) (xy 47.728667 -51.576066)
			(xy 47.781023 -51.642642) (xy 47.826813 -51.713894) (xy 47.865624 -51.789175) (xy 47.897103 -51.867805)
			(xy 47.920964 -51.949072) (xy 47.936993 -52.032238) (xy 47.945044 -52.116552) (xy 47.945548 -52.1589)
			(xy 47.94497 -52.205296) (xy 47.935324 -52.297584) (xy 47.916127 -52.388368) (xy 47.887587 -52.476662)
			(xy 47.869348 -52.519326) (xy 47.86554 -52.529268) (xy 47.86554 -52.550532) (xy 47.869348 -52.560474)
			(xy 47.887595 -52.603135) (xy 47.916138 -52.691428) (xy 47.93533 -52.782213) (xy 47.944963 -52.874504)
			(xy 47.945068 -52.8828) (xy 48.427132 -52.8828) (xy 48.427711 -52.836404) (xy 48.437357 -52.744116)
			(xy 48.456554 -52.653332) (xy 48.485093 -52.565039) (xy 48.503332 -52.522374) (xy 48.507141 -52.512432)
			(xy 48.507141 -52.491168) (xy 48.503332 -52.481226) (xy 48.48509 -52.438563) (xy 48.456544 -52.350271)
			(xy 48.437351 -52.259486) (xy 48.427717 -52.167196) (xy 48.427132 -52.1208) (xy 48.427552 -52.079696)
			(xy 48.435138 -51.997838) (xy 48.450244 -51.917029) (xy 48.472742 -51.837959) (xy 48.50244 -51.761302)
			(xy 48.539085 -51.687712) (xy 48.582363 -51.617817) (xy 48.631906 -51.552214) (xy 48.687291 -51.491463)
			(xy 48.748045 -51.43608) (xy 48.81365 -51.38654) (xy 48.883547 -51.343265) (xy 48.957138 -51.306624)
			(xy 49.033797 -51.276929) (xy 49.112868 -51.254435) (xy 49.193677 -51.239332) (xy 49.275536 -51.23175)
			(xy 49.31664 -51.231292) (xy 49.363035 -51.231896) (xy 49.455323 -51.241535) (xy 49.546107 -51.260725)
			(xy 49.634401 -51.289257) (xy 49.677066 -51.307492) (xy 49.687008 -51.311298) (xy 49.708272 -51.311298)
			(xy 49.718214 -51.307492) (xy 49.760871 -51.289234) (xy 49.849165 -51.260693) (xy 49.939952 -51.241504)
			(xy 50.032243 -51.231875) (xy 50.07864 -51.231292) (xy 50.125035 -51.231896) (xy 50.217323 -51.241535)
			(xy 50.308107 -51.260725) (xy 50.396401 -51.289257) (xy 50.439066 -51.307492) (xy 50.449008 -51.311298)
			(xy 50.470272 -51.311298) (xy 50.480214 -51.307492) (xy 50.522871 -51.289234) (xy 50.611165 -51.260693)
			(xy 50.701952 -51.241504) (xy 50.794243 -51.231875) (xy 50.84064 -51.231292) (xy 50.881743 -51.231728)
			(xy 50.963598 -51.239317) (xy 51.044404 -51.254426) (xy 51.123472 -51.276925) (xy 51.200126 -51.306624)
			(xy 51.273713 -51.343269) (xy 51.343605 -51.386547) (xy 51.409206 -51.436089) (xy 51.469955 -51.491473)
			(xy 51.525336 -51.552225) (xy 51.574875 -51.617828) (xy 51.61815 -51.687722) (xy 51.654792 -51.761311)
			(xy 51.684487 -51.837966) (xy 51.706984 -51.917034) (xy 51.722089 -51.997841) (xy 51.729673 -52.079697)
			(xy 51.730148 -52.1208) (xy 51.72957 -52.167196) (xy 51.719924 -52.259484) (xy 51.706282 -52.324)
			(xy 70.992492 -52.324) (xy 70.99288 -52.285716) (xy 70.999419 -52.209427) (xy 71.0125 -52.133985)
			(xy 71.032027 -52.059948) (xy 71.044562 -52.023772) (xy 71.047213 -52.015335) (xy 71.047213 -51.997665)
			(xy 71.044562 -51.989228) (xy 71.032037 -51.95305) (xy 71.012529 -51.87901) (xy 70.999449 -51.803569)
			(xy 70.992894 -51.727283) (xy 70.992492 -51.689) (xy 70.992943 -51.648953) (xy 71.000117 -51.569181)
			(xy 71.014434 -51.490378) (xy 71.035778 -51.413181) (xy 71.063976 -51.338215) (xy 71.0988 -51.266088)
			(xy 71.139968 -51.197385) (xy 71.187146 -51.13266) (xy 71.213218 -51.10226) (xy 71.218983 -51.095171)
			(xy 71.225495 -51.078114) (xy 71.225918 -51.068986) (xy 71.225918 -51.039014) (xy 71.225484 -51.029891)
			(xy 71.218964 -51.012841) (xy 71.213218 -51.00574) (xy 71.187158 -50.975329) (xy 71.139979 -50.910606)
			(xy 71.098809 -50.841904) (xy 71.063981 -50.769779) (xy 71.035779 -50.694815) (xy 71.014429 -50.61762)
			(xy 71.000105 -50.538818) (xy 70.992923 -50.459047) (xy 70.992492 -50.419) (xy 70.99288 -50.380716)
			(xy 70.999419 -50.304427) (xy 71.0125 -50.228985) (xy 71.032027 -50.154948) (xy 71.044562 -50.118772)
			(xy 71.047213 -50.110335) (xy 71.047213 -50.092665) (xy 71.044562 -50.084228) (xy 71.032037 -50.04805)
			(xy 71.012529 -49.97401) (xy 70.999449 -49.898569) (xy 70.992894 -49.822283) (xy 70.992492 -49.784)
			(xy 70.992996 -49.741652) (xy 71.001047 -49.657338) (xy 71.017076 -49.574172) (xy 71.040937 -49.492905)
			(xy 71.072416 -49.414275) (xy 71.111227 -49.338994) (xy 71.157017 -49.267742) (xy 71.209373 -49.201166)
			(xy 71.267821 -49.139868) (xy 71.331831 -49.084403) (xy 71.400823 -49.035274) (xy 71.474173 -48.992925)
			(xy 71.551216 -48.957741) (xy 71.631255 -48.930039) (xy 71.713564 -48.910071) (xy 71.797399 -48.898018)
			(xy 71.882 -48.893988) (xy 71.966601 -48.898018) (xy 72.050436 -48.910071) (xy 72.132745 -48.930039)
			(xy 72.212784 -48.957741) (xy 72.289827 -48.992925) (xy 72.363177 -49.035274) (xy 72.432169 -49.084403)
			(xy 72.496179 -49.139868) (xy 72.554627 -49.201166) (xy 72.606983 -49.267742) (xy 72.652773 -49.338994)
			(xy 72.691584 -49.414275) (xy 72.723063 -49.492905) (xy 72.746924 -49.574172) (xy 72.762953 -49.657338)
			(xy 72.771004 -49.741652) (xy 72.771508 -49.784) (xy 72.77112 -49.822284) (xy 72.764581 -49.898573)
			(xy 72.7515 -49.974015) (xy 72.731973 -50.048052) (xy 72.719438 -50.084228) (xy 72.716787 -50.092665)
			(xy 72.716787 -50.110335) (xy 72.719438 -50.118772) (xy 72.731963 -50.15495) (xy 72.751471 -50.22899)
			(xy 72.764551 -50.304431) (xy 72.771106 -50.380717) (xy 72.771508 -50.419) (xy 72.771057 -50.459047)
			(xy 72.763883 -50.538819) (xy 72.749566 -50.617622) (xy 72.728222 -50.694819) (xy 72.700024 -50.769785)
			(xy 72.6652 -50.841912) (xy 72.624032 -50.910615) (xy 72.576854 -50.97534) (xy 72.550782 -51.00574)
			(xy 72.545017 -51.012829) (xy 72.538505 -51.029886) (xy 72.538082 -51.039014) (xy 72.538082 -51.068986)
			(xy 72.538516 -51.078109) (xy 72.545036 -51.095159) (xy 72.550782 -51.10226) (xy 72.576842 -51.132671)
			(xy 72.624021 -51.197394) (xy 72.665191 -51.266096) (xy 72.700019 -51.338221) (xy 72.728221 -51.413185)
			(xy 72.749571 -51.49038) (xy 72.763895 -51.569182) (xy 72.771077 -51.648953) (xy 72.771508 -51.689)
			(xy 72.77112 -51.727284) (xy 72.764581 -51.803573) (xy 72.7515 -51.879015) (xy 72.731973 -51.953052)
			(xy 72.719438 -51.989228) (xy 72.716787 -51.997665) (xy 72.716787 -52.015335) (xy 72.719438 -52.023772)
			(xy 72.731963 -52.05995) (xy 72.751471 -52.13399) (xy 72.764551 -52.209431) (xy 72.771106 -52.285717)
			(xy 72.771508 -52.324) (xy 76.453492 -52.324) (xy 76.45388 -52.285716) (xy 76.460419 -52.209427)
			(xy 76.4735 -52.133985) (xy 76.493027 -52.059948) (xy 76.505562 -52.023772) (xy 76.508213 -52.015335)
			(xy 76.508213 -51.997665) (xy 76.505562 -51.989228) (xy 76.493037 -51.95305) (xy 76.473529 -51.87901)
			(xy 76.460449 -51.803569) (xy 76.453894 -51.727283) (xy 76.453492 -51.689) (xy 76.453943 -51.648953)
			(xy 76.461117 -51.569181) (xy 76.475434 -51.490378) (xy 76.496778 -51.413181) (xy 76.524976 -51.338215)
			(xy 76.5598 -51.266088) (xy 76.600968 -51.197385) (xy 76.648146 -51.13266) (xy 76.674218 -51.10226)
			(xy 76.679983 -51.095171) (xy 76.686495 -51.078114) (xy 76.686918 -51.068986) (xy 76.686918 -51.039014)
			(xy 76.686484 -51.029891) (xy 76.679964 -51.012841) (xy 76.674218 -51.00574) (xy 76.648158 -50.975329)
			(xy 76.600979 -50.910606) (xy 76.559809 -50.841904) (xy 76.524981 -50.769779) (xy 76.496779 -50.694815)
			(xy 76.475429 -50.61762) (xy 76.461105 -50.538818) (xy 76.453923 -50.459047) (xy 76.453492 -50.419)
			(xy 76.45388 -50.380716) (xy 76.460419 -50.304427) (xy 76.4735 -50.228985) (xy 76.493027 -50.154948)
			(xy 76.505562 -50.118772) (xy 76.508213 -50.110335) (xy 76.508213 -50.092665) (xy 76.505562 -50.084228)
			(xy 76.493037 -50.04805) (xy 76.473529 -49.97401) (xy 76.460449 -49.898569) (xy 76.453894 -49.822283)
			(xy 76.453492 -49.784) (xy 76.453996 -49.741652) (xy 76.462047 -49.657338) (xy 76.478076 -49.574172)
			(xy 76.501937 -49.492905) (xy 76.533416 -49.414275) (xy 76.572227 -49.338994) (xy 76.618017 -49.267742)
			(xy 76.670373 -49.201166) (xy 76.728821 -49.139868) (xy 76.792831 -49.084403) (xy 76.861823 -49.035274)
			(xy 76.935173 -48.992925) (xy 77.012216 -48.957741) (xy 77.092255 -48.930039) (xy 77.174564 -48.910071)
			(xy 77.258399 -48.898018) (xy 77.343 -48.893988) (xy 77.427601 -48.898018) (xy 77.511436 -48.910071)
			(xy 77.593745 -48.930039) (xy 77.673784 -48.957741) (xy 77.750827 -48.992925) (xy 77.824177 -49.035274)
			(xy 77.893169 -49.084403) (xy 77.957179 -49.139868) (xy 78.015627 -49.201166) (xy 78.067983 -49.267742)
			(xy 78.113773 -49.338994) (xy 78.152584 -49.414275) (xy 78.184063 -49.492905) (xy 78.207924 -49.574172)
			(xy 78.223953 -49.657338) (xy 78.232004 -49.741652) (xy 78.232508 -49.784) (xy 78.23212 -49.822284)
			(xy 78.225581 -49.898573) (xy 78.2125 -49.974015) (xy 78.192973 -50.048052) (xy 78.180438 -50.084228)
			(xy 78.177787 -50.092665) (xy 78.177787 -50.110335) (xy 78.180438 -50.118772) (xy 78.192963 -50.15495)
			(xy 78.212471 -50.22899) (xy 78.225551 -50.304431) (xy 78.232106 -50.380717) (xy 78.232508 -50.419)
			(xy 78.232057 -50.459047) (xy 78.224883 -50.538819) (xy 78.210566 -50.617622) (xy 78.189222 -50.694819)
			(xy 78.161024 -50.769785) (xy 78.1262 -50.841912) (xy 78.085032 -50.910615) (xy 78.037854 -50.97534)
			(xy 78.011782 -51.00574) (xy 78.006017 -51.012829) (xy 77.999505 -51.029886) (xy 77.999082 -51.039014)
			(xy 77.999082 -51.068986) (xy 77.999516 -51.078109) (xy 78.006036 -51.095159) (xy 78.011782 -51.10226)
			(xy 78.037842 -51.132671) (xy 78.085021 -51.197394) (xy 78.126191 -51.266096) (xy 78.161019 -51.338221)
			(xy 78.189221 -51.413185) (xy 78.210571 -51.49038) (xy 78.224895 -51.569182) (xy 78.232077 -51.648953)
			(xy 78.232508 -51.689) (xy 78.23212 -51.727284) (xy 78.225581 -51.803573) (xy 78.2125 -51.879015)
			(xy 78.192973 -51.953052) (xy 78.180438 -51.989228) (xy 78.177787 -51.997665) (xy 78.177787 -52.015335)
			(xy 78.180438 -52.023772) (xy 78.192963 -52.05995) (xy 78.212471 -52.13399) (xy 78.225551 -52.209431)
			(xy 78.232106 -52.285717) (xy 78.232508 -52.324) (xy 81.914492 -52.324) (xy 81.91488 -52.285716)
			(xy 81.921419 -52.209427) (xy 81.9345 -52.133985) (xy 81.954027 -52.059948) (xy 81.966562 -52.023772)
			(xy 81.969213 -52.015335) (xy 81.969213 -51.997665) (xy 81.966562 -51.989228) (xy 81.954037 -51.95305)
			(xy 81.934529 -51.87901) (xy 81.921449 -51.803569) (xy 81.914894 -51.727283) (xy 81.914492 -51.689)
			(xy 81.914943 -51.648953) (xy 81.922117 -51.569181) (xy 81.936434 -51.490378) (xy 81.957778 -51.413181)
			(xy 81.985976 -51.338215) (xy 82.0208 -51.266088) (xy 82.061968 -51.197385) (xy 82.109146 -51.13266)
			(xy 82.135218 -51.10226) (xy 82.140983 -51.095171) (xy 82.147495 -51.078114) (xy 82.147918 -51.068986)
			(xy 82.147918 -51.039014) (xy 82.147484 -51.029891) (xy 82.140964 -51.012841) (xy 82.135218 -51.00574)
			(xy 82.109158 -50.975329) (xy 82.061979 -50.910606) (xy 82.020809 -50.841904) (xy 81.985981 -50.769779)
			(xy 81.957779 -50.694815) (xy 81.936429 -50.61762) (xy 81.922105 -50.538818) (xy 81.914923 -50.459047)
			(xy 81.914492 -50.419) (xy 81.91488 -50.380716) (xy 81.921419 -50.304427) (xy 81.9345 -50.228985)
			(xy 81.954027 -50.154948) (xy 81.966562 -50.118772) (xy 81.969213 -50.110335) (xy 81.969213 -50.092665)
			(xy 81.966562 -50.084228) (xy 81.954037 -50.04805) (xy 81.934529 -49.97401) (xy 81.921449 -49.898569)
			(xy 81.914894 -49.822283) (xy 81.914492 -49.784) (xy 81.914996 -49.741652) (xy 81.923047 -49.657338)
			(xy 81.939076 -49.574172) (xy 81.962937 -49.492905) (xy 81.994416 -49.414275) (xy 82.033227 -49.338994)
			(xy 82.079017 -49.267742) (xy 82.131373 -49.201166) (xy 82.189821 -49.139868) (xy 82.253831 -49.084403)
			(xy 82.322823 -49.035274) (xy 82.396173 -48.992925) (xy 82.473216 -48.957741) (xy 82.553255 -48.930039)
			(xy 82.635564 -48.910071) (xy 82.719399 -48.898018) (xy 82.804 -48.893988) (xy 82.888601 -48.898018)
			(xy 82.972436 -48.910071) (xy 83.054745 -48.930039) (xy 83.134784 -48.957741) (xy 83.211827 -48.992925)
			(xy 83.285177 -49.035274) (xy 83.354169 -49.084403) (xy 83.418179 -49.139868) (xy 83.476627 -49.201166)
			(xy 83.528983 -49.267742) (xy 83.574773 -49.338994) (xy 83.613584 -49.414275) (xy 83.645063 -49.492905)
			(xy 83.668924 -49.574172) (xy 83.684953 -49.657338) (xy 83.693004 -49.741652) (xy 83.693508 -49.784)
			(xy 83.69312 -49.822284) (xy 83.686581 -49.898573) (xy 83.6735 -49.974015) (xy 83.653973 -50.048052)
			(xy 83.641438 -50.084228) (xy 83.638787 -50.092665) (xy 83.638787 -50.110335) (xy 83.641438 -50.118772)
			(xy 83.653963 -50.15495) (xy 83.673471 -50.22899) (xy 83.686551 -50.304431) (xy 83.693106 -50.380717)
			(xy 83.693508 -50.419) (xy 83.693057 -50.459047) (xy 83.685883 -50.538819) (xy 83.671566 -50.617622)
			(xy 83.650222 -50.694819) (xy 83.622024 -50.769785) (xy 83.5872 -50.841912) (xy 83.546032 -50.910615)
			(xy 83.498854 -50.97534) (xy 83.472782 -51.00574) (xy 83.467017 -51.012829) (xy 83.460505 -51.029886)
			(xy 83.460082 -51.039014) (xy 83.460082 -51.068986) (xy 83.460516 -51.078109) (xy 83.467036 -51.095159)
			(xy 83.472782 -51.10226) (xy 83.498842 -51.132671) (xy 83.546021 -51.197394) (xy 83.587191 -51.266096)
			(xy 83.622019 -51.338221) (xy 83.650221 -51.413185) (xy 83.671571 -51.49038) (xy 83.685895 -51.569182)
			(xy 83.693077 -51.648953) (xy 83.693508 -51.689) (xy 83.69312 -51.727284) (xy 83.686581 -51.803573)
			(xy 83.6735 -51.879015) (xy 83.653973 -51.953052) (xy 83.641438 -51.989228) (xy 83.638787 -51.997665)
			(xy 83.638787 -52.015335) (xy 83.641438 -52.023772) (xy 83.653963 -52.05995) (xy 83.673471 -52.13399)
			(xy 83.686551 -52.209431) (xy 83.693106 -52.285717) (xy 83.693508 -52.324) (xy 87.375492 -52.324)
			(xy 87.37588 -52.285716) (xy 87.382419 -52.209427) (xy 87.3955 -52.133985) (xy 87.415027 -52.059948)
			(xy 87.427562 -52.023772) (xy 87.430213 -52.015335) (xy 87.430213 -51.997665) (xy 87.427562 -51.989228)
			(xy 87.415037 -51.95305) (xy 87.395529 -51.87901) (xy 87.382449 -51.803569) (xy 87.375894 -51.727283)
			(xy 87.375492 -51.689) (xy 87.375943 -51.648953) (xy 87.383117 -51.569181) (xy 87.397434 -51.490378)
			(xy 87.418778 -51.413181) (xy 87.446976 -51.338215) (xy 87.4818 -51.266088) (xy 87.522968 -51.197385)
			(xy 87.570146 -51.13266) (xy 87.596218 -51.10226) (xy 87.601983 -51.095171) (xy 87.608495 -51.078114)
			(xy 87.608918 -51.068986) (xy 87.608918 -51.039014) (xy 87.608484 -51.029891) (xy 87.601964 -51.012841)
			(xy 87.596218 -51.00574) (xy 87.570158 -50.975329) (xy 87.522979 -50.910606) (xy 87.481809 -50.841904)
			(xy 87.446981 -50.769779) (xy 87.418779 -50.694815) (xy 87.397429 -50.61762) (xy 87.383105 -50.538818)
			(xy 87.375923 -50.459047) (xy 87.375492 -50.419) (xy 87.37588 -50.380716) (xy 87.382419 -50.304427)
			(xy 87.3955 -50.228985) (xy 87.415027 -50.154948) (xy 87.427562 -50.118772) (xy 87.430213 -50.110335)
			(xy 87.430213 -50.092665) (xy 87.427562 -50.084228) (xy 87.415037 -50.04805) (xy 87.395529 -49.97401)
			(xy 87.382449 -49.898569) (xy 87.375894 -49.822283) (xy 87.375492 -49.784) (xy 87.375996 -49.741652)
			(xy 87.384047 -49.657338) (xy 87.400076 -49.574172) (xy 87.423937 -49.492905) (xy 87.455416 -49.414275)
			(xy 87.494227 -49.338994) (xy 87.540017 -49.267742) (xy 87.592373 -49.201166) (xy 87.650821 -49.139868)
			(xy 87.714831 -49.084403) (xy 87.783823 -49.035274) (xy 87.857173 -48.992925) (xy 87.934216 -48.957741)
			(xy 88.014255 -48.930039) (xy 88.096564 -48.910071) (xy 88.180399 -48.898018) (xy 88.265 -48.893988)
			(xy 88.349601 -48.898018) (xy 88.433436 -48.910071) (xy 88.515745 -48.930039) (xy 88.595784 -48.957741)
			(xy 88.672827 -48.992925) (xy 88.746177 -49.035274) (xy 88.815169 -49.084403) (xy 88.879179 -49.139868)
			(xy 88.937627 -49.201166) (xy 88.989983 -49.267742) (xy 89.035773 -49.338994) (xy 89.074584 -49.414275)
			(xy 89.106063 -49.492905) (xy 89.129924 -49.574172) (xy 89.145953 -49.657338) (xy 89.154004 -49.741652)
			(xy 89.154508 -49.784) (xy 89.15412 -49.822284) (xy 89.147581 -49.898573) (xy 89.1345 -49.974015)
			(xy 89.114973 -50.048052) (xy 89.102438 -50.084228) (xy 89.099787 -50.092665) (xy 89.099787 -50.110335)
			(xy 89.102438 -50.118772) (xy 89.114963 -50.15495) (xy 89.134471 -50.22899) (xy 89.147551 -50.304431)
			(xy 89.154106 -50.380717) (xy 89.154508 -50.419) (xy 89.154057 -50.459047) (xy 89.146883 -50.538819)
			(xy 89.132566 -50.617622) (xy 89.111222 -50.694819) (xy 89.083024 -50.769785) (xy 89.0482 -50.841912)
			(xy 89.007032 -50.910615) (xy 88.959854 -50.97534) (xy 88.933782 -51.00574) (xy 88.928017 -51.012829)
			(xy 88.921505 -51.029886) (xy 88.921082 -51.039014) (xy 88.921082 -51.068986) (xy 88.921516 -51.078109)
			(xy 88.928036 -51.095159) (xy 88.933782 -51.10226) (xy 88.959842 -51.132671) (xy 89.007021 -51.197394)
			(xy 89.048191 -51.266096) (xy 89.083019 -51.338221) (xy 89.111221 -51.413185) (xy 89.132571 -51.49038)
			(xy 89.146895 -51.569182) (xy 89.154077 -51.648953) (xy 89.154508 -51.689) (xy 89.15412 -51.727284)
			(xy 89.147581 -51.803573) (xy 89.1345 -51.879015) (xy 89.114973 -51.953052) (xy 89.102438 -51.989228)
			(xy 89.099787 -51.997665) (xy 89.099787 -52.015335) (xy 89.102438 -52.023772) (xy 89.114963 -52.05995)
			(xy 89.134471 -52.13399) (xy 89.147551 -52.209431) (xy 89.154106 -52.285717) (xy 89.154508 -52.324)
			(xy 92.836492 -52.324) (xy 92.83688 -52.285716) (xy 92.843419 -52.209427) (xy 92.8565 -52.133985)
			(xy 92.876027 -52.059948) (xy 92.888562 -52.023772) (xy 92.891213 -52.015335) (xy 92.891213 -51.997665)
			(xy 92.888562 -51.989228) (xy 92.876037 -51.95305) (xy 92.856529 -51.87901) (xy 92.843449 -51.803569)
			(xy 92.836894 -51.727283) (xy 92.836492 -51.689) (xy 92.836943 -51.648953) (xy 92.844117 -51.569181)
			(xy 92.858434 -51.490378) (xy 92.879778 -51.413181) (xy 92.907976 -51.338215) (xy 92.9428 -51.266088)
			(xy 92.983968 -51.197385) (xy 93.031146 -51.13266) (xy 93.057218 -51.10226) (xy 93.062983 -51.095171)
			(xy 93.069495 -51.078114) (xy 93.069918 -51.068986) (xy 93.069918 -51.039014) (xy 93.069484 -51.029891)
			(xy 93.062964 -51.012841) (xy 93.057218 -51.00574) (xy 93.031158 -50.975329) (xy 92.983979 -50.910606)
			(xy 92.942809 -50.841904) (xy 92.907981 -50.769779) (xy 92.879779 -50.694815) (xy 92.858429 -50.61762)
			(xy 92.844105 -50.538818) (xy 92.836923 -50.459047) (xy 92.836492 -50.419) (xy 92.83688 -50.380716)
			(xy 92.843419 -50.304427) (xy 92.8565 -50.228985) (xy 92.876027 -50.154948) (xy 92.888562 -50.118772)
			(xy 92.891213 -50.110335) (xy 92.891213 -50.092665) (xy 92.888562 -50.084228) (xy 92.876037 -50.04805)
			(xy 92.856529 -49.97401) (xy 92.843449 -49.898569) (xy 92.836894 -49.822283) (xy 92.836492 -49.784)
			(xy 92.836996 -49.741652) (xy 92.845047 -49.657338) (xy 92.861076 -49.574172) (xy 92.884937 -49.492905)
			(xy 92.916416 -49.414275) (xy 92.955227 -49.338994) (xy 93.001017 -49.267742) (xy 93.053373 -49.201166)
			(xy 93.111821 -49.139868) (xy 93.175831 -49.084403) (xy 93.244823 -49.035274) (xy 93.318173 -48.992925)
			(xy 93.395216 -48.957741) (xy 93.475255 -48.930039) (xy 93.557564 -48.910071) (xy 93.641399 -48.898018)
			(xy 93.726 -48.893988) (xy 93.810601 -48.898018) (xy 93.894436 -48.910071) (xy 93.976745 -48.930039)
			(xy 94.056784 -48.957741) (xy 94.133827 -48.992925) (xy 94.207177 -49.035274) (xy 94.276169 -49.084403)
			(xy 94.340179 -49.139868) (xy 94.398627 -49.201166) (xy 94.450983 -49.267742) (xy 94.496773 -49.338994)
			(xy 94.535584 -49.414275) (xy 94.567063 -49.492905) (xy 94.590924 -49.574172) (xy 94.606953 -49.657338)
			(xy 94.615004 -49.741652) (xy 94.615508 -49.784) (xy 94.61512 -49.822284) (xy 94.608581 -49.898573)
			(xy 94.5955 -49.974015) (xy 94.575973 -50.048052) (xy 94.563438 -50.084228) (xy 94.560787 -50.092665)
			(xy 94.560787 -50.110335) (xy 94.563438 -50.118772) (xy 94.575963 -50.15495) (xy 94.595471 -50.22899)
			(xy 94.608551 -50.304431) (xy 94.615106 -50.380717) (xy 94.615508 -50.419) (xy 94.615057 -50.459047)
			(xy 94.607883 -50.538819) (xy 94.593566 -50.617622) (xy 94.572222 -50.694819) (xy 94.544024 -50.769785)
			(xy 94.5092 -50.841912) (xy 94.468032 -50.910615) (xy 94.420854 -50.97534) (xy 94.394782 -51.00574)
			(xy 94.389017 -51.012829) (xy 94.382505 -51.029886) (xy 94.382082 -51.039014) (xy 94.382082 -51.068986)
			(xy 94.382516 -51.078109) (xy 94.389036 -51.095159) (xy 94.394782 -51.10226) (xy 94.420842 -51.132671)
			(xy 94.468021 -51.197394) (xy 94.509191 -51.266096) (xy 94.544019 -51.338221) (xy 94.572221 -51.413185)
			(xy 94.593571 -51.49038) (xy 94.607895 -51.569182) (xy 94.615077 -51.648953) (xy 94.615508 -51.689)
			(xy 94.61512 -51.727284) (xy 94.608581 -51.803573) (xy 94.5955 -51.879015) (xy 94.575973 -51.953052)
			(xy 94.563438 -51.989228) (xy 94.560787 -51.997665) (xy 94.560787 -52.015335) (xy 94.563438 -52.023772)
			(xy 94.575963 -52.05995) (xy 94.595471 -52.13399) (xy 94.608551 -52.209431) (xy 94.615106 -52.285717)
			(xy 94.615508 -52.324) (xy 98.297492 -52.324) (xy 98.29788 -52.285716) (xy 98.304419 -52.209427)
			(xy 98.3175 -52.133985) (xy 98.337027 -52.059948) (xy 98.349562 -52.023772) (xy 98.352213 -52.015335)
			(xy 98.352213 -51.997665) (xy 98.349562 -51.989228) (xy 98.337037 -51.95305) (xy 98.317529 -51.87901)
			(xy 98.304449 -51.803569) (xy 98.297894 -51.727283) (xy 98.297492 -51.689) (xy 98.297943 -51.648953)
			(xy 98.305117 -51.569181) (xy 98.319434 -51.490378) (xy 98.340778 -51.413181) (xy 98.368976 -51.338215)
			(xy 98.4038 -51.266088) (xy 98.444968 -51.197385) (xy 98.492146 -51.13266) (xy 98.518218 -51.10226)
			(xy 98.523983 -51.095171) (xy 98.530495 -51.078114) (xy 98.530918 -51.068986) (xy 98.530918 -51.039014)
			(xy 98.530484 -51.029891) (xy 98.523964 -51.012841) (xy 98.518218 -51.00574) (xy 98.492158 -50.975329)
			(xy 98.444979 -50.910606) (xy 98.403809 -50.841904) (xy 98.368981 -50.769779) (xy 98.340779 -50.694815)
			(xy 98.319429 -50.61762) (xy 98.305105 -50.538818) (xy 98.297923 -50.459047) (xy 98.297492 -50.419)
			(xy 98.29788 -50.380716) (xy 98.304419 -50.304427) (xy 98.3175 -50.228985) (xy 98.337027 -50.154948)
			(xy 98.349562 -50.118772) (xy 98.352213 -50.110335) (xy 98.352213 -50.092665) (xy 98.349562 -50.084228)
			(xy 98.337037 -50.04805) (xy 98.317529 -49.97401) (xy 98.304449 -49.898569) (xy 98.297894 -49.822283)
			(xy 98.297492 -49.784) (xy 98.297996 -49.741652) (xy 98.306047 -49.657338) (xy 98.322076 -49.574172)
			(xy 98.345937 -49.492905) (xy 98.377416 -49.414275) (xy 98.416227 -49.338994) (xy 98.462017 -49.267742)
			(xy 98.514373 -49.201166) (xy 98.572821 -49.139868) (xy 98.636831 -49.084403) (xy 98.705823 -49.035274)
			(xy 98.779173 -48.992925) (xy 98.856216 -48.957741) (xy 98.936255 -48.930039) (xy 99.018564 -48.910071)
			(xy 99.102399 -48.898018) (xy 99.187 -48.893988) (xy 99.271601 -48.898018) (xy 99.355436 -48.910071)
			(xy 99.437745 -48.930039) (xy 99.517784 -48.957741) (xy 99.594827 -48.992925) (xy 99.668177 -49.035274)
			(xy 99.737169 -49.084403) (xy 99.801179 -49.139868) (xy 99.859627 -49.201166) (xy 99.911983 -49.267742)
			(xy 99.957773 -49.338994) (xy 99.996584 -49.414275) (xy 100.028063 -49.492905) (xy 100.051924 -49.574172)
			(xy 100.067953 -49.657338) (xy 100.076004 -49.741652) (xy 100.076508 -49.784) (xy 100.07612 -49.822284)
			(xy 100.069581 -49.898573) (xy 100.0565 -49.974015) (xy 100.036973 -50.048052) (xy 100.024438 -50.084228)
			(xy 100.021787 -50.092665) (xy 100.021787 -50.110335) (xy 100.024438 -50.118772) (xy 100.036963 -50.15495)
			(xy 100.056471 -50.22899) (xy 100.069551 -50.304431) (xy 100.076106 -50.380717) (xy 100.076508 -50.419)
			(xy 100.076057 -50.459047) (xy 100.068883 -50.538819) (xy 100.054566 -50.617622) (xy 100.033222 -50.694819)
			(xy 100.005024 -50.769785) (xy 99.9702 -50.841912) (xy 99.929032 -50.910615) (xy 99.881854 -50.97534)
			(xy 99.855782 -51.00574) (xy 99.850017 -51.012829) (xy 99.843505 -51.029886) (xy 99.843082 -51.039014)
			(xy 99.843082 -51.068986) (xy 99.843516 -51.078109) (xy 99.850036 -51.095159) (xy 99.855782 -51.10226)
			(xy 99.881842 -51.132671) (xy 99.929021 -51.197394) (xy 99.970191 -51.266096) (xy 100.005019 -51.338221)
			(xy 100.033221 -51.413185) (xy 100.054571 -51.49038) (xy 100.068895 -51.569182) (xy 100.076077 -51.648953)
			(xy 100.076508 -51.689) (xy 100.07612 -51.727284) (xy 100.069581 -51.803573) (xy 100.0565 -51.879015)
			(xy 100.036973 -51.953052) (xy 100.024438 -51.989228) (xy 100.021787 -51.997665) (xy 100.021787 -52.015335)
			(xy 100.024438 -52.023772) (xy 100.036963 -52.05995) (xy 100.056471 -52.13399) (xy 100.069551 -52.209431)
			(xy 100.076106 -52.285717) (xy 100.076508 -52.324) (xy 103.758492 -52.324) (xy 103.75888 -52.285716)
			(xy 103.765419 -52.209427) (xy 103.7785 -52.133985) (xy 103.798027 -52.059948) (xy 103.810562 -52.023772)
			(xy 103.813213 -52.015335) (xy 103.813213 -51.997665) (xy 103.810562 -51.989228) (xy 103.798037 -51.95305)
			(xy 103.778529 -51.87901) (xy 103.765449 -51.803569) (xy 103.758894 -51.727283) (xy 103.758492 -51.689)
			(xy 103.758943 -51.648953) (xy 103.766117 -51.569181) (xy 103.780434 -51.490378) (xy 103.801778 -51.413181)
			(xy 103.829976 -51.338215) (xy 103.8648 -51.266088) (xy 103.905968 -51.197385) (xy 103.953146 -51.13266)
			(xy 103.979218 -51.10226) (xy 103.984983 -51.095171) (xy 103.991495 -51.078114) (xy 103.991918 -51.068986)
			(xy 103.991918 -51.039014) (xy 103.991484 -51.029891) (xy 103.984964 -51.012841) (xy 103.979218 -51.00574)
			(xy 103.953158 -50.975329) (xy 103.905979 -50.910606) (xy 103.864809 -50.841904) (xy 103.829981 -50.769779)
			(xy 103.801779 -50.694815) (xy 103.780429 -50.61762) (xy 103.766105 -50.538818) (xy 103.758923 -50.459047)
			(xy 103.758492 -50.419) (xy 103.75888 -50.380716) (xy 103.765419 -50.304427) (xy 103.7785 -50.228985)
			(xy 103.798027 -50.154948) (xy 103.810562 -50.118772) (xy 103.813213 -50.110335) (xy 103.813213 -50.092665)
			(xy 103.810562 -50.084228) (xy 103.798037 -50.04805) (xy 103.778529 -49.97401) (xy 103.765449 -49.898569)
			(xy 103.758894 -49.822283) (xy 103.758492 -49.784) (xy 103.758996 -49.741652) (xy 103.767047 -49.657338)
			(xy 103.783076 -49.574172) (xy 103.806937 -49.492905) (xy 103.838416 -49.414275) (xy 103.877227 -49.338994)
			(xy 103.923017 -49.267742) (xy 103.975373 -49.201166) (xy 104.033821 -49.139868) (xy 104.097831 -49.084403)
			(xy 104.166823 -49.035274) (xy 104.240173 -48.992925) (xy 104.317216 -48.957741) (xy 104.397255 -48.930039)
			(xy 104.479564 -48.910071) (xy 104.563399 -48.898018) (xy 104.648 -48.893988) (xy 104.732601 -48.898018)
			(xy 104.816436 -48.910071) (xy 104.898745 -48.930039) (xy 104.978784 -48.957741) (xy 105.055827 -48.992925)
			(xy 105.129177 -49.035274) (xy 105.198169 -49.084403) (xy 105.262179 -49.139868) (xy 105.320627 -49.201166)
			(xy 105.372983 -49.267742) (xy 105.418773 -49.338994) (xy 105.457584 -49.414275) (xy 105.489063 -49.492905)
			(xy 105.512924 -49.574172) (xy 105.528953 -49.657338) (xy 105.537004 -49.741652) (xy 105.537508 -49.784)
			(xy 105.53712 -49.822284) (xy 105.530581 -49.898573) (xy 105.5175 -49.974015) (xy 105.497973 -50.048052)
			(xy 105.485438 -50.084228) (xy 105.482787 -50.092665) (xy 105.482787 -50.110335) (xy 105.485438 -50.118772)
			(xy 105.497963 -50.15495) (xy 105.517471 -50.22899) (xy 105.530551 -50.304431) (xy 105.537106 -50.380717)
			(xy 105.537508 -50.419) (xy 105.537057 -50.459047) (xy 105.529883 -50.538819) (xy 105.515566 -50.617622)
			(xy 105.494222 -50.694819) (xy 105.466024 -50.769785) (xy 105.4312 -50.841912) (xy 105.390032 -50.910615)
			(xy 105.342854 -50.97534) (xy 105.316782 -51.00574) (xy 105.311017 -51.012829) (xy 105.304505 -51.029886)
			(xy 105.304082 -51.039014) (xy 105.304082 -51.068986) (xy 105.304516 -51.078109) (xy 105.311036 -51.095159)
			(xy 105.316782 -51.10226) (xy 105.342842 -51.132671) (xy 105.390021 -51.197394) (xy 105.431191 -51.266096)
			(xy 105.466019 -51.338221) (xy 105.494221 -51.413185) (xy 105.515571 -51.49038) (xy 105.529895 -51.569182)
			(xy 105.537077 -51.648953) (xy 105.537508 -51.689) (xy 105.53712 -51.727284) (xy 105.530581 -51.803573)
			(xy 105.5175 -51.879015) (xy 105.497973 -51.953052) (xy 105.485438 -51.989228) (xy 105.482787 -51.997665)
			(xy 105.482787 -52.015335) (xy 105.485438 -52.023772) (xy 105.497963 -52.05995) (xy 105.517471 -52.13399)
			(xy 105.528396 -52.197) (xy 149.097492 -52.197) (xy 149.09788 -52.158716) (xy 149.104419 -52.082427)
			(xy 149.1175 -52.006985) (xy 149.137027 -51.932948) (xy 149.149562 -51.896772) (xy 149.152213 -51.888335)
			(xy 149.152213 -51.870665) (xy 149.149562 -51.862228) (xy 149.137037 -51.82605) (xy 149.117529 -51.75201)
			(xy 149.104449 -51.676569) (xy 149.097894 -51.600283) (xy 149.097492 -51.562) (xy 149.097943 -51.521953)
			(xy 149.105117 -51.442181) (xy 149.119434 -51.363378) (xy 149.140778 -51.286181) (xy 149.168976 -51.211215)
			(xy 149.2038 -51.139088) (xy 149.244968 -51.070385) (xy 149.292146 -51.00566) (xy 149.318218 -50.97526)
			(xy 149.323983 -50.968171) (xy 149.330495 -50.951114) (xy 149.330918 -50.941986) (xy 149.330918 -50.912014)
			(xy 149.330484 -50.902891) (xy 149.323964 -50.885841) (xy 149.318218 -50.87874) (xy 149.292158 -50.848329)
			(xy 149.244979 -50.783606) (xy 149.203809 -50.714904) (xy 149.168981 -50.642779) (xy 149.140779 -50.567815)
			(xy 149.119429 -50.49062) (xy 149.105105 -50.411818) (xy 149.097923 -50.332047) (xy 149.097492 -50.292)
			(xy 149.09788 -50.253716) (xy 149.104419 -50.177427) (xy 149.1175 -50.101985) (xy 149.137027 -50.027948)
			(xy 149.149562 -49.991772) (xy 149.152213 -49.983335) (xy 149.152213 -49.965665) (xy 149.149562 -49.957228)
			(xy 149.137037 -49.92105) (xy 149.117529 -49.84701) (xy 149.104449 -49.771569) (xy 149.097894 -49.695283)
			(xy 149.097492 -49.657) (xy 149.097996 -49.614652) (xy 149.106047 -49.530338) (xy 149.122076 -49.447172)
			(xy 149.145937 -49.365905) (xy 149.177416 -49.287275) (xy 149.216227 -49.211994) (xy 149.262017 -49.140742)
			(xy 149.314373 -49.074166) (xy 149.372821 -49.012868) (xy 149.436831 -48.957403) (xy 149.505823 -48.908274)
			(xy 149.579173 -48.865925) (xy 149.656216 -48.830741) (xy 149.736255 -48.803039) (xy 149.818564 -48.783071)
			(xy 149.902399 -48.771018) (xy 149.987 -48.766988) (xy 150.071601 -48.771018) (xy 150.155436 -48.783071)
			(xy 150.237745 -48.803039) (xy 150.317784 -48.830741) (xy 150.394827 -48.865925) (xy 150.468177 -48.908274)
			(xy 150.537169 -48.957403) (xy 150.601179 -49.012868) (xy 150.659627 -49.074166) (xy 150.711983 -49.140742)
			(xy 150.757773 -49.211994) (xy 150.796584 -49.287275) (xy 150.828063 -49.365905) (xy 150.851924 -49.447172)
			(xy 150.867953 -49.530338) (xy 150.876004 -49.614652) (xy 150.876508 -49.657) (xy 150.87612 -49.695284)
			(xy 150.869581 -49.771573) (xy 150.8565 -49.847015) (xy 150.836973 -49.921052) (xy 150.824438 -49.957228)
			(xy 150.821787 -49.965665) (xy 150.821787 -49.983335) (xy 150.824438 -49.991772) (xy 150.836963 -50.02795)
			(xy 150.856471 -50.10199) (xy 150.869551 -50.177431) (xy 150.876106 -50.253717) (xy 150.876508 -50.292)
			(xy 150.876057 -50.332047) (xy 150.868883 -50.411819) (xy 150.854566 -50.490622) (xy 150.833222 -50.567819)
			(xy 150.805024 -50.642785) (xy 150.7702 -50.714912) (xy 150.729032 -50.783615) (xy 150.681854 -50.84834)
			(xy 150.655782 -50.87874) (xy 150.650017 -50.885829) (xy 150.643505 -50.902886) (xy 150.643082 -50.912014)
			(xy 150.643082 -50.941986) (xy 150.643516 -50.951109) (xy 150.650036 -50.968159) (xy 150.655782 -50.97526)
			(xy 150.681842 -51.005671) (xy 150.729021 -51.070394) (xy 150.770191 -51.139096) (xy 150.805019 -51.211221)
			(xy 150.833221 -51.286185) (xy 150.854571 -51.36338) (xy 150.868895 -51.442182) (xy 150.876077 -51.521953)
			(xy 150.876508 -51.562) (xy 150.87612 -51.600284) (xy 150.869581 -51.676573) (xy 150.8565 -51.752015)
			(xy 150.836973 -51.826052) (xy 150.824438 -51.862228) (xy 150.821787 -51.870665) (xy 150.821787 -51.888335)
			(xy 150.824438 -51.896772) (xy 150.836963 -51.93295) (xy 150.856471 -52.00699) (xy 150.869551 -52.082431)
			(xy 150.876106 -52.158717) (xy 150.876508 -52.197) (xy 154.558492 -52.197) (xy 154.55888 -52.158716)
			(xy 154.565419 -52.082427) (xy 154.5785 -52.006985) (xy 154.598027 -51.932948) (xy 154.610562 -51.896772)
			(xy 154.613213 -51.888335) (xy 154.613213 -51.870665) (xy 154.610562 -51.862228) (xy 154.598037 -51.82605)
			(xy 154.578529 -51.75201) (xy 154.565449 -51.676569) (xy 154.558894 -51.600283) (xy 154.558492 -51.562)
			(xy 154.558943 -51.521953) (xy 154.566117 -51.442181) (xy 154.580434 -51.363378) (xy 154.601778 -51.286181)
			(xy 154.629976 -51.211215) (xy 154.6648 -51.139088) (xy 154.705968 -51.070385) (xy 154.753146 -51.00566)
			(xy 154.779218 -50.97526) (xy 154.784983 -50.968171) (xy 154.791495 -50.951114) (xy 154.791918 -50.941986)
			(xy 154.791918 -50.912014) (xy 154.791484 -50.902891) (xy 154.784964 -50.885841) (xy 154.779218 -50.87874)
			(xy 154.753158 -50.848329) (xy 154.705979 -50.783606) (xy 154.664809 -50.714904) (xy 154.629981 -50.642779)
			(xy 154.601779 -50.567815) (xy 154.580429 -50.49062) (xy 154.566105 -50.411818) (xy 154.558923 -50.332047)
			(xy 154.558492 -50.292) (xy 154.55888 -50.253716) (xy 154.565419 -50.177427) (xy 154.5785 -50.101985)
			(xy 154.598027 -50.027948) (xy 154.610562 -49.991772) (xy 154.613213 -49.983335) (xy 154.613213 -49.965665)
			(xy 154.610562 -49.957228) (xy 154.598037 -49.92105) (xy 154.578529 -49.84701) (xy 154.565449 -49.771569)
			(xy 154.558894 -49.695283) (xy 154.558492 -49.657) (xy 154.558996 -49.614652) (xy 154.567047 -49.530338)
			(xy 154.583076 -49.447172) (xy 154.606937 -49.365905) (xy 154.638416 -49.287275) (xy 154.677227 -49.211994)
			(xy 154.723017 -49.140742) (xy 154.775373 -49.074166) (xy 154.833821 -49.012868) (xy 154.897831 -48.957403)
			(xy 154.966823 -48.908274) (xy 155.040173 -48.865925) (xy 155.117216 -48.830741) (xy 155.197255 -48.803039)
			(xy 155.279564 -48.783071) (xy 155.363399 -48.771018) (xy 155.448 -48.766988) (xy 155.532601 -48.771018)
			(xy 155.616436 -48.783071) (xy 155.698745 -48.803039) (xy 155.778784 -48.830741) (xy 155.855827 -48.865925)
			(xy 155.929177 -48.908274) (xy 155.998169 -48.957403) (xy 156.062179 -49.012868) (xy 156.120627 -49.074166)
			(xy 156.172983 -49.140742) (xy 156.218773 -49.211994) (xy 156.257584 -49.287275) (xy 156.289063 -49.365905)
			(xy 156.312924 -49.447172) (xy 156.328953 -49.530338) (xy 156.337004 -49.614652) (xy 156.337508 -49.657)
			(xy 156.33712 -49.695284) (xy 156.330581 -49.771573) (xy 156.3175 -49.847015) (xy 156.297973 -49.921052)
			(xy 156.285438 -49.957228) (xy 156.282787 -49.965665) (xy 156.282787 -49.983335) (xy 156.285438 -49.991772)
			(xy 156.297963 -50.02795) (xy 156.317471 -50.10199) (xy 156.330551 -50.177431) (xy 156.337106 -50.253717)
			(xy 156.337508 -50.292) (xy 156.337057 -50.332047) (xy 156.329883 -50.411819) (xy 156.315566 -50.490622)
			(xy 156.294222 -50.567819) (xy 156.266024 -50.642785) (xy 156.2312 -50.714912) (xy 156.190032 -50.783615)
			(xy 156.142854 -50.84834) (xy 156.116782 -50.87874) (xy 156.111017 -50.885829) (xy 156.104505 -50.902886)
			(xy 156.104082 -50.912014) (xy 156.104082 -50.941986) (xy 156.104516 -50.951109) (xy 156.111036 -50.968159)
			(xy 156.116782 -50.97526) (xy 156.142842 -51.005671) (xy 156.190021 -51.070394) (xy 156.231191 -51.139096)
			(xy 156.266019 -51.211221) (xy 156.294221 -51.286185) (xy 156.315571 -51.36338) (xy 156.329895 -51.442182)
			(xy 156.337077 -51.521953) (xy 156.337508 -51.562) (xy 156.33712 -51.600284) (xy 156.330581 -51.676573)
			(xy 156.3175 -51.752015) (xy 156.297973 -51.826052) (xy 156.285438 -51.862228) (xy 156.282787 -51.870665)
			(xy 156.282787 -51.888335) (xy 156.285438 -51.896772) (xy 156.297963 -51.93295) (xy 156.317471 -52.00699)
			(xy 156.330551 -52.082431) (xy 156.337106 -52.158717) (xy 156.337508 -52.197) (xy 160.019492 -52.197)
			(xy 160.01988 -52.158716) (xy 160.026419 -52.082427) (xy 160.0395 -52.006985) (xy 160.059027 -51.932948)
			(xy 160.071562 -51.896772) (xy 160.074213 -51.888335) (xy 160.074213 -51.870665) (xy 160.071562 -51.862228)
			(xy 160.059037 -51.82605) (xy 160.039529 -51.75201) (xy 160.026449 -51.676569) (xy 160.019894 -51.600283)
			(xy 160.019492 -51.562) (xy 160.019943 -51.521953) (xy 160.027117 -51.442181) (xy 160.041434 -51.363378)
			(xy 160.062778 -51.286181) (xy 160.090976 -51.211215) (xy 160.1258 -51.139088) (xy 160.166968 -51.070385)
			(xy 160.214146 -51.00566) (xy 160.240218 -50.97526) (xy 160.245983 -50.968171) (xy 160.252495 -50.951114)
			(xy 160.252918 -50.941986) (xy 160.252918 -50.912014) (xy 160.252484 -50.902891) (xy 160.245964 -50.885841)
			(xy 160.240218 -50.87874) (xy 160.214158 -50.848329) (xy 160.166979 -50.783606) (xy 160.125809 -50.714904)
			(xy 160.090981 -50.642779) (xy 160.062779 -50.567815) (xy 160.041429 -50.49062) (xy 160.027105 -50.411818)
			(xy 160.019923 -50.332047) (xy 160.019492 -50.292) (xy 160.01988 -50.253716) (xy 160.026419 -50.177427)
			(xy 160.0395 -50.101985) (xy 160.059027 -50.027948) (xy 160.071562 -49.991772) (xy 160.074213 -49.983335)
			(xy 160.074213 -49.965665) (xy 160.071562 -49.957228) (xy 160.059037 -49.92105) (xy 160.039529 -49.84701)
			(xy 160.026449 -49.771569) (xy 160.019894 -49.695283) (xy 160.019492 -49.657) (xy 160.019996 -49.614652)
			(xy 160.028047 -49.530338) (xy 160.044076 -49.447172) (xy 160.067937 -49.365905) (xy 160.099416 -49.287275)
			(xy 160.138227 -49.211994) (xy 160.184017 -49.140742) (xy 160.236373 -49.074166) (xy 160.294821 -49.012868)
			(xy 160.358831 -48.957403) (xy 160.427823 -48.908274) (xy 160.501173 -48.865925) (xy 160.578216 -48.830741)
			(xy 160.658255 -48.803039) (xy 160.740564 -48.783071) (xy 160.824399 -48.771018) (xy 160.909 -48.766988)
			(xy 160.993601 -48.771018) (xy 161.077436 -48.783071) (xy 161.159745 -48.803039) (xy 161.239784 -48.830741)
			(xy 161.316827 -48.865925) (xy 161.390177 -48.908274) (xy 161.459169 -48.957403) (xy 161.523179 -49.012868)
			(xy 161.581627 -49.074166) (xy 161.633983 -49.140742) (xy 161.679773 -49.211994) (xy 161.718584 -49.287275)
			(xy 161.750063 -49.365905) (xy 161.773924 -49.447172) (xy 161.789953 -49.530338) (xy 161.798004 -49.614652)
			(xy 161.798508 -49.657) (xy 161.79812 -49.695284) (xy 161.791581 -49.771573) (xy 161.7785 -49.847015)
			(xy 161.758973 -49.921052) (xy 161.746438 -49.957228) (xy 161.743787 -49.965665) (xy 161.743787 -49.983335)
			(xy 161.746438 -49.991772) (xy 161.758963 -50.02795) (xy 161.778471 -50.10199) (xy 161.791551 -50.177431)
			(xy 161.798106 -50.253717) (xy 161.798508 -50.292) (xy 161.798057 -50.332047) (xy 161.790883 -50.411819)
			(xy 161.776566 -50.490622) (xy 161.755222 -50.567819) (xy 161.727024 -50.642785) (xy 161.6922 -50.714912)
			(xy 161.651032 -50.783615) (xy 161.603854 -50.84834) (xy 161.577782 -50.87874) (xy 161.572017 -50.885829)
			(xy 161.565505 -50.902886) (xy 161.565082 -50.912014) (xy 161.565082 -50.941986) (xy 161.565516 -50.951109)
			(xy 161.572036 -50.968159) (xy 161.577782 -50.97526) (xy 161.603842 -51.005671) (xy 161.651021 -51.070394)
			(xy 161.692191 -51.139096) (xy 161.727019 -51.211221) (xy 161.755221 -51.286185) (xy 161.776571 -51.36338)
			(xy 161.790895 -51.442182) (xy 161.798077 -51.521953) (xy 161.798508 -51.562) (xy 161.79812 -51.600284)
			(xy 161.791581 -51.676573) (xy 161.7785 -51.752015) (xy 161.758973 -51.826052) (xy 161.746438 -51.862228)
			(xy 161.743787 -51.870665) (xy 161.743787 -51.888335) (xy 161.746438 -51.896772) (xy 161.758963 -51.93295)
			(xy 161.778471 -52.00699) (xy 161.791551 -52.082431) (xy 161.798106 -52.158717) (xy 161.798508 -52.197)
			(xy 165.480492 -52.197) (xy 165.48088 -52.158716) (xy 165.487419 -52.082427) (xy 165.5005 -52.006985)
			(xy 165.520027 -51.932948) (xy 165.532562 -51.896772) (xy 165.535213 -51.888335) (xy 165.535213 -51.870665)
			(xy 165.532562 -51.862228) (xy 165.520037 -51.82605) (xy 165.500529 -51.75201) (xy 165.487449 -51.676569)
			(xy 165.480894 -51.600283) (xy 165.480492 -51.562) (xy 165.480943 -51.521953) (xy 165.488117 -51.442181)
			(xy 165.502434 -51.363378) (xy 165.523778 -51.286181) (xy 165.551976 -51.211215) (xy 165.5868 -51.139088)
			(xy 165.627968 -51.070385) (xy 165.675146 -51.00566) (xy 165.701218 -50.97526) (xy 165.706983 -50.968171)
			(xy 165.713495 -50.951114) (xy 165.713918 -50.941986) (xy 165.713918 -50.912014) (xy 165.713484 -50.902891)
			(xy 165.706964 -50.885841) (xy 165.701218 -50.87874) (xy 165.675158 -50.848329) (xy 165.627979 -50.783606)
			(xy 165.586809 -50.714904) (xy 165.551981 -50.642779) (xy 165.523779 -50.567815) (xy 165.502429 -50.49062)
			(xy 165.488105 -50.411818) (xy 165.480923 -50.332047) (xy 165.480492 -50.292) (xy 165.48088 -50.253716)
			(xy 165.487419 -50.177427) (xy 165.5005 -50.101985) (xy 165.520027 -50.027948) (xy 165.532562 -49.991772)
			(xy 165.535213 -49.983335) (xy 165.535213 -49.965665) (xy 165.532562 -49.957228) (xy 165.520037 -49.92105)
			(xy 165.500529 -49.84701) (xy 165.487449 -49.771569) (xy 165.480894 -49.695283) (xy 165.480492 -49.657)
			(xy 165.480996 -49.614652) (xy 165.489047 -49.530338) (xy 165.505076 -49.447172) (xy 165.528937 -49.365905)
			(xy 165.560416 -49.287275) (xy 165.599227 -49.211994) (xy 165.645017 -49.140742) (xy 165.697373 -49.074166)
			(xy 165.755821 -49.012868) (xy 165.819831 -48.957403) (xy 165.888823 -48.908274) (xy 165.962173 -48.865925)
			(xy 166.039216 -48.830741) (xy 166.119255 -48.803039) (xy 166.201564 -48.783071) (xy 166.285399 -48.771018)
			(xy 166.37 -48.766988) (xy 166.454601 -48.771018) (xy 166.538436 -48.783071) (xy 166.620745 -48.803039)
			(xy 166.700784 -48.830741) (xy 166.777827 -48.865925) (xy 166.851177 -48.908274) (xy 166.920169 -48.957403)
			(xy 166.984179 -49.012868) (xy 167.042627 -49.074166) (xy 167.094983 -49.140742) (xy 167.140773 -49.211994)
			(xy 167.179584 -49.287275) (xy 167.211063 -49.365905) (xy 167.234924 -49.447172) (xy 167.250953 -49.530338)
			(xy 167.259004 -49.614652) (xy 167.259508 -49.657) (xy 167.25912 -49.695284) (xy 167.252581 -49.771573)
			(xy 167.2395 -49.847015) (xy 167.219973 -49.921052) (xy 167.207438 -49.957228) (xy 167.204787 -49.965665)
			(xy 167.204787 -49.983335) (xy 167.207438 -49.991772) (xy 167.219963 -50.02795) (xy 167.239471 -50.10199)
			(xy 167.252551 -50.177431) (xy 167.259106 -50.253717) (xy 167.259508 -50.292) (xy 167.259057 -50.332047)
			(xy 167.251883 -50.411819) (xy 167.237566 -50.490622) (xy 167.216222 -50.567819) (xy 167.188024 -50.642785)
			(xy 167.1532 -50.714912) (xy 167.112032 -50.783615) (xy 167.064854 -50.84834) (xy 167.038782 -50.87874)
			(xy 167.033017 -50.885829) (xy 167.026505 -50.902886) (xy 167.026082 -50.912014) (xy 167.026082 -50.941986)
			(xy 167.026516 -50.951109) (xy 167.033036 -50.968159) (xy 167.038782 -50.97526) (xy 167.064842 -51.005671)
			(xy 167.112021 -51.070394) (xy 167.153191 -51.139096) (xy 167.188019 -51.211221) (xy 167.216221 -51.286185)
			(xy 167.237571 -51.36338) (xy 167.251895 -51.442182) (xy 167.259077 -51.521953) (xy 167.259508 -51.562)
			(xy 167.25912 -51.600284) (xy 167.252581 -51.676573) (xy 167.2395 -51.752015) (xy 167.219973 -51.826052)
			(xy 167.207438 -51.862228) (xy 167.204787 -51.870665) (xy 167.204787 -51.888335) (xy 167.207438 -51.896772)
			(xy 167.219963 -51.93295) (xy 167.239471 -52.00699) (xy 167.252551 -52.082431) (xy 167.259106 -52.158717)
			(xy 167.259508 -52.197) (xy 170.941492 -52.197) (xy 170.94188 -52.158716) (xy 170.948419 -52.082427)
			(xy 170.9615 -52.006985) (xy 170.981027 -51.932948) (xy 170.993562 -51.896772) (xy 170.996213 -51.888335)
			(xy 170.996213 -51.870665) (xy 170.993562 -51.862228) (xy 170.981037 -51.82605) (xy 170.961529 -51.75201)
			(xy 170.948449 -51.676569) (xy 170.941894 -51.600283) (xy 170.941492 -51.562) (xy 170.941943 -51.521953)
			(xy 170.949117 -51.442181) (xy 170.963434 -51.363378) (xy 170.984778 -51.286181) (xy 171.012976 -51.211215)
			(xy 171.0478 -51.139088) (xy 171.088968 -51.070385) (xy 171.136146 -51.00566) (xy 171.162218 -50.97526)
			(xy 171.167983 -50.968171) (xy 171.174495 -50.951114) (xy 171.174918 -50.941986) (xy 171.174918 -50.912014)
			(xy 171.174484 -50.902891) (xy 171.167964 -50.885841) (xy 171.162218 -50.87874) (xy 171.136158 -50.848329)
			(xy 171.088979 -50.783606) (xy 171.047809 -50.714904) (xy 171.012981 -50.642779) (xy 170.984779 -50.567815)
			(xy 170.963429 -50.49062) (xy 170.949105 -50.411818) (xy 170.941923 -50.332047) (xy 170.941492 -50.292)
			(xy 170.94188 -50.253716) (xy 170.948419 -50.177427) (xy 170.9615 -50.101985) (xy 170.981027 -50.027948)
			(xy 170.993562 -49.991772) (xy 170.996213 -49.983335) (xy 170.996213 -49.965665) (xy 170.993562 -49.957228)
			(xy 170.981037 -49.92105) (xy 170.961529 -49.84701) (xy 170.948449 -49.771569) (xy 170.941894 -49.695283)
			(xy 170.941492 -49.657) (xy 170.941996 -49.614652) (xy 170.950047 -49.530338) (xy 170.966076 -49.447172)
			(xy 170.989937 -49.365905) (xy 171.021416 -49.287275) (xy 171.060227 -49.211994) (xy 171.106017 -49.140742)
			(xy 171.158373 -49.074166) (xy 171.216821 -49.012868) (xy 171.280831 -48.957403) (xy 171.349823 -48.908274)
			(xy 171.423173 -48.865925) (xy 171.500216 -48.830741) (xy 171.580255 -48.803039) (xy 171.662564 -48.783071)
			(xy 171.746399 -48.771018) (xy 171.831 -48.766988) (xy 171.915601 -48.771018) (xy 171.999436 -48.783071)
			(xy 172.081745 -48.803039) (xy 172.161784 -48.830741) (xy 172.238827 -48.865925) (xy 172.312177 -48.908274)
			(xy 172.381169 -48.957403) (xy 172.445179 -49.012868) (xy 172.503627 -49.074166) (xy 172.555983 -49.140742)
			(xy 172.601773 -49.211994) (xy 172.640584 -49.287275) (xy 172.672063 -49.365905) (xy 172.695924 -49.447172)
			(xy 172.711953 -49.530338) (xy 172.720004 -49.614652) (xy 172.720508 -49.657) (xy 172.72012 -49.695284)
			(xy 172.713581 -49.771573) (xy 172.7005 -49.847015) (xy 172.680973 -49.921052) (xy 172.668438 -49.957228)
			(xy 172.665787 -49.965665) (xy 172.665787 -49.983335) (xy 172.668438 -49.991772) (xy 172.680963 -50.02795)
			(xy 172.700471 -50.10199) (xy 172.713551 -50.177431) (xy 172.720106 -50.253717) (xy 172.720508 -50.292)
			(xy 172.720057 -50.332047) (xy 172.712883 -50.411819) (xy 172.698566 -50.490622) (xy 172.677222 -50.567819)
			(xy 172.649024 -50.642785) (xy 172.6142 -50.714912) (xy 172.573032 -50.783615) (xy 172.525854 -50.84834)
			(xy 172.499782 -50.87874) (xy 172.494017 -50.885829) (xy 172.487505 -50.902886) (xy 172.487082 -50.912014)
			(xy 172.487082 -50.941986) (xy 172.487516 -50.951109) (xy 172.494036 -50.968159) (xy 172.499782 -50.97526)
			(xy 172.525842 -51.005671) (xy 172.573021 -51.070394) (xy 172.614191 -51.139096) (xy 172.649019 -51.211221)
			(xy 172.677221 -51.286185) (xy 172.698571 -51.36338) (xy 172.712895 -51.442182) (xy 172.720077 -51.521953)
			(xy 172.720508 -51.562) (xy 172.72012 -51.600284) (xy 172.713581 -51.676573) (xy 172.7005 -51.752015)
			(xy 172.680973 -51.826052) (xy 172.668438 -51.862228) (xy 172.665787 -51.870665) (xy 172.665787 -51.888335)
			(xy 172.668438 -51.896772) (xy 172.680963 -51.93295) (xy 172.700471 -52.00699) (xy 172.713551 -52.082431)
			(xy 172.720106 -52.158717) (xy 172.720508 -52.197) (xy 176.399952 -52.197) (xy 176.400342 -52.158716)
			(xy 176.406881 -52.082427) (xy 176.419962 -52.006985) (xy 176.439487 -51.932948) (xy 176.452022 -51.896772)
			(xy 176.454674 -51.888335) (xy 176.454674 -51.870665) (xy 176.452022 -51.862228) (xy 176.439495 -51.82605)
			(xy 176.419988 -51.75201) (xy 176.406909 -51.676569) (xy 176.400354 -51.600283) (xy 176.399952 -51.562)
			(xy 176.400388 -51.521953) (xy 176.407563 -51.44218) (xy 176.421881 -51.363376) (xy 176.443226 -51.286178)
			(xy 176.471427 -51.211212) (xy 176.506253 -51.139086) (xy 176.547423 -51.070383) (xy 176.594604 -51.00566)
			(xy 176.620678 -50.97526) (xy 176.626439 -50.968167) (xy 176.632954 -50.951113) (xy 176.633378 -50.941986)
			(xy 176.633378 -50.912014) (xy 176.632931 -50.902892) (xy 176.626419 -50.885843) (xy 176.620678 -50.87874)
			(xy 176.594628 -50.84832) (xy 176.547447 -50.7836) (xy 176.506274 -50.714899) (xy 176.471445 -50.642776)
			(xy 176.443241 -50.567813) (xy 176.42189 -50.490618) (xy 176.407565 -50.411817) (xy 176.400383 -50.332047)
			(xy 176.399952 -50.292) (xy 176.400342 -50.253716) (xy 176.406881 -50.177427) (xy 176.419962 -50.101985)
			(xy 176.439487 -50.027948) (xy 176.452022 -49.991772) (xy 176.454674 -49.983335) (xy 176.454674 -49.965665)
			(xy 176.452022 -49.957228) (xy 176.439495 -49.92105) (xy 176.419988 -49.84701) (xy 176.406909 -49.771569)
			(xy 176.400354 -49.695283) (xy 176.399952 -49.657) (xy 176.400456 -49.614652) (xy 176.408507 -49.530338)
			(xy 176.424536 -49.447172) (xy 176.448397 -49.365905) (xy 176.479876 -49.287275) (xy 176.518687 -49.211994)
			(xy 176.564477 -49.140742) (xy 176.616833 -49.074166) (xy 176.675281 -49.012868) (xy 176.739291 -48.957403)
			(xy 176.808283 -48.908274) (xy 176.881633 -48.865925) (xy 176.958676 -48.830741) (xy 177.038715 -48.803039)
			(xy 177.121024 -48.783071) (xy 177.204859 -48.771018) (xy 177.28946 -48.766988) (xy 177.374061 -48.771018)
			(xy 177.457896 -48.783071) (xy 177.540205 -48.803039) (xy 177.620244 -48.830741) (xy 177.697287 -48.865925)
			(xy 177.770637 -48.908274) (xy 177.839629 -48.957403) (xy 177.903639 -49.012868) (xy 177.962087 -49.074166)
			(xy 178.014443 -49.140742) (xy 178.060233 -49.211994) (xy 178.099044 -49.287275) (xy 178.130523 -49.365905)
			(xy 178.154384 -49.447172) (xy 178.170413 -49.530338) (xy 178.178464 -49.614652) (xy 178.178968 -49.657)
			(xy 178.178577 -49.695284) (xy 178.172038 -49.771573) (xy 178.158958 -49.847015) (xy 178.139432 -49.921052)
			(xy 178.126898 -49.957228) (xy 178.124245 -49.965664) (xy 178.124245 -49.983336) (xy 178.126898 -49.991772)
			(xy 178.139422 -50.027951) (xy 178.15893 -50.10199) (xy 178.172011 -50.177431) (xy 178.178566 -50.253717)
			(xy 178.178968 -50.292) (xy 178.178527 -50.332047) (xy 178.171353 -50.411819) (xy 178.157035 -50.490623)
			(xy 178.13569 -50.567821) (xy 178.10749 -50.642787) (xy 178.072665 -50.714913) (xy 178.031495 -50.783617)
			(xy 177.984315 -50.84834) (xy 177.958242 -50.87874) (xy 177.952472 -50.885825) (xy 177.945964 -50.902886)
			(xy 177.945542 -50.912014) (xy 177.945542 -50.941986) (xy 177.945985 -50.951108) (xy 177.9525 -50.968158)
			(xy 177.958242 -50.97526) (xy 177.984295 -51.005677) (xy 178.031476 -51.070398) (xy 178.072647 -51.139099)
			(xy 178.107476 -51.211223) (xy 178.13568 -51.286186) (xy 178.15703 -51.363381) (xy 178.171355 -51.442183)
			(xy 178.178537 -51.521953) (xy 178.178968 -51.562) (xy 178.178577 -51.600284) (xy 178.172038 -51.676573)
			(xy 178.158958 -51.752015) (xy 178.139432 -51.826052) (xy 178.126898 -51.862228) (xy 178.124245 -51.870664)
			(xy 178.124245 -51.888336) (xy 178.126898 -51.896772) (xy 178.139422 -51.932951) (xy 178.15893 -52.00699)
			(xy 178.172011 -52.082431) (xy 178.178566 -52.158717) (xy 178.178968 -52.197) (xy 181.860952 -52.197)
			(xy 181.861342 -52.158716) (xy 181.867881 -52.082427) (xy 181.880962 -52.006985) (xy 181.900487 -51.932948)
			(xy 181.913022 -51.896772) (xy 181.915674 -51.888335) (xy 181.915674 -51.870665) (xy 181.913022 -51.862228)
			(xy 181.900495 -51.82605) (xy 181.880988 -51.75201) (xy 181.867909 -51.676569) (xy 181.861354 -51.600283)
			(xy 181.860952 -51.562) (xy 181.861388 -51.521953) (xy 181.868563 -51.44218) (xy 181.882881 -51.363376)
			(xy 181.904226 -51.286178) (xy 181.932427 -51.211212) (xy 181.967253 -51.139086) (xy 182.008423 -51.070383)
			(xy 182.055604 -51.00566) (xy 182.081678 -50.97526) (xy 182.087439 -50.968167) (xy 182.093954 -50.951113)
			(xy 182.094378 -50.941986) (xy 182.094378 -50.912014) (xy 182.093931 -50.902892) (xy 182.087419 -50.885843)
			(xy 182.081678 -50.87874) (xy 182.055628 -50.84832) (xy 182.008447 -50.7836) (xy 181.967274 -50.714899)
			(xy 181.932445 -50.642776) (xy 181.904241 -50.567813) (xy 181.88289 -50.490618) (xy 181.868565 -50.411817)
			(xy 181.861383 -50.332047) (xy 181.860952 -50.292) (xy 181.861342 -50.253716) (xy 181.867881 -50.177427)
			(xy 181.880962 -50.101985) (xy 181.900487 -50.027948) (xy 181.913022 -49.991772) (xy 181.915674 -49.983335)
			(xy 181.915674 -49.965665) (xy 181.913022 -49.957228) (xy 181.900495 -49.92105) (xy 181.880988 -49.84701)
			(xy 181.867909 -49.771569) (xy 181.861354 -49.695283) (xy 181.860952 -49.657) (xy 181.861456 -49.614652)
			(xy 181.869507 -49.530338) (xy 181.885536 -49.447172) (xy 181.909397 -49.365905) (xy 181.940876 -49.287275)
			(xy 181.979687 -49.211994) (xy 182.025477 -49.140742) (xy 182.077833 -49.074166) (xy 182.136281 -49.012868)
			(xy 182.200291 -48.957403) (xy 182.269283 -48.908274) (xy 182.342633 -48.865925) (xy 182.419676 -48.830741)
			(xy 182.499715 -48.803039) (xy 182.582024 -48.783071) (xy 182.665859 -48.771018) (xy 182.75046 -48.766988)
			(xy 182.835061 -48.771018) (xy 182.918896 -48.783071) (xy 183.001205 -48.803039) (xy 183.081244 -48.830741)
			(xy 183.158287 -48.865925) (xy 183.231637 -48.908274) (xy 183.300629 -48.957403) (xy 183.364639 -49.012868)
			(xy 183.423087 -49.074166) (xy 183.475443 -49.140742) (xy 183.521233 -49.211994) (xy 183.560044 -49.287275)
			(xy 183.591523 -49.365905) (xy 183.615384 -49.447172) (xy 183.631413 -49.530338) (xy 183.639464 -49.614652)
			(xy 183.639968 -49.657) (xy 183.639577 -49.695284) (xy 183.633038 -49.771573) (xy 183.619958 -49.847015)
			(xy 183.600432 -49.921052) (xy 183.587898 -49.957228) (xy 183.585245 -49.965664) (xy 183.585245 -49.983336)
			(xy 183.587898 -49.991772) (xy 183.600422 -50.027951) (xy 183.61993 -50.10199) (xy 183.633011 -50.177431)
			(xy 183.639566 -50.253717) (xy 183.639791 -50.275179) (xy 257.330698 -50.275179) (xy 257.330698 -50.190457)
			(xy 257.338751 -50.10612) (xy 257.354785 -50.02293) (xy 257.378653 -49.94164) (xy 257.410141 -49.862988)
			(xy 257.448963 -49.787685) (xy 257.494766 -49.716413) (xy 257.547137 -49.649817) (xy 257.605602 -49.588502)
			(xy 257.66963 -49.533021) (xy 257.738642 -49.483878) (xy 257.812012 -49.441518) (xy 257.889077 -49.406323)
			(xy 257.969139 -49.378614) (xy 258.051472 -49.35864) (xy 258.135331 -49.346583) (xy 258.219956 -49.342552)
			(xy 258.304581 -49.346583) (xy 258.38844 -49.35864) (xy 258.470773 -49.378614) (xy 258.550835 -49.406323)
			(xy 258.6279 -49.441518) (xy 258.70127 -49.483878) (xy 258.770282 -49.533021) (xy 258.83431 -49.588502)
			(xy 258.892775 -49.649817) (xy 258.945146 -49.716413) (xy 258.990949 -49.787685) (xy 259.029771 -49.862988)
			(xy 259.061259 -49.94164) (xy 259.085127 -50.02293) (xy 259.101161 -50.10612) (xy 259.109214 -50.190457)
			(xy 259.109718 -50.232818) (xy 259.109214 -50.275179) (xy 259.101161 -50.359516) (xy 259.085127 -50.442706)
			(xy 259.061259 -50.523996) (xy 259.029771 -50.602648) (xy 258.990949 -50.677951) (xy 258.945146 -50.749223)
			(xy 258.892775 -50.815819) (xy 258.83431 -50.877134) (xy 258.770282 -50.932615) (xy 258.70127 -50.981758)
			(xy 258.6279 -51.024118) (xy 258.562469 -51.054) (xy 275.335492 -51.054) (xy 275.336075 -51.007604)
			(xy 275.34572 -50.915316) (xy 275.364916 -50.824532) (xy 275.393454 -50.736239) (xy 275.411692 -50.693574)
			(xy 275.415498 -50.683632) (xy 275.415498 -50.662368) (xy 275.411692 -50.652426) (xy 275.393447 -50.609764)
			(xy 275.364903 -50.521471) (xy 275.34571 -50.430686) (xy 275.336077 -50.338396) (xy 275.335492 -50.292)
			(xy 275.335996 -50.249652) (xy 275.344047 -50.165338) (xy 275.360076 -50.082172) (xy 275.383937 -50.000905)
			(xy 275.415416 -49.922275) (xy 275.454227 -49.846994) (xy 275.500017 -49.775742) (xy 275.552373 -49.709166)
			(xy 275.610821 -49.647868) (xy 275.674831 -49.592403) (xy 275.743823 -49.543274) (xy 275.817173 -49.500925)
			(xy 275.894216 -49.465741) (xy 275.974255 -49.438039) (xy 276.056564 -49.418071) (xy 276.140399 -49.406018)
			(xy 276.225 -49.401988) (xy 276.309601 -49.406018) (xy 276.393436 -49.418071) (xy 276.475745 -49.438039)
			(xy 276.555784 -49.465741) (xy 276.632827 -49.500925) (xy 276.706177 -49.543274) (xy 276.775169 -49.592403)
			(xy 276.825713 -49.6362) (xy 285.093159 -49.6362) (xy 285.09719 -49.551598) (xy 285.109243 -49.467762)
			(xy 285.129211 -49.385452) (xy 285.156912 -49.305412) (xy 285.192097 -49.228367) (xy 285.234445 -49.155016)
			(xy 285.283574 -49.086023) (xy 285.339038 -49.022012) (xy 285.400336 -48.963562) (xy 285.466912 -48.911204)
			(xy 285.538164 -48.865412) (xy 285.613445 -48.826599) (xy 285.692075 -48.795118) (xy 285.773342 -48.771254)
			(xy 285.856509 -48.755222) (xy 285.940823 -48.747169) (xy 285.983172 -48.746664) (xy 286.024585 -48.747103)
			(xy 286.107056 -48.754768) (xy 286.188456 -48.770071) (xy 286.268079 -48.792879) (xy 286.345236 -48.822996)
			(xy 286.38246 -48.841152) (xy 286.392777 -48.845742) (xy 286.415322 -48.846392) (xy 286.425894 -48.842422)
			(xy 286.468239 -48.824491) (xy 286.555816 -48.796434) (xy 286.64582 -48.77756) (xy 286.737291 -48.768071)
			(xy 286.783272 -48.767492) (xy 286.825938 -48.767984) (xy 286.910879 -48.776144) (xy 286.994648 -48.792402)
			(xy 287.076474 -48.816609) (xy 287.155606 -48.848541) (xy 287.231316 -48.887905) (xy 287.302908 -48.93434)
			(xy 287.369723 -48.987418) (xy 287.431148 -49.046651) (xy 287.486617 -49.111494) (xy 287.535621 -49.181353)
			(xy 287.577709 -49.255583) (xy 287.612494 -49.333503) (xy 287.626552 -49.37379) (xy 287.630761 -49.384635)
			(xy 287.647113 -49.401156) (xy 287.669044 -49.40886) (xy 287.680654 -49.40808) (xy 287.705905 -49.405417)
			(xy 287.756609 -49.402622) (xy 287.782 -49.402492) (xy 287.824348 -49.402996) (xy 287.908662 -49.411047)
			(xy 287.991828 -49.427076) (xy 288.073095 -49.450937) (xy 288.151725 -49.482416) (xy 288.227006 -49.521227)
			(xy 288.298258 -49.567017) (xy 288.364834 -49.619373) (xy 288.426132 -49.677821) (xy 288.481597 -49.741831)
			(xy 288.530726 -49.810823) (xy 288.573075 -49.884173) (xy 288.608259 -49.961216) (xy 288.635961 -50.041255)
			(xy 288.655929 -50.123564) (xy 288.667982 -50.207399) (xy 288.672013 -50.292) (xy 288.667982 -50.376601)
			(xy 288.655929 -50.460436) (xy 288.635961 -50.542745) (xy 288.608259 -50.622784) (xy 288.573075 -50.699827)
			(xy 288.530726 -50.773177) (xy 288.481597 -50.842169) (xy 288.426132 -50.906179) (xy 288.364834 -50.964627)
			(xy 288.298258 -51.016983) (xy 288.227006 -51.062773) (xy 288.151725 -51.101584) (xy 288.073095 -51.133063)
			(xy 287.991828 -51.156924) (xy 287.908662 -51.172953) (xy 287.824348 -51.181004) (xy 287.782 -51.181508)
			(xy 287.739333 -51.181042) (xy 287.654392 -51.172878) (xy 287.570622 -51.156618) (xy 287.488795 -51.132409)
			(xy 287.409663 -51.100474) (xy 287.333953 -51.061108) (xy 287.262361 -51.014671) (xy 287.195546 -50.961591)
			(xy 287.134122 -50.902356) (xy 287.078653 -50.837511) (xy 287.02965 -50.767651) (xy 286.987562 -50.693419)
			(xy 286.952778 -50.615497) (xy 286.93872 -50.57521) (xy 286.934449 -50.564396) (xy 286.918124 -50.547876)
			(xy 286.896219 -50.540156) (xy 286.884618 -50.54092) (xy 286.859367 -50.543586) (xy 286.808663 -50.546379)
			(xy 286.783272 -50.546508) (xy 286.741859 -50.546054) (xy 286.659389 -50.538393) (xy 286.577989 -50.523094)
			(xy 286.498365 -50.500288) (xy 286.421208 -50.470175) (xy 286.383984 -50.45202) (xy 286.373658 -50.447458)
			(xy 286.351122 -50.446792) (xy 286.34055 -50.45075) (xy 286.298212 -50.468697) (xy 286.210632 -50.496751)
			(xy 286.120626 -50.51562) (xy 286.029153 -50.525104) (xy 285.983172 -50.52568) (xy 285.940823 -50.525231)
			(xy 285.856509 -50.517178) (xy 285.773342 -50.501146) (xy 285.692075 -50.477282) (xy 285.613445 -50.445801)
			(xy 285.538164 -50.406988) (xy 285.466912 -50.361196) (xy 285.400336 -50.308838) (xy 285.339038 -50.250388)
			(xy 285.283574 -50.186377) (xy 285.234445 -50.117384) (xy 285.192097 -50.044033) (xy 285.156912 -49.966988)
			(xy 285.129211 -49.886948) (xy 285.109243 -49.804638) (xy 285.09719 -49.720802) (xy 285.093159 -49.6362)
			(xy 276.825713 -49.6362) (xy 276.839179 -49.647868) (xy 276.897627 -49.709166) (xy 276.949983 -49.775742)
			(xy 276.995773 -49.846994) (xy 277.034584 -49.922275) (xy 277.066063 -50.000905) (xy 277.089924 -50.082172)
			(xy 277.105953 -50.165338) (xy 277.114004 -50.249652) (xy 277.114508 -50.292) (xy 277.113925 -50.338396)
			(xy 277.10428 -50.430684) (xy 277.085084 -50.521468) (xy 277.056546 -50.609761) (xy 277.038308 -50.652426)
			(xy 277.034502 -50.662368) (xy 277.034502 -50.683632) (xy 277.038308 -50.693574) (xy 277.056553 -50.736236)
			(xy 277.085097 -50.824529) (xy 277.10429 -50.915314) (xy 277.113923 -51.007604) (xy 277.114508 -51.054)
			(xy 277.114004 -51.096348) (xy 277.105953 -51.180662) (xy 277.089924 -51.263828) (xy 277.066063 -51.345095)
			(xy 277.034584 -51.423725) (xy 276.995773 -51.499006) (xy 276.949983 -51.570258) (xy 276.897627 -51.636834)
			(xy 276.839179 -51.698132) (xy 276.775169 -51.753597) (xy 276.706177 -51.802726) (xy 276.632827 -51.845075)
			(xy 276.555784 -51.880259) (xy 276.475745 -51.907961) (xy 276.393436 -51.927929) (xy 276.309601 -51.939982)
			(xy 276.225 -51.944013) (xy 276.140399 -51.939982) (xy 276.056564 -51.927929) (xy 275.974255 -51.907961)
			(xy 275.894216 -51.880259) (xy 275.817173 -51.845075) (xy 275.743823 -51.802726) (xy 275.674831 -51.753597)
			(xy 275.610821 -51.698132) (xy 275.552373 -51.636834) (xy 275.500017 -51.570258) (xy 275.454227 -51.499006)
			(xy 275.415416 -51.423725) (xy 275.383937 -51.345095) (xy 275.360076 -51.263828) (xy 275.344047 -51.180662)
			(xy 275.335996 -51.096348) (xy 275.335492 -51.054) (xy 258.562469 -51.054) (xy 258.550835 -51.059313)
			(xy 258.470773 -51.087022) (xy 258.38844 -51.106996) (xy 258.304581 -51.119053) (xy 258.219956 -51.123085)
			(xy 258.135331 -51.119053) (xy 258.051472 -51.106996) (xy 257.969139 -51.087022) (xy 257.889077 -51.059313)
			(xy 257.812012 -51.024118) (xy 257.738642 -50.981758) (xy 257.66963 -50.932615) (xy 257.605602 -50.877134)
			(xy 257.547137 -50.815819) (xy 257.494766 -50.749223) (xy 257.448963 -50.677951) (xy 257.410141 -50.602648)
			(xy 257.378653 -50.523996) (xy 257.354785 -50.442706) (xy 257.338751 -50.359516) (xy 257.330698 -50.275179)
			(xy 183.639791 -50.275179) (xy 183.639968 -50.292) (xy 183.639527 -50.332047) (xy 183.632353 -50.411819)
			(xy 183.618035 -50.490623) (xy 183.59669 -50.567821) (xy 183.56849 -50.642787) (xy 183.533665 -50.714913)
			(xy 183.492495 -50.783617) (xy 183.445315 -50.84834) (xy 183.419242 -50.87874) (xy 183.413472 -50.885825)
			(xy 183.406964 -50.902886) (xy 183.406542 -50.912014) (xy 183.406542 -50.941986) (xy 183.406985 -50.951108)
			(xy 183.4135 -50.968158) (xy 183.419242 -50.97526) (xy 183.445295 -51.005677) (xy 183.492476 -51.070398)
			(xy 183.533647 -51.139099) (xy 183.568476 -51.211223) (xy 183.59668 -51.286186) (xy 183.61803 -51.363381)
			(xy 183.632355 -51.442183) (xy 183.639537 -51.521953) (xy 183.639968 -51.562) (xy 183.639577 -51.600284)
			(xy 183.633038 -51.676573) (xy 183.619958 -51.752015) (xy 183.600432 -51.826052) (xy 183.587898 -51.862228)
			(xy 183.585245 -51.870664) (xy 183.585245 -51.888336) (xy 183.587898 -51.896772) (xy 183.600422 -51.932951)
			(xy 183.61993 -52.00699) (xy 183.633011 -52.082431) (xy 183.639566 -52.158717) (xy 183.639968 -52.197)
			(xy 183.639464 -52.239348) (xy 183.631413 -52.323662) (xy 183.615384 -52.406828) (xy 183.591523 -52.488095)
			(xy 183.560044 -52.566725) (xy 183.521233 -52.642006) (xy 183.475443 -52.713258) (xy 183.423087 -52.779834)
			(xy 183.364639 -52.841132) (xy 183.300629 -52.896597) (xy 183.231637 -52.945726) (xy 183.158287 -52.988075)
			(xy 183.081244 -53.023259) (xy 183.001205 -53.050961) (xy 182.918896 -53.070929) (xy 182.835061 -53.082982)
			(xy 182.75046 -53.087013) (xy 182.665859 -53.082982) (xy 182.582024 -53.070929) (xy 182.499715 -53.050961)
			(xy 182.419676 -53.023259) (xy 182.342633 -52.988075) (xy 182.269283 -52.945726) (xy 182.200291 -52.896597)
			(xy 182.136281 -52.841132) (xy 182.077833 -52.779834) (xy 182.025477 -52.713258) (xy 181.979687 -52.642006)
			(xy 181.940876 -52.566725) (xy 181.909397 -52.488095) (xy 181.885536 -52.406828) (xy 181.869507 -52.323662)
			(xy 181.861456 -52.239348) (xy 181.860952 -52.197) (xy 178.178968 -52.197) (xy 178.178464 -52.239348)
			(xy 178.170413 -52.323662) (xy 178.154384 -52.406828) (xy 178.130523 -52.488095) (xy 178.099044 -52.566725)
			(xy 178.060233 -52.642006) (xy 178.014443 -52.713258) (xy 177.962087 -52.779834) (xy 177.903639 -52.841132)
			(xy 177.839629 -52.896597) (xy 177.770637 -52.945726) (xy 177.697287 -52.988075) (xy 177.620244 -53.023259)
			(xy 177.540205 -53.050961) (xy 177.457896 -53.070929) (xy 177.374061 -53.082982) (xy 177.28946 -53.087013)
			(xy 177.204859 -53.082982) (xy 177.121024 -53.070929) (xy 177.038715 -53.050961) (xy 176.958676 -53.023259)
			(xy 176.881633 -52.988075) (xy 176.808283 -52.945726) (xy 176.739291 -52.896597) (xy 176.675281 -52.841132)
			(xy 176.616833 -52.779834) (xy 176.564477 -52.713258) (xy 176.518687 -52.642006) (xy 176.479876 -52.566725)
			(xy 176.448397 -52.488095) (xy 176.424536 -52.406828) (xy 176.408507 -52.323662) (xy 176.400456 -52.239348)
			(xy 176.399952 -52.197) (xy 172.720508 -52.197) (xy 172.720004 -52.239348) (xy 172.711953 -52.323662)
			(xy 172.695924 -52.406828) (xy 172.672063 -52.488095) (xy 172.640584 -52.566725) (xy 172.601773 -52.642006)
			(xy 172.555983 -52.713258) (xy 172.503627 -52.779834) (xy 172.445179 -52.841132) (xy 172.381169 -52.896597)
			(xy 172.312177 -52.945726) (xy 172.238827 -52.988075) (xy 172.161784 -53.023259) (xy 172.081745 -53.050961)
			(xy 171.999436 -53.070929) (xy 171.915601 -53.082982) (xy 171.831 -53.087013) (xy 171.746399 -53.082982)
			(xy 171.662564 -53.070929) (xy 171.580255 -53.050961) (xy 171.500216 -53.023259) (xy 171.423173 -52.988075)
			(xy 171.349823 -52.945726) (xy 171.280831 -52.896597) (xy 171.216821 -52.841132) (xy 171.158373 -52.779834)
			(xy 171.106017 -52.713258) (xy 171.060227 -52.642006) (xy 171.021416 -52.566725) (xy 170.989937 -52.488095)
			(xy 170.966076 -52.406828) (xy 170.950047 -52.323662) (xy 170.941996 -52.239348) (xy 170.941492 -52.197)
			(xy 167.259508 -52.197) (xy 167.259004 -52.239348) (xy 167.250953 -52.323662) (xy 167.234924 -52.406828)
			(xy 167.211063 -52.488095) (xy 167.179584 -52.566725) (xy 167.140773 -52.642006) (xy 167.094983 -52.713258)
			(xy 167.042627 -52.779834) (xy 166.984179 -52.841132) (xy 166.920169 -52.896597) (xy 166.851177 -52.945726)
			(xy 166.777827 -52.988075) (xy 166.700784 -53.023259) (xy 166.620745 -53.050961) (xy 166.538436 -53.070929)
			(xy 166.454601 -53.082982) (xy 166.37 -53.087013) (xy 166.285399 -53.082982) (xy 166.201564 -53.070929)
			(xy 166.119255 -53.050961) (xy 166.039216 -53.023259) (xy 165.962173 -52.988075) (xy 165.888823 -52.945726)
			(xy 165.819831 -52.896597) (xy 165.755821 -52.841132) (xy 165.697373 -52.779834) (xy 165.645017 -52.713258)
			(xy 165.599227 -52.642006) (xy 165.560416 -52.566725) (xy 165.528937 -52.488095) (xy 165.505076 -52.406828)
			(xy 165.489047 -52.323662) (xy 165.480996 -52.239348) (xy 165.480492 -52.197) (xy 161.798508 -52.197)
			(xy 161.798004 -52.239348) (xy 161.789953 -52.323662) (xy 161.773924 -52.406828) (xy 161.750063 -52.488095)
			(xy 161.718584 -52.566725) (xy 161.679773 -52.642006) (xy 161.633983 -52.713258) (xy 161.581627 -52.779834)
			(xy 161.523179 -52.841132) (xy 161.459169 -52.896597) (xy 161.390177 -52.945726) (xy 161.316827 -52.988075)
			(xy 161.239784 -53.023259) (xy 161.159745 -53.050961) (xy 161.077436 -53.070929) (xy 160.993601 -53.082982)
			(xy 160.909 -53.087013) (xy 160.824399 -53.082982) (xy 160.740564 -53.070929) (xy 160.658255 -53.050961)
			(xy 160.578216 -53.023259) (xy 160.501173 -52.988075) (xy 160.427823 -52.945726) (xy 160.358831 -52.896597)
			(xy 160.294821 -52.841132) (xy 160.236373 -52.779834) (xy 160.184017 -52.713258) (xy 160.138227 -52.642006)
			(xy 160.099416 -52.566725) (xy 160.067937 -52.488095) (xy 160.044076 -52.406828) (xy 160.028047 -52.323662)
			(xy 160.019996 -52.239348) (xy 160.019492 -52.197) (xy 156.337508 -52.197) (xy 156.337004 -52.239348)
			(xy 156.328953 -52.323662) (xy 156.312924 -52.406828) (xy 156.289063 -52.488095) (xy 156.257584 -52.566725)
			(xy 156.218773 -52.642006) (xy 156.172983 -52.713258) (xy 156.120627 -52.779834) (xy 156.062179 -52.841132)
			(xy 155.998169 -52.896597) (xy 155.929177 -52.945726) (xy 155.855827 -52.988075) (xy 155.778784 -53.023259)
			(xy 155.698745 -53.050961) (xy 155.616436 -53.070929) (xy 155.532601 -53.082982) (xy 155.448 -53.087013)
			(xy 155.363399 -53.082982) (xy 155.279564 -53.070929) (xy 155.197255 -53.050961) (xy 155.117216 -53.023259)
			(xy 155.040173 -52.988075) (xy 154.966823 -52.945726) (xy 154.897831 -52.896597) (xy 154.833821 -52.841132)
			(xy 154.775373 -52.779834) (xy 154.723017 -52.713258) (xy 154.677227 -52.642006) (xy 154.638416 -52.566725)
			(xy 154.606937 -52.488095) (xy 154.583076 -52.406828) (xy 154.567047 -52.323662) (xy 154.558996 -52.239348)
			(xy 154.558492 -52.197) (xy 150.876508 -52.197) (xy 150.876004 -52.239348) (xy 150.867953 -52.323662)
			(xy 150.851924 -52.406828) (xy 150.828063 -52.488095) (xy 150.796584 -52.566725) (xy 150.757773 -52.642006)
			(xy 150.711983 -52.713258) (xy 150.659627 -52.779834) (xy 150.601179 -52.841132) (xy 150.537169 -52.896597)
			(xy 150.468177 -52.945726) (xy 150.394827 -52.988075) (xy 150.317784 -53.023259) (xy 150.237745 -53.050961)
			(xy 150.155436 -53.070929) (xy 150.071601 -53.082982) (xy 149.987 -53.087013) (xy 149.902399 -53.082982)
			(xy 149.818564 -53.070929) (xy 149.736255 -53.050961) (xy 149.656216 -53.023259) (xy 149.579173 -52.988075)
			(xy 149.505823 -52.945726) (xy 149.436831 -52.896597) (xy 149.372821 -52.841132) (xy 149.314373 -52.779834)
			(xy 149.262017 -52.713258) (xy 149.216227 -52.642006) (xy 149.177416 -52.566725) (xy 149.145937 -52.488095)
			(xy 149.122076 -52.406828) (xy 149.106047 -52.323662) (xy 149.097996 -52.239348) (xy 149.097492 -52.197)
			(xy 105.528396 -52.197) (xy 105.530551 -52.209431) (xy 105.537106 -52.285717) (xy 105.537508 -52.324)
			(xy 105.537004 -52.366348) (xy 105.528953 -52.450662) (xy 105.512924 -52.533828) (xy 105.489063 -52.615095)
			(xy 105.457584 -52.693725) (xy 105.418773 -52.769006) (xy 105.372983 -52.840258) (xy 105.320627 -52.906834)
			(xy 105.262179 -52.968132) (xy 105.198169 -53.023597) (xy 105.129177 -53.072726) (xy 105.055827 -53.115075)
			(xy 104.978784 -53.150259) (xy 104.898745 -53.177961) (xy 104.816436 -53.197929) (xy 104.732601 -53.209982)
			(xy 104.648 -53.214013) (xy 104.563399 -53.209982) (xy 104.479564 -53.197929) (xy 104.397255 -53.177961)
			(xy 104.317216 -53.150259) (xy 104.240173 -53.115075) (xy 104.166823 -53.072726) (xy 104.097831 -53.023597)
			(xy 104.033821 -52.968132) (xy 103.975373 -52.906834) (xy 103.923017 -52.840258) (xy 103.877227 -52.769006)
			(xy 103.838416 -52.693725) (xy 103.806937 -52.615095) (xy 103.783076 -52.533828) (xy 103.767047 -52.450662)
			(xy 103.758996 -52.366348) (xy 103.758492 -52.324) (xy 100.076508 -52.324) (xy 100.076004 -52.366348)
			(xy 100.067953 -52.450662) (xy 100.051924 -52.533828) (xy 100.028063 -52.615095) (xy 99.996584 -52.693725)
			(xy 99.957773 -52.769006) (xy 99.911983 -52.840258) (xy 99.859627 -52.906834) (xy 99.801179 -52.968132)
			(xy 99.737169 -53.023597) (xy 99.668177 -53.072726) (xy 99.594827 -53.115075) (xy 99.517784 -53.150259)
			(xy 99.437745 -53.177961) (xy 99.355436 -53.197929) (xy 99.271601 -53.209982) (xy 99.187 -53.214013)
			(xy 99.102399 -53.209982) (xy 99.018564 -53.197929) (xy 98.936255 -53.177961) (xy 98.856216 -53.150259)
			(xy 98.779173 -53.115075) (xy 98.705823 -53.072726) (xy 98.636831 -53.023597) (xy 98.572821 -52.968132)
			(xy 98.514373 -52.906834) (xy 98.462017 -52.840258) (xy 98.416227 -52.769006) (xy 98.377416 -52.693725)
			(xy 98.345937 -52.615095) (xy 98.322076 -52.533828) (xy 98.306047 -52.450662) (xy 98.297996 -52.366348)
			(xy 98.297492 -52.324) (xy 94.615508 -52.324) (xy 94.615004 -52.366348) (xy 94.606953 -52.450662)
			(xy 94.590924 -52.533828) (xy 94.567063 -52.615095) (xy 94.535584 -52.693725) (xy 94.496773 -52.769006)
			(xy 94.450983 -52.840258) (xy 94.398627 -52.906834) (xy 94.340179 -52.968132) (xy 94.276169 -53.023597)
			(xy 94.207177 -53.072726) (xy 94.133827 -53.115075) (xy 94.056784 -53.150259) (xy 93.976745 -53.177961)
			(xy 93.894436 -53.197929) (xy 93.810601 -53.209982) (xy 93.726 -53.214013) (xy 93.641399 -53.209982)
			(xy 93.557564 -53.197929) (xy 93.475255 -53.177961) (xy 93.395216 -53.150259) (xy 93.318173 -53.115075)
			(xy 93.244823 -53.072726) (xy 93.175831 -53.023597) (xy 93.111821 -52.968132) (xy 93.053373 -52.906834)
			(xy 93.001017 -52.840258) (xy 92.955227 -52.769006) (xy 92.916416 -52.693725) (xy 92.884937 -52.615095)
			(xy 92.861076 -52.533828) (xy 92.845047 -52.450662) (xy 92.836996 -52.366348) (xy 92.836492 -52.324)
			(xy 89.154508 -52.324) (xy 89.154004 -52.366348) (xy 89.145953 -52.450662) (xy 89.129924 -52.533828)
			(xy 89.106063 -52.615095) (xy 89.074584 -52.693725) (xy 89.035773 -52.769006) (xy 88.989983 -52.840258)
			(xy 88.937627 -52.906834) (xy 88.879179 -52.968132) (xy 88.815169 -53.023597) (xy 88.746177 -53.072726)
			(xy 88.672827 -53.115075) (xy 88.595784 -53.150259) (xy 88.515745 -53.177961) (xy 88.433436 -53.197929)
			(xy 88.349601 -53.209982) (xy 88.265 -53.214013) (xy 88.180399 -53.209982) (xy 88.096564 -53.197929)
			(xy 88.014255 -53.177961) (xy 87.934216 -53.150259) (xy 87.857173 -53.115075) (xy 87.783823 -53.072726)
			(xy 87.714831 -53.023597) (xy 87.650821 -52.968132) (xy 87.592373 -52.906834) (xy 87.540017 -52.840258)
			(xy 87.494227 -52.769006) (xy 87.455416 -52.693725) (xy 87.423937 -52.615095) (xy 87.400076 -52.533828)
			(xy 87.384047 -52.450662) (xy 87.375996 -52.366348) (xy 87.375492 -52.324) (xy 83.693508 -52.324)
			(xy 83.693004 -52.366348) (xy 83.684953 -52.450662) (xy 83.668924 -52.533828) (xy 83.645063 -52.615095)
			(xy 83.613584 -52.693725) (xy 83.574773 -52.769006) (xy 83.528983 -52.840258) (xy 83.476627 -52.906834)
			(xy 83.418179 -52.968132) (xy 83.354169 -53.023597) (xy 83.285177 -53.072726) (xy 83.211827 -53.115075)
			(xy 83.134784 -53.150259) (xy 83.054745 -53.177961) (xy 82.972436 -53.197929) (xy 82.888601 -53.209982)
			(xy 82.804 -53.214013) (xy 82.719399 -53.209982) (xy 82.635564 -53.197929) (xy 82.553255 -53.177961)
			(xy 82.473216 -53.150259) (xy 82.396173 -53.115075) (xy 82.322823 -53.072726) (xy 82.253831 -53.023597)
			(xy 82.189821 -52.968132) (xy 82.131373 -52.906834) (xy 82.079017 -52.840258) (xy 82.033227 -52.769006)
			(xy 81.994416 -52.693725) (xy 81.962937 -52.615095) (xy 81.939076 -52.533828) (xy 81.923047 -52.450662)
			(xy 81.914996 -52.366348) (xy 81.914492 -52.324) (xy 78.232508 -52.324) (xy 78.232004 -52.366348)
			(xy 78.223953 -52.450662) (xy 78.207924 -52.533828) (xy 78.184063 -52.615095) (xy 78.152584 -52.693725)
			(xy 78.113773 -52.769006) (xy 78.067983 -52.840258) (xy 78.015627 -52.906834) (xy 77.957179 -52.968132)
			(xy 77.893169 -53.023597) (xy 77.824177 -53.072726) (xy 77.750827 -53.115075) (xy 77.673784 -53.150259)
			(xy 77.593745 -53.177961) (xy 77.511436 -53.197929) (xy 77.427601 -53.209982) (xy 77.343 -53.214013)
			(xy 77.258399 -53.209982) (xy 77.174564 -53.197929) (xy 77.092255 -53.177961) (xy 77.012216 -53.150259)
			(xy 76.935173 -53.115075) (xy 76.861823 -53.072726) (xy 76.792831 -53.023597) (xy 76.728821 -52.968132)
			(xy 76.670373 -52.906834) (xy 76.618017 -52.840258) (xy 76.572227 -52.769006) (xy 76.533416 -52.693725)
			(xy 76.501937 -52.615095) (xy 76.478076 -52.533828) (xy 76.462047 -52.450662) (xy 76.453996 -52.366348)
			(xy 76.453492 -52.324) (xy 72.771508 -52.324) (xy 72.771004 -52.366348) (xy 72.762953 -52.450662)
			(xy 72.746924 -52.533828) (xy 72.723063 -52.615095) (xy 72.691584 -52.693725) (xy 72.652773 -52.769006)
			(xy 72.606983 -52.840258) (xy 72.554627 -52.906834) (xy 72.496179 -52.968132) (xy 72.432169 -53.023597)
			(xy 72.363177 -53.072726) (xy 72.289827 -53.115075) (xy 72.212784 -53.150259) (xy 72.132745 -53.177961)
			(xy 72.050436 -53.197929) (xy 71.966601 -53.209982) (xy 71.882 -53.214013) (xy 71.797399 -53.209982)
			(xy 71.713564 -53.197929) (xy 71.631255 -53.177961) (xy 71.551216 -53.150259) (xy 71.474173 -53.115075)
			(xy 71.400823 -53.072726) (xy 71.331831 -53.023597) (xy 71.267821 -52.968132) (xy 71.209373 -52.906834)
			(xy 71.157017 -52.840258) (xy 71.111227 -52.769006) (xy 71.072416 -52.693725) (xy 71.040937 -52.615095)
			(xy 71.017076 -52.533828) (xy 71.001047 -52.450662) (xy 70.992996 -52.366348) (xy 70.992492 -52.324)
			(xy 51.706282 -52.324) (xy 51.700727 -52.350268) (xy 51.672187 -52.438562) (xy 51.653948 -52.481226)
			(xy 51.65014 -52.491168) (xy 51.65014 -52.512432) (xy 51.653948 -52.522374) (xy 51.672195 -52.565035)
			(xy 51.700738 -52.653328) (xy 51.71993 -52.744113) (xy 51.729563 -52.836404) (xy 51.730148 -52.8828)
			(xy 51.729633 -52.923901) (xy 51.722049 -53.005753) (xy 51.706945 -53.086556) (xy 51.684449 -53.165621)
			(xy 51.654755 -53.242273) (xy 51.618115 -53.315858) (xy 51.574842 -53.385749) (xy 51.525305 -53.451349)
			(xy 51.469927 -53.512099) (xy 51.40918 -53.56748) (xy 51.343582 -53.61702) (xy 51.273693 -53.660296)
			(xy 51.20011 -53.696939) (xy 51.123459 -53.726637) (xy 51.044395 -53.749136) (xy 50.963593 -53.764243)
			(xy 50.881741 -53.771832) (xy 50.84064 -53.772308) (xy 50.794245 -53.771711) (xy 50.701957 -53.76207)
			(xy 50.611173 -53.742878) (xy 50.522879 -53.714344) (xy 50.480214 -53.696108) (xy 50.470272 -53.692302)
			(xy 50.449008 -53.692302) (xy 50.439066 -53.696108) (xy 50.396398 -53.71434) (xy 50.308108 -53.742887)
			(xy 50.217325 -53.762084) (xy 50.125036 -53.771721) (xy 50.07864 -53.772308) (xy 50.032245 -53.771711)
			(xy 49.939957 -53.76207) (xy 49.849173 -53.742878) (xy 49.760879 -53.714344) (xy 49.718214 -53.696108)
			(xy 49.708272 -53.692302) (xy 49.687008 -53.692302) (xy 49.677066 -53.696108) (xy 49.634398 -53.71434)
			(xy 49.546108 -53.742887) (xy 49.455325 -53.762084) (xy 49.363036 -53.771721) (xy 49.31664 -53.772308)
			(xy 49.275537 -53.77181) (xy 49.193683 -53.764228) (xy 49.112877 -53.749126) (xy 49.033809 -53.726633)
			(xy 48.957154 -53.69694) (xy 48.883566 -53.6603) (xy 48.813673 -53.617027) (xy 48.748071 -53.567489)
			(xy 48.687319 -53.512109) (xy 48.631937 -53.45136) (xy 48.582396 -53.38576) (xy 48.53912 -53.315869)
			(xy 48.502477 -53.242282) (xy 48.47278 -53.165629) (xy 48.450283 -53.086562) (xy 48.435177 -53.005757)
			(xy 48.427592 -52.923902) (xy 48.427132 -52.8828) (xy 47.945068 -52.8828) (xy 47.945548 -52.9209)
			(xy 47.945044 -52.963248) (xy 47.936993 -53.047562) (xy 47.920964 -53.130728) (xy 47.897103 -53.211995)
			(xy 47.865624 -53.290625) (xy 47.826813 -53.365906) (xy 47.781023 -53.437158) (xy 47.728667 -53.503734)
			(xy 47.670219 -53.565032) (xy 47.606209 -53.620497) (xy 47.537217 -53.669626) (xy 47.463867 -53.711975)
			(xy 47.386824 -53.747159) (xy 47.306785 -53.774861) (xy 47.224476 -53.794829) (xy 47.140641 -53.806882)
			(xy 47.05604 -53.810913) (xy 46.971439 -53.806882) (xy 46.887604 -53.794829) (xy 46.805295 -53.774861)
			(xy 46.725256 -53.747159) (xy 46.648213 -53.711975) (xy 46.574863 -53.669626) (xy 46.505871 -53.620497)
			(xy 46.441861 -53.565032) (xy 46.383413 -53.503734) (xy 46.331057 -53.437158) (xy 46.285267 -53.365906)
			(xy 46.246456 -53.290625) (xy 46.214977 -53.211995) (xy 46.191116 -53.130728) (xy 46.175087 -53.047562)
			(xy 46.167036 -52.963248) (xy 46.166532 -52.9209) (xy 44.986526 -52.9209) (xy 44.977819 -52.930032)
			(xy 44.913809 -52.985497) (xy 44.844817 -53.034626) (xy 44.771467 -53.076975) (xy 44.694424 -53.112159)
			(xy 44.614385 -53.139861) (xy 44.532076 -53.159829) (xy 44.448241 -53.171882) (xy 44.36364 -53.175913)
			(xy 44.279039 -53.171882) (xy 44.195204 -53.159829) (xy 44.112895 -53.139861) (xy 44.032856 -53.112159)
			(xy 43.955813 -53.076975) (xy 43.882463 -53.034626) (xy 43.813471 -52.985497) (xy 43.749461 -52.930032)
			(xy 43.691013 -52.868734) (xy 43.638657 -52.802158) (xy 43.592867 -52.730906) (xy 43.554056 -52.655625)
			(xy 43.522577 -52.576995) (xy 43.498716 -52.495728) (xy 43.482687 -52.412562) (xy 43.474636 -52.328248)
			(xy 43.474132 -52.2859) (xy 0.509016 -52.2859) (xy 0.509016 -54.399942) (xy 3.446023 -54.399942)
			(xy 3.450044 -54.28608) (xy 3.462086 -54.172786) (xy 3.482091 -54.060624) (xy 3.509957 -53.950152)
			(xy 3.545546 -53.84192) (xy 3.588681 -53.736469) (xy 3.639147 -53.634323) (xy 3.696693 -53.535992)
			(xy 3.761032 -53.441964) (xy 3.831843 -53.352709) (xy 3.908773 -53.268672) (xy 3.99144 -53.19027)
			(xy 4.079431 -53.117895) (xy 4.172308 -53.051907) (xy 4.269609 -52.992635) (xy 4.370848 -52.940374)
			(xy 4.475522 -52.895384) (xy 4.583108 -52.85789) (xy 4.693071 -52.828079) (xy 4.804864 -52.806098)
			(xy 4.917928 -52.792058) (xy 5.0317 -52.786028) (xy 5.145615 -52.788039) (xy 5.259104 -52.79808)
			(xy 5.371603 -52.816102) (xy 5.482549 -52.842014) (xy 5.591392 -52.875688) (xy 5.697588 -52.916955)
			(xy 5.800608 -52.965611) (xy 5.89994 -53.021412) (xy 5.995089 -53.084081) (xy 6.085579 -53.153306)
			(xy 6.170961 -53.228741) (xy 6.25081 -53.310012) (xy 6.324727 -53.396712) (xy 6.392343 -53.48841)
			(xy 6.453324 -53.584649) (xy 6.507363 -53.684951) (xy 6.554193 -53.788814) (xy 6.59358 -53.895722)
			(xy 6.625327 -54.005142) (xy 6.649277 -54.116528) (xy 6.665311 -54.229327) (xy 6.673347 -54.342976)
			(xy 6.67385 -54.399942) (xy 6.673347 -54.456908) (xy 6.665311 -54.570557) (xy 6.649277 -54.683356)
			(xy 6.625327 -54.794742) (xy 6.59358 -54.904162) (xy 6.554193 -55.01107) (xy 6.507363 -55.114933)
			(xy 6.453324 -55.215235) (xy 6.392343 -55.311474) (xy 6.324727 -55.403172) (xy 6.25081 -55.489872)
			(xy 6.170961 -55.571143) (xy 6.090758 -55.642002) (xy 37.371528 -55.642002) (xy 37.372032 -55.599654)
			(xy 37.380083 -55.51534) (xy 37.396112 -55.432174) (xy 37.419973 -55.350907) (xy 37.451452 -55.272277)
			(xy 37.490263 -55.196996) (xy 37.536053 -55.125744) (xy 37.588409 -55.059168) (xy 37.646857 -54.99787)
			(xy 37.710867 -54.942405) (xy 37.779859 -54.893276) (xy 37.853209 -54.850927) (xy 37.930252 -54.815743)
			(xy 38.010291 -54.788041) (xy 38.0926 -54.768073) (xy 38.176435 -54.75602) (xy 38.261036 -54.75199)
			(xy 38.345637 -54.75602) (xy 38.429472 -54.768073) (xy 38.511781 -54.788041) (xy 38.59182 -54.815743)
			(xy 38.668863 -54.850927) (xy 38.742213 -54.893276) (xy 38.811205 -54.942405) (xy 38.875215 -54.99787)
			(xy 38.933663 -55.059168) (xy 38.986019 -55.125744) (xy 39.031809 -55.196996) (xy 39.07062 -55.272277)
			(xy 39.102099 -55.350907) (xy 39.12596 -55.432174) (xy 39.141989 -55.51534) (xy 39.15004 -55.599654)
			(xy 39.150544 -55.642002) (xy 39.149888 -55.692156) (xy 39.13869 -55.791837) (xy 39.128192 -55.840884)
			(xy 39.126403 -55.851401) (xy 39.130519 -55.872305) (xy 39.142729 -55.889765) (xy 39.15156 -55.895748)
			(xy 39.188993 -55.918893) (xy 39.259542 -55.971521) (xy 39.324556 -56.030851) (xy 39.383399 -56.096306)
			(xy 39.409878 -56.13146) (xy 39.416788 -56.140033) (xy 39.436031 -56.150694) (xy 39.446962 -56.152034)
			(xy 39.488331 -56.155768) (xy 39.570195 -56.169853) (xy 39.65039 -56.191507) (xy 39.728218 -56.220543)
			(xy 39.802999 -56.256707) (xy 39.874084 -56.299685) (xy 39.940853 -56.349102) (xy 40.002725 -56.404528)
			(xy 40.05916 -56.465481) (xy 40.109668 -56.531428) (xy 40.153809 -56.601797) (xy 40.191198 -56.675974)
			(xy 40.221509 -56.753314) (xy 40.244479 -56.833142) (xy 40.259907 -56.914764) (xy 40.267659 -56.997468)
			(xy 40.268144 -57.039002) (xy 40.267664 -57.082792) (xy 40.259099 -57.169952) (xy 40.242002 -57.255846)
			(xy 40.216539 -57.339643) (xy 40.182958 -57.420528) (xy 40.162734 -57.459372) (xy 40.157312 -57.470837)
			(xy 40.157313 -57.496166) (xy 40.162734 -57.507632) (xy 40.182954 -57.546475) (xy 40.216507 -57.627369)
			(xy 40.241955 -57.711167) (xy 40.259051 -57.797058) (xy 40.267631 -57.884214) (xy 40.268144 -57.928002)
			(xy 40.267664 -57.971792) (xy 40.259099 -58.058952) (xy 40.242002 -58.144846) (xy 40.216539 -58.228643)
			(xy 40.182958 -58.309528) (xy 40.162734 -58.348372) (xy 40.157312 -58.359837) (xy 40.157313 -58.385166)
			(xy 40.162734 -58.396632) (xy 40.182954 -58.435475) (xy 40.216507 -58.516369) (xy 40.241955 -58.600167)
			(xy 40.242899 -58.604912) (xy 40.474392 -58.604912) (xy 40.474903 -58.560519) (xy 40.483698 -58.472169)
			(xy 40.50125 -58.385135) (xy 40.527387 -58.300283) (xy 40.561847 -58.218457) (xy 40.582596 -58.179208)
			(xy 40.586434 -58.171656) (xy 40.589251 -58.154957) (xy 40.586406 -58.138263) (xy 40.582596 -58.130694)
			(xy 40.561847 -58.091445) (xy 40.527387 -58.009619) (xy 40.501251 -57.924767) (xy 40.483698 -57.837733)
			(xy 40.474903 -57.749383) (xy 40.474392 -57.70499) (xy 40.474894 -57.660596) (xy 40.48369 -57.572247)
			(xy 40.501245 -57.485213) (xy 40.527384 -57.400361) (xy 40.561846 -57.318535) (xy 40.582596 -57.279286)
			(xy 40.586376 -57.271708) (xy 40.589213 -57.255026) (xy 40.586393 -57.23834) (xy 40.582596 -57.230772)
			(xy 40.561839 -57.191527) (xy 40.52738 -57.1097) (xy 40.501246 -57.024847) (xy 40.483694 -56.937812)
			(xy 40.474902 -56.849462) (xy 40.474392 -56.805068) (xy 40.474941 -56.760669) (xy 40.483788 -56.672313)
			(xy 40.501391 -56.585278) (xy 40.527575 -56.500428) (xy 40.562079 -56.418608) (xy 40.58285 -56.379364)
			(xy 40.586655 -56.371754) (xy 40.589465 -56.354982) (xy 40.586644 -56.338212) (xy 40.58285 -56.330596)
			(xy 40.56208 -56.291351) (xy 40.527568 -56.209533) (xy 40.501379 -56.124684) (xy 40.483774 -56.037648)
			(xy 40.474928 -55.949291) (xy 40.474392 -55.904892) (xy 40.474795 -55.863896) (xy 40.482332 -55.782251)
			(xy 40.497352 -55.701646) (xy 40.519727 -55.622766) (xy 40.549266 -55.546279) (xy 40.585719 -55.472836)
			(xy 40.628776 -55.40306) (xy 40.678073 -55.337542) (xy 40.73319 -55.276839) (xy 40.79366 -55.221467)
			(xy 40.85897 -55.171895) (xy 40.928564 -55.128544) (xy 41.001853 -55.091782) (xy 41.078215 -55.061921)
			(xy 41.157 -55.039215) (xy 41.237541 -55.023856) (xy 41.278302 -55.019448) (xy 41.294304 -55.017924)
			(xy 41.318434 -54.997604) (xy 41.351708 -54.874922) (xy 41.341294 -54.845204) (xy 41.328086 -54.835806)
			(xy 41.294308 -54.810762) (xy 41.231103 -54.755296) (xy 41.173413 -54.694112) (xy 41.121754 -54.627759)
			(xy 41.076587 -54.556826) (xy 41.038314 -54.481948) (xy 41.007278 -54.403793) (xy 40.983755 -54.323058)
			(xy 40.967956 -54.240463) (xy 40.960021 -54.156746) (xy 40.959532 -54.1147) (xy 40.95995 -54.074933)
			(xy 40.96699 -53.995711) (xy 40.981077 -53.917434) (xy 41.002099 -53.840728) (xy 41.029886 -53.766206)
			(xy 41.046654 -53.730144) (xy 41.050985 -53.719643) (xy 41.050985 -53.696957) (xy 41.046654 -53.686456)
			(xy 41.029913 -53.650383) (xy 41.002132 -53.57586) (xy 40.981109 -53.499157) (xy 40.967012 -53.420884)
			(xy 40.959954 -53.341666) (xy 40.959532 -53.3019) (xy 40.959952 -53.260796) (xy 40.967538 -53.178938)
			(xy 40.982644 -53.098129) (xy 41.005142 -53.019059) (xy 41.03484 -52.942402) (xy 41.071485 -52.868812)
			(xy 41.114763 -52.798917) (xy 41.164306 -52.733314) (xy 41.219691 -52.672563) (xy 41.280445 -52.61718)
			(xy 41.34605 -52.56764) (xy 41.415947 -52.524365) (xy 41.489538 -52.487724) (xy 41.566197 -52.458029)
			(xy 41.645268 -52.435535) (xy 41.726077 -52.420432) (xy 41.807936 -52.41285) (xy 41.84904 -52.412392)
			(xy 41.893805 -52.412911) (xy 41.982887 -52.421844) (xy 42.07062 -52.439686) (xy 42.156115 -52.466255)
			(xy 42.197528 -52.483258) (xy 42.207119 -52.486823) (xy 42.227561 -52.486823) (xy 42.237152 -52.483258)
			(xy 42.278569 -52.466265) (xy 42.364066 -52.439708) (xy 42.451797 -52.421867) (xy 42.540876 -52.412923)
			(xy 42.58564 -52.412392) (xy 42.626743 -52.412828) (xy 42.708598 -52.420417) (xy 42.789404 -52.435526)
			(xy 42.868472 -52.458025) (xy 42.945126 -52.487724) (xy 43.018713 -52.524369) (xy 43.088605 -52.567647)
			(xy 43.154206 -52.617189) (xy 43.214955 -52.672573) (xy 43.270336 -52.733325) (xy 43.319875 -52.798928)
			(xy 43.36315 -52.868822) (xy 43.399792 -52.942411) (xy 43.429487 -53.019066) (xy 43.451984 -53.098134)
			(xy 43.467089 -53.178941) (xy 43.474673 -53.260797) (xy 43.475148 -53.3019) (xy 43.474732 -53.341667)
			(xy 43.467691 -53.42089) (xy 43.453604 -53.499166) (xy 43.432582 -53.575872) (xy 43.404794 -53.650394)
			(xy 43.388026 -53.686456) (xy 43.383691 -53.696957) (xy 43.383691 -53.719643) (xy 43.388026 -53.730144)
			(xy 43.404773 -53.766215) (xy 43.432551 -53.840738) (xy 43.453572 -53.917442) (xy 43.467668 -53.995715)
			(xy 43.474726 -54.074934) (xy 43.475148 -54.1147) (xy 43.474633 -54.155801) (xy 43.467049 -54.237653)
			(xy 43.451945 -54.318456) (xy 43.441263 -54.356) (xy 296.671492 -54.356) (xy 296.672075 -54.309604)
			(xy 296.68172 -54.217316) (xy 296.700916 -54.126532) (xy 296.729454 -54.038239) (xy 296.747692 -53.995574)
			(xy 296.751498 -53.985632) (xy 296.751498 -53.964368) (xy 296.747692 -53.954426) (xy 296.729447 -53.911764)
			(xy 296.700903 -53.823471) (xy 296.68171 -53.732686) (xy 296.672077 -53.640396) (xy 296.671492 -53.594)
			(xy 296.672075 -53.547604) (xy 296.68172 -53.455316) (xy 296.700916 -53.364532) (xy 296.729454 -53.276239)
			(xy 296.747692 -53.233574) (xy 296.751498 -53.223632) (xy 296.751498 -53.202368) (xy 296.747692 -53.192426)
			(xy 296.729447 -53.149764) (xy 296.700903 -53.061471) (xy 296.68171 -52.970686) (xy 296.672077 -52.878396)
			(xy 296.671492 -52.832) (xy 296.672075 -52.785604) (xy 296.68172 -52.693316) (xy 296.700916 -52.602532)
			(xy 296.729454 -52.514239) (xy 296.747692 -52.471574) (xy 296.751498 -52.461632) (xy 296.751498 -52.440368)
			(xy 296.747692 -52.430426) (xy 296.729447 -52.387764) (xy 296.700903 -52.299471) (xy 296.68171 -52.208686)
			(xy 296.672077 -52.116396) (xy 296.671492 -52.07) (xy 296.671967 -52.028898) (xy 296.679552 -51.947043)
			(xy 296.694657 -51.866238) (xy 296.717153 -51.787171) (xy 296.746849 -51.710517) (xy 296.783491 -51.63693)
			(xy 296.826766 -51.567038) (xy 296.876306 -51.501437) (xy 296.931687 -51.440687) (xy 296.992437 -51.385306)
			(xy 297.058038 -51.335766) (xy 297.12793 -51.292491) (xy 297.201517 -51.255849) (xy 297.278171 -51.226153)
			(xy 297.357238 -51.203657) (xy 297.438043 -51.188552) (xy 297.519898 -51.180967) (xy 297.561 -51.180492)
			(xy 297.607396 -51.181075) (xy 297.699684 -51.19072) (xy 297.790468 -51.209916) (xy 297.878761 -51.238454)
			(xy 297.921426 -51.256692) (xy 297.931368 -51.260498) (xy 297.952632 -51.260498) (xy 297.962574 -51.256692)
			(xy 298.005236 -51.238447) (xy 298.093529 -51.209903) (xy 298.184314 -51.19071) (xy 298.276604 -51.181077)
			(xy 298.323 -51.180492) (xy 298.364102 -51.180967) (xy 298.445957 -51.188552) (xy 298.526762 -51.203657)
			(xy 298.605829 -51.226153) (xy 298.682483 -51.255849) (xy 298.75607 -51.292491) (xy 298.825962 -51.335766)
			(xy 298.891563 -51.385306) (xy 298.952313 -51.440687) (xy 299.007694 -51.501437) (xy 299.057234 -51.567038)
			(xy 299.100509 -51.63693) (xy 299.137151 -51.710517) (xy 299.166847 -51.787171) (xy 299.189343 -51.866238)
			(xy 299.204448 -51.947043) (xy 299.212033 -52.028898) (xy 299.212508 -52.07) (xy 299.211925 -52.116396)
			(xy 299.20228 -52.208684) (xy 299.183084 -52.299468) (xy 299.154546 -52.387761) (xy 299.136308 -52.430426)
			(xy 299.132502 -52.440368) (xy 299.132502 -52.461632) (xy 299.136308 -52.471574) (xy 299.154553 -52.514236)
			(xy 299.183097 -52.602529) (xy 299.20229 -52.693314) (xy 299.211923 -52.785604) (xy 299.212508 -52.832)
			(xy 299.211925 -52.878396) (xy 299.20228 -52.970684) (xy 299.183084 -53.061468) (xy 299.154546 -53.149761)
			(xy 299.136308 -53.192426) (xy 299.132502 -53.202368) (xy 299.132502 -53.223632) (xy 299.136308 -53.233574)
			(xy 299.154553 -53.276236) (xy 299.183097 -53.364529) (xy 299.20229 -53.455314) (xy 299.211923 -53.547604)
			(xy 299.212508 -53.594) (xy 299.211925 -53.640396) (xy 299.20228 -53.732684) (xy 299.183084 -53.823468)
			(xy 299.154546 -53.911761) (xy 299.136308 -53.954426) (xy 299.132502 -53.964368) (xy 299.132502 -53.985632)
			(xy 299.136308 -53.995574) (xy 299.154553 -54.038236) (xy 299.183097 -54.126529) (xy 299.20229 -54.217314)
			(xy 299.211923 -54.309604) (xy 299.212508 -54.356) (xy 299.212033 -54.397102) (xy 299.204448 -54.478957)
			(xy 299.189343 -54.559762) (xy 299.166847 -54.638829) (xy 299.137151 -54.715483) (xy 299.100509 -54.78907)
			(xy 299.057234 -54.858962) (xy 299.007694 -54.924563) (xy 298.952313 -54.985313) (xy 298.891563 -55.040694)
			(xy 298.825962 -55.090234) (xy 298.75607 -55.133509) (xy 298.682483 -55.170151) (xy 298.605829 -55.199847)
			(xy 298.526762 -55.222343) (xy 298.445957 -55.237448) (xy 298.364102 -55.245033) (xy 298.323 -55.245508)
			(xy 298.276604 -55.244925) (xy 298.184316 -55.23528) (xy 298.093532 -55.216084) (xy 298.005239 -55.187546)
			(xy 297.962574 -55.169308) (xy 297.952632 -55.165502) (xy 297.931368 -55.165502) (xy 297.921426 -55.169308)
			(xy 297.878764 -55.187553) (xy 297.790471 -55.216097) (xy 297.699686 -55.23529) (xy 297.607396 -55.244923)
			(xy 297.561 -55.245508) (xy 297.519898 -55.245033) (xy 297.438043 -55.237448) (xy 297.357238 -55.222343)
			(xy 297.278171 -55.199847) (xy 297.201517 -55.170151) (xy 297.12793 -55.133509) (xy 297.058038 -55.090234)
			(xy 296.992437 -55.040694) (xy 296.931687 -54.985313) (xy 296.876306 -54.924563) (xy 296.826766 -54.858962)
			(xy 296.783491 -54.78907) (xy 296.746849 -54.715483) (xy 296.717153 -54.638829) (xy 296.694657 -54.559762)
			(xy 296.679552 -54.478957) (xy 296.671967 -54.397102) (xy 296.671492 -54.356) (xy 43.441263 -54.356)
			(xy 43.429449 -54.397521) (xy 43.399755 -54.474173) (xy 43.363115 -54.547758) (xy 43.319842 -54.617649)
			(xy 43.270305 -54.683249) (xy 43.214927 -54.743999) (xy 43.15418 -54.79938) (xy 43.088582 -54.84892)
			(xy 43.018693 -54.892196) (xy 42.94511 -54.928839) (xy 42.868459 -54.958537) (xy 42.789395 -54.981036)
			(xy 42.708593 -54.996143) (xy 42.626741 -55.003732) (xy 42.58564 -55.004208) (xy 42.540875 -55.003695)
			(xy 42.451793 -54.994761) (xy 42.36406 -54.976917) (xy 42.278565 -54.950346) (xy 42.237152 -54.933342)
			(xy 42.227561 -54.929777) (xy 42.207119 -54.929777) (xy 42.197528 -54.933342) (xy 42.182542 -54.939438)
			(xy 42.17275 -54.944035) (xy 42.157834 -54.959663) (xy 42.150643 -54.980036) (xy 42.152446 -55.001564)
			(xy 42.162924 -55.020457) (xy 42.180232 -55.033387) (xy 42.19067 -55.036212) (xy 42.232544 -55.046034)
			(xy 42.314349 -55.072611) (xy 42.393207 -55.106959) (xy 42.468382 -55.148756) (xy 42.539173 -55.197614)
			(xy 42.604918 -55.253075) (xy 42.665004 -55.314623) (xy 42.718869 -55.381682) (xy 42.766012 -55.453626)
			(xy 42.805991 -55.529784) (xy 42.838434 -55.609444) (xy 42.863037 -55.691864) (xy 42.879572 -55.776274)
			(xy 42.887883 -55.861885) (xy 42.888408 -55.904892) (xy 42.887885 -55.949292) (xy 42.879032 -56.037648)
			(xy 42.861423 -56.124684) (xy 42.835233 -56.209533) (xy 42.800723 -56.291352) (xy 42.77995 -56.330596)
			(xy 42.776174 -56.338218) (xy 42.773354 -56.354982) (xy 42.776163 -56.371748) (xy 42.77995 -56.379364)
			(xy 42.800704 -56.418617) (xy 42.835219 -56.500433) (xy 42.861411 -56.585279) (xy 42.87902 -56.672314)
			(xy 42.88787 -56.760669) (xy 42.888408 -56.805068) (xy 42.887888 -56.849461) (xy 42.879096 -56.93781)
			(xy 42.861545 -57.024844) (xy 42.83541 -57.109696) (xy 42.800952 -57.191523) (xy 42.780204 -57.230772)
			(xy 42.774742 -57.242292) (xy 42.774755 -57.267758) (xy 42.780204 -57.279286) (xy 42.800945 -57.318539)
			(xy 42.835407 -57.400364) (xy 42.861545 -57.485215) (xy 42.8791 -57.572248) (xy 42.887896 -57.660597)
			(xy 42.888408 -57.70499) (xy 42.887898 -57.749383) (xy 42.879103 -57.837733) (xy 42.86155 -57.924767)
			(xy 42.835413 -58.009619) (xy 42.800953 -58.091445) (xy 42.780204 -58.130694) (xy 42.774796 -58.142234)
			(xy 42.774774 -58.167681) (xy 42.780204 -58.179208) (xy 42.800954 -58.218457) (xy 42.835413 -58.300283)
			(xy 42.86155 -58.385135) (xy 42.879103 -58.472169) (xy 42.887897 -58.560519) (xy 42.888408 -58.604912)
			(xy 42.887945 -58.646015) (xy 42.880359 -58.727869) (xy 42.865253 -58.808675) (xy 42.842755 -58.887742)
			(xy 42.813058 -58.964396) (xy 42.776416 -59.037983) (xy 42.733139 -59.107875) (xy 42.683599 -59.173476)
			(xy 42.628217 -59.234226) (xy 42.567466 -59.289607) (xy 42.501865 -59.339146) (xy 42.431972 -59.382421)
			(xy 42.358385 -59.419063) (xy 42.28173 -59.448759) (xy 42.202663 -59.471255) (xy 42.121857 -59.48636)
			(xy 42.040003 -59.493945) (xy 41.9989 -59.49442) (xy 41.960616 -59.494032) (xy 41.884327 -59.487493)
			(xy 41.808885 -59.474411) (xy 41.734848 -59.454885) (xy 41.698672 -59.44235) (xy 41.690235 -59.439699)
			(xy 41.672565 -59.439699) (xy 41.664128 -59.44235) (xy 41.62795 -59.454876) (xy 41.55391 -59.474383)
			(xy 41.478469 -59.487463) (xy 41.402183 -59.494018) (xy 41.3639 -59.49442) (xy 41.322798 -59.493933)
			(xy 41.240944 -59.486349) (xy 41.16014 -59.471244) (xy 41.081073 -59.448748) (xy 41.00442 -59.419052)
			(xy 40.930834 -59.382411) (xy 40.860942 -59.339136) (xy 40.795341 -59.289598) (xy 40.734591 -59.234217)
			(xy 40.67921 -59.173468) (xy 40.62967 -59.107868) (xy 40.586395 -59.037977) (xy 40.549753 -58.964391)
			(xy 40.520056 -58.887738) (xy 40.497559 -58.808672) (xy 40.482453 -58.727868) (xy 40.474867 -58.646014)
			(xy 40.474392 -58.604912) (xy 40.242899 -58.604912) (xy 40.259051 -58.686058) (xy 40.267631 -58.773214)
			(xy 40.268144 -58.817002) (xy 40.267689 -58.858109) (xy 40.260105 -58.939973) (xy 40.245 -59.020789)
			(xy 40.222505 -59.099866) (xy 40.19281 -59.17653) (xy 40.156169 -59.250129) (xy 40.112895 -59.320033)
			(xy 40.063357 -59.385647) (xy 40.007977 -59.446411) (xy 39.947227 -59.501807) (xy 39.881626 -59.551363)
			(xy 39.811733 -59.594655) (xy 39.738145 -59.631315) (xy 39.661488 -59.66103) (xy 39.582416 -59.683546)
			(xy 39.501605 -59.698672) (xy 39.419743 -59.706279) (xy 39.378636 -59.706764) (xy 39.336929 -59.706247)
			(xy 39.253882 -59.698432) (xy 39.17193 -59.682877) (xy 39.091796 -59.659718) (xy 39.014181 -59.629158)
			(xy 38.939768 -59.591467) (xy 38.86921 -59.546974) (xy 38.803128 -59.496072) (xy 38.742101 -59.439206)
			(xy 38.686666 -59.376878) (xy 38.661594 -59.343544) (xy 38.654652 -59.335001) (xy 38.635433 -59.324324)
			(xy 38.62451 -59.32297) (xy 38.583139 -59.319256) (xy 38.501275 -59.305169) (xy 38.42108 -59.283512)
			(xy 38.343252 -59.254474) (xy 38.268471 -59.218308) (xy 38.197386 -59.175329) (xy 38.130618 -59.12591)
			(xy 38.068746 -59.070482) (xy 38.012311 -59.009529) (xy 37.961804 -58.94358) (xy 37.917663 -58.873211)
			(xy 37.880275 -58.799033) (xy 37.849964 -58.721692) (xy 37.826994 -58.641864) (xy 37.811565 -58.560241)
			(xy 37.803813 -58.477536) (xy 37.803328 -58.436002) (xy 37.803813 -58.392212) (xy 37.812377 -58.305053)
			(xy 37.829473 -58.219158) (xy 37.854935 -58.135362) (xy 37.888515 -58.054476) (xy 37.908738 -58.015632)
			(xy 37.914152 -58.004165) (xy 37.914153 -57.978839) (xy 37.908738 -57.967372) (xy 37.888517 -57.928529)
			(xy 37.854964 -57.847635) (xy 37.829517 -57.763837) (xy 37.812421 -57.677946) (xy 37.803841 -57.59079)
			(xy 37.803328 -57.547002) (xy 37.803813 -57.503212) (xy 37.812377 -57.416053) (xy 37.829473 -57.330158)
			(xy 37.854935 -57.246362) (xy 37.888515 -57.165476) (xy 37.908738 -57.126632) (xy 37.914152 -57.115165)
			(xy 37.914153 -57.089839) (xy 37.908738 -57.078372) (xy 37.888517 -57.039529) (xy 37.854964 -56.958635)
			(xy 37.829517 -56.874837) (xy 37.812421 -56.788946) (xy 37.803841 -56.70179) (xy 37.803328 -56.658002)
			(xy 37.803969 -56.607847) (xy 37.815177 -56.508167) (xy 37.82568 -56.45912) (xy 37.827479 -56.448604)
			(xy 37.823362 -56.427696) (xy 37.811147 -56.410236) (xy 37.802312 -56.404256) (xy 37.766912 -56.382369)
			(xy 37.699929 -56.332962) (xy 37.637853 -56.277515) (xy 37.581226 -56.216513) (xy 37.530544 -56.15049)
			(xy 37.48625 -56.080021) (xy 37.44873 -56.005724) (xy 37.418313 -55.928248) (xy 37.395264 -55.84827)
			(xy 37.379785 -55.766488) (xy 37.372012 -55.683619) (xy 37.371528 -55.642002) (xy 6.090758 -55.642002)
			(xy 6.085579 -55.646578) (xy 5.995089 -55.715803) (xy 5.89994 -55.778472) (xy 5.800608 -55.834273)
			(xy 5.697588 -55.882929) (xy 5.591392 -55.924196) (xy 5.482549 -55.95787) (xy 5.371603 -55.983782)
			(xy 5.259104 -56.001804) (xy 5.145615 -56.011845) (xy 5.0317 -56.013856) (xy 4.917928 -56.007826)
			(xy 4.804864 -55.993786) (xy 4.693071 -55.971805) (xy 4.583108 -55.941994) (xy 4.475522 -55.9045)
			(xy 4.370848 -55.85951) (xy 4.269609 -55.807249) (xy 4.172308 -55.747977) (xy 4.079431 -55.681989)
			(xy 3.99144 -55.609614) (xy 3.908773 -55.531212) (xy 3.831843 -55.447175) (xy 3.761032 -55.35792)
			(xy 3.696693 -55.263892) (xy 3.639147 -55.165561) (xy 3.588681 -55.063415) (xy 3.545546 -54.957964)
			(xy 3.509957 -54.849732) (xy 3.482091 -54.73926) (xy 3.462086 -54.627098) (xy 3.450044 -54.513804)
			(xy 3.446023 -54.399942) (xy 0.509016 -54.399942) (xy 0.509016 -60.96) (xy 66.673737 -60.96) (xy 66.677742 -60.854251)
			(xy 66.689732 -60.749108) (xy 66.709641 -60.645173) (xy 66.737352 -60.543041) (xy 66.772709 -60.443297)
			(xy 66.815507 -60.346513) (xy 66.865503 -60.253243) (xy 66.92241 -60.164022) (xy 66.985901 -60.079359)
			(xy 67.055613 -59.999741) (xy 67.131147 -59.925623) (xy 67.21207 -59.85743) (xy 67.297919 -59.795552)
			(xy 67.388202 -59.740345) (xy 67.482401 -59.692123) (xy 67.579978 -59.651163) (xy 67.680373 -59.617701)
			(xy 67.783011 -59.591927) (xy 67.887304 -59.573989) (xy 67.992655 -59.56399) (xy 68.098461 -59.561987)
			(xy 68.204115 -59.567992) (xy 68.309012 -59.581971) (xy 68.412552 -59.603842) (xy 68.514141 -59.633482)
			(xy 68.613198 -59.67072) (xy 68.709155 -59.715342) (xy 68.801462 -59.767094) (xy 68.889591 -59.825679)
			(xy 68.973037 -59.890761) (xy 69.051321 -59.961967) (xy 69.123996 -60.03889) (xy 69.190646 -60.12109)
			(xy 69.250888 -60.208094) (xy 69.304377 -60.299405) (xy 69.350808 -60.3945) (xy 69.389913 -60.492834)
			(xy 69.42147 -60.593845) (xy 69.445297 -60.696952) (xy 69.461258 -60.801566) (xy 69.469262 -60.907088)
			(xy 69.469762 -60.96) (xy 77.976737 -60.96) (xy 77.980742 -60.854251) (xy 77.992732 -60.749108) (xy 78.012641 -60.645173)
			(xy 78.040352 -60.543041) (xy 78.075709 -60.443297) (xy 78.118507 -60.346513) (xy 78.168503 -60.253243)
			(xy 78.22541 -60.164022) (xy 78.288901 -60.079359) (xy 78.358613 -59.999741) (xy 78.434147 -59.925623)
			(xy 78.51507 -59.85743) (xy 78.600919 -59.795552) (xy 78.691202 -59.740345) (xy 78.785401 -59.692123)
			(xy 78.882978 -59.651163) (xy 78.983373 -59.617701) (xy 79.086011 -59.591927) (xy 79.190304 -59.573989)
			(xy 79.295655 -59.56399) (xy 79.401461 -59.561987) (xy 79.507115 -59.567992) (xy 79.612012 -59.581971)
			(xy 79.715552 -59.603842) (xy 79.817141 -59.633482) (xy 79.916198 -59.67072) (xy 80.012155 -59.715342)
			(xy 80.104462 -59.767094) (xy 80.192591 -59.825679) (xy 80.276037 -59.890761) (xy 80.354321 -59.961967)
			(xy 80.426996 -60.03889) (xy 80.493646 -60.12109) (xy 80.553888 -60.208094) (xy 80.607377 -60.299405)
			(xy 80.653808 -60.3945) (xy 80.692913 -60.492834) (xy 80.72447 -60.593845) (xy 80.748297 -60.696952)
			(xy 80.764258 -60.801566) (xy 80.772262 -60.907088) (xy 80.772762 -60.96) (xy 89.279737 -60.96) (xy 89.283742 -60.854251)
			(xy 89.295732 -60.749108) (xy 89.315641 -60.645173) (xy 89.343352 -60.543041) (xy 89.378709 -60.443297)
			(xy 89.421507 -60.346513) (xy 89.471503 -60.253243) (xy 89.52841 -60.164022) (xy 89.591901 -60.079359)
			(xy 89.661613 -59.999741) (xy 89.737147 -59.925623) (xy 89.81807 -59.85743) (xy 89.903919 -59.795552)
			(xy 89.994202 -59.740345) (xy 90.088401 -59.692123) (xy 90.185978 -59.651163) (xy 90.286373 -59.617701)
			(xy 90.389011 -59.591927) (xy 90.493304 -59.573989) (xy 90.598655 -59.56399) (xy 90.704461 -59.561987)
			(xy 90.810115 -59.567992) (xy 90.915012 -59.581971) (xy 91.018552 -59.603842) (xy 91.120141 -59.633482)
			(xy 91.219198 -59.67072) (xy 91.315155 -59.715342) (xy 91.407462 -59.767094) (xy 91.495591 -59.825679)
			(xy 91.579037 -59.890761) (xy 91.657321 -59.961967) (xy 91.729996 -60.03889) (xy 91.796646 -60.12109)
			(xy 91.856888 -60.208094) (xy 91.910377 -60.299405) (xy 91.956808 -60.3945) (xy 91.995913 -60.492834)
			(xy 92.02747 -60.593845) (xy 92.051297 -60.696952) (xy 92.067258 -60.801566) (xy 92.075262 -60.907088)
			(xy 92.075762 -60.96) (xy 107.440737 -60.96) (xy 107.444742 -60.854251) (xy 107.456732 -60.749108)
			(xy 107.476641 -60.645173) (xy 107.504352 -60.543041) (xy 107.539709 -60.443297) (xy 107.582507 -60.346513)
			(xy 107.632503 -60.253243) (xy 107.68941 -60.164022) (xy 107.752901 -60.079359) (xy 107.822613 -59.999741)
			(xy 107.898147 -59.925623) (xy 107.97907 -59.85743) (xy 108.064919 -59.795552) (xy 108.155202 -59.740345)
			(xy 108.249401 -59.692123) (xy 108.346978 -59.651163) (xy 108.447373 -59.617701) (xy 108.550011 -59.591927)
			(xy 108.654304 -59.573989) (xy 108.759655 -59.56399) (xy 108.865461 -59.561987) (xy 108.971115 -59.567992)
			(xy 109.076012 -59.581971) (xy 109.179552 -59.603842) (xy 109.281141 -59.633482) (xy 109.380198 -59.67072)
			(xy 109.476155 -59.715342) (xy 109.568462 -59.767094) (xy 109.656591 -59.825679) (xy 109.740037 -59.890761)
			(xy 109.818321 -59.961967) (xy 109.890996 -60.03889) (xy 109.957646 -60.12109) (xy 110.017888 -60.208094)
			(xy 110.071377 -60.299405) (xy 110.117808 -60.3945) (xy 110.156913 -60.492834) (xy 110.18847 -60.593845)
			(xy 110.212297 -60.696952) (xy 110.228258 -60.801566) (xy 110.236262 -60.907088) (xy 110.236762 -60.96)
			(xy 118.616737 -60.96) (xy 118.620742 -60.854251) (xy 118.632732 -60.749108) (xy 118.652641 -60.645173)
			(xy 118.680352 -60.543041) (xy 118.715709 -60.443297) (xy 118.758507 -60.346513) (xy 118.808503 -60.253243)
			(xy 118.86541 -60.164022) (xy 118.928901 -60.079359) (xy 118.998613 -59.999741) (xy 119.074147 -59.925623)
			(xy 119.15507 -59.85743) (xy 119.240919 -59.795552) (xy 119.331202 -59.740345) (xy 119.425401 -59.692123)
			(xy 119.522978 -59.651163) (xy 119.623373 -59.617701) (xy 119.726011 -59.591927) (xy 119.830304 -59.573989)
			(xy 119.935655 -59.56399) (xy 120.041461 -59.561987) (xy 120.147115 -59.567992) (xy 120.252012 -59.581971)
			(xy 120.355552 -59.603842) (xy 120.457141 -59.633482) (xy 120.556198 -59.67072) (xy 120.652155 -59.715342)
			(xy 120.744462 -59.767094) (xy 120.832591 -59.825679) (xy 120.916037 -59.890761) (xy 120.994321 -59.961967)
			(xy 121.066996 -60.03889) (xy 121.133646 -60.12109) (xy 121.193888 -60.208094) (xy 121.247377 -60.299405)
			(xy 121.293808 -60.3945) (xy 121.332913 -60.492834) (xy 121.36447 -60.593845) (xy 121.388297 -60.696952)
			(xy 121.404258 -60.801566) (xy 121.412262 -60.907088) (xy 121.412762 -60.96) (xy 129.792737 -60.96)
			(xy 129.796742 -60.854251) (xy 129.808732 -60.749108) (xy 129.828641 -60.645173) (xy 129.856352 -60.543041)
			(xy 129.891709 -60.443297) (xy 129.934507 -60.346513) (xy 129.984503 -60.253243) (xy 130.04141 -60.164022)
			(xy 130.104901 -60.079359) (xy 130.174613 -59.999741) (xy 130.250147 -59.925623) (xy 130.33107 -59.85743)
			(xy 130.416919 -59.795552) (xy 130.507202 -59.740345) (xy 130.601401 -59.692123) (xy 130.698978 -59.651163)
			(xy 130.799373 -59.617701) (xy 130.902011 -59.591927) (xy 131.006304 -59.573989) (xy 131.111655 -59.56399)
			(xy 131.217461 -59.561987) (xy 131.323115 -59.567992) (xy 131.428012 -59.581971) (xy 131.531552 -59.603842)
			(xy 131.633141 -59.633482) (xy 131.732198 -59.67072) (xy 131.828155 -59.715342) (xy 131.920462 -59.767094)
			(xy 132.008591 -59.825679) (xy 132.092037 -59.890761) (xy 132.170321 -59.961967) (xy 132.242996 -60.03889)
			(xy 132.309646 -60.12109) (xy 132.369888 -60.208094) (xy 132.423377 -60.299405) (xy 132.469808 -60.3945)
			(xy 132.508913 -60.492834) (xy 132.54047 -60.593845) (xy 132.564297 -60.696952) (xy 132.580258 -60.801566)
			(xy 132.588262 -60.907088) (xy 132.588762 -60.96) (xy 145.540737 -60.96) (xy 145.544742 -60.854251)
			(xy 145.556732 -60.749108) (xy 145.576641 -60.645173) (xy 145.604352 -60.543041) (xy 145.639709 -60.443297)
			(xy 145.682507 -60.346513) (xy 145.732503 -60.253243) (xy 145.78941 -60.164022) (xy 145.852901 -60.079359)
			(xy 145.922613 -59.999741) (xy 145.998147 -59.925623) (xy 146.07907 -59.85743) (xy 146.164919 -59.795552)
			(xy 146.255202 -59.740345) (xy 146.349401 -59.692123) (xy 146.446978 -59.651163) (xy 146.547373 -59.617701)
			(xy 146.650011 -59.591927) (xy 146.754304 -59.573989) (xy 146.859655 -59.56399) (xy 146.965461 -59.561987)
			(xy 147.071115 -59.567992) (xy 147.176012 -59.581971) (xy 147.279552 -59.603842) (xy 147.381141 -59.633482)
			(xy 147.480198 -59.67072) (xy 147.576155 -59.715342) (xy 147.668462 -59.767094) (xy 147.756591 -59.825679)
			(xy 147.840037 -59.890761) (xy 147.918321 -59.961967) (xy 147.990996 -60.03889) (xy 148.057646 -60.12109)
			(xy 148.117888 -60.208094) (xy 148.171377 -60.299405) (xy 148.217808 -60.3945) (xy 148.256913 -60.492834)
			(xy 148.28847 -60.593845) (xy 148.312297 -60.696952) (xy 148.328258 -60.801566) (xy 148.336262 -60.907088)
			(xy 148.336762 -60.96) (xy 156.716737 -60.96) (xy 156.720742 -60.854251) (xy 156.732732 -60.749108)
			(xy 156.752641 -60.645173) (xy 156.780352 -60.543041) (xy 156.815709 -60.443297) (xy 156.858507 -60.346513)
			(xy 156.908503 -60.253243) (xy 156.96541 -60.164022) (xy 157.028901 -60.079359) (xy 157.098613 -59.999741)
			(xy 157.174147 -59.925623) (xy 157.25507 -59.85743) (xy 157.340919 -59.795552) (xy 157.431202 -59.740345)
			(xy 157.525401 -59.692123) (xy 157.622978 -59.651163) (xy 157.723373 -59.617701) (xy 157.826011 -59.591927)
			(xy 157.930304 -59.573989) (xy 158.035655 -59.56399) (xy 158.141461 -59.561987) (xy 158.247115 -59.567992)
			(xy 158.352012 -59.581971) (xy 158.455552 -59.603842) (xy 158.557141 -59.633482) (xy 158.656198 -59.67072)
			(xy 158.752155 -59.715342) (xy 158.844462 -59.767094) (xy 158.932591 -59.825679) (xy 159.016037 -59.890761)
			(xy 159.094321 -59.961967) (xy 159.166996 -60.03889) (xy 159.233646 -60.12109) (xy 159.293888 -60.208094)
			(xy 159.347377 -60.299405) (xy 159.393808 -60.3945) (xy 159.432913 -60.492834) (xy 159.46447 -60.593845)
			(xy 159.488297 -60.696952) (xy 159.504258 -60.801566) (xy 159.512262 -60.907088) (xy 159.512762 -60.96)
			(xy 167.892737 -60.96) (xy 167.896742 -60.854251) (xy 167.908732 -60.749108) (xy 167.928641 -60.645173)
			(xy 167.956352 -60.543041) (xy 167.991709 -60.443297) (xy 168.034507 -60.346513) (xy 168.084503 -60.253243)
			(xy 168.14141 -60.164022) (xy 168.204901 -60.079359) (xy 168.274613 -59.999741) (xy 168.350147 -59.925623)
			(xy 168.43107 -59.85743) (xy 168.516919 -59.795552) (xy 168.607202 -59.740345) (xy 168.701401 -59.692123)
			(xy 168.798978 -59.651163) (xy 168.899373 -59.617701) (xy 169.002011 -59.591927) (xy 169.106304 -59.573989)
			(xy 169.211655 -59.56399) (xy 169.317461 -59.561987) (xy 169.423115 -59.567992) (xy 169.528012 -59.581971)
			(xy 169.631552 -59.603842) (xy 169.733141 -59.633482) (xy 169.832198 -59.67072) (xy 169.928155 -59.715342)
			(xy 170.020462 -59.767094) (xy 170.108591 -59.825679) (xy 170.192037 -59.890761) (xy 170.270321 -59.961967)
			(xy 170.342996 -60.03889) (xy 170.409646 -60.12109) (xy 170.469888 -60.208094) (xy 170.523377 -60.299405)
			(xy 170.569808 -60.3945) (xy 170.608913 -60.492834) (xy 170.64047 -60.593845) (xy 170.664297 -60.696952)
			(xy 170.680258 -60.801566) (xy 170.688262 -60.907088) (xy 170.688762 -60.96) (xy 185.540911 -60.96)
			(xy 185.544916 -60.854251) (xy 185.556906 -60.749108) (xy 185.576815 -60.645173) (xy 185.604526 -60.543041)
			(xy 185.639883 -60.443297) (xy 185.682681 -60.346513) (xy 185.732677 -60.253243) (xy 185.789584 -60.164022)
			(xy 185.853075 -60.079359) (xy 185.922787 -59.999741) (xy 185.998321 -59.925623) (xy 186.079244 -59.85743)
			(xy 186.165093 -59.795552) (xy 186.255376 -59.740345) (xy 186.349575 -59.692123) (xy 186.447152 -59.651163)
			(xy 186.547547 -59.617701) (xy 186.650185 -59.591927) (xy 186.754478 -59.573989) (xy 186.859829 -59.56399)
			(xy 186.965635 -59.561987) (xy 187.071289 -59.567992) (xy 187.176186 -59.581971) (xy 187.279726 -59.603842)
			(xy 187.381315 -59.633482) (xy 187.480372 -59.67072) (xy 187.576329 -59.715342) (xy 187.668636 -59.767094)
			(xy 187.756765 -59.825679) (xy 187.840211 -59.890761) (xy 187.918495 -59.961967) (xy 187.99117 -60.03889)
			(xy 188.05782 -60.12109) (xy 188.118062 -60.208094) (xy 188.171551 -60.299405) (xy 188.217982 -60.3945)
			(xy 188.257087 -60.492834) (xy 188.288644 -60.593845) (xy 188.312471 -60.696952) (xy 188.328432 -60.801566)
			(xy 188.336436 -60.907088) (xy 188.336936 -60.96) (xy 196.716911 -60.96) (xy 196.720916 -60.854251)
			(xy 196.732906 -60.749108) (xy 196.752815 -60.645173) (xy 196.780526 -60.543041) (xy 196.815883 -60.443297)
			(xy 196.858681 -60.346513) (xy 196.908677 -60.253243) (xy 196.965584 -60.164022) (xy 197.029075 -60.079359)
			(xy 197.098787 -59.999741) (xy 197.174321 -59.925623) (xy 197.255244 -59.85743) (xy 197.341093 -59.795552)
			(xy 197.431376 -59.740345) (xy 197.525575 -59.692123) (xy 197.623152 -59.651163) (xy 197.723547 -59.617701)
			(xy 197.826185 -59.591927) (xy 197.930478 -59.573989) (xy 198.035829 -59.56399) (xy 198.141635 -59.561987)
			(xy 198.247289 -59.567992) (xy 198.352186 -59.581971) (xy 198.455726 -59.603842) (xy 198.557315 -59.633482)
			(xy 198.656372 -59.67072) (xy 198.752329 -59.715342) (xy 198.844636 -59.767094) (xy 198.932765 -59.825679)
			(xy 199.016211 -59.890761) (xy 199.094495 -59.961967) (xy 199.16717 -60.03889) (xy 199.23382 -60.12109)
			(xy 199.294062 -60.208094) (xy 199.347551 -60.299405) (xy 199.393982 -60.3945) (xy 199.433087 -60.492834)
			(xy 199.464644 -60.593845) (xy 199.488471 -60.696952) (xy 199.504432 -60.801566) (xy 199.512436 -60.907088)
			(xy 199.512936 -60.96) (xy 207.892911 -60.96) (xy 207.896916 -60.854251) (xy 207.908906 -60.749108)
			(xy 207.928815 -60.645173) (xy 207.956526 -60.543041) (xy 207.991883 -60.443297) (xy 208.034681 -60.346513)
			(xy 208.084677 -60.253243) (xy 208.141584 -60.164022) (xy 208.205075 -60.079359) (xy 208.274787 -59.999741)
			(xy 208.350321 -59.925623) (xy 208.431244 -59.85743) (xy 208.517093 -59.795552) (xy 208.607376 -59.740345)
			(xy 208.701575 -59.692123) (xy 208.799152 -59.651163) (xy 208.899547 -59.617701) (xy 209.002185 -59.591927)
			(xy 209.106478 -59.573989) (xy 209.211829 -59.56399) (xy 209.317635 -59.561987) (xy 209.423289 -59.567992)
			(xy 209.528186 -59.581971) (xy 209.631726 -59.603842) (xy 209.733315 -59.633482) (xy 209.832372 -59.67072)
			(xy 209.928329 -59.715342) (xy 210.020636 -59.767094) (xy 210.108765 -59.825679) (xy 210.192211 -59.890761)
			(xy 210.270495 -59.961967) (xy 210.34317 -60.03889) (xy 210.40982 -60.12109) (xy 210.470062 -60.208094)
			(xy 210.523551 -60.299405) (xy 210.569982 -60.3945) (xy 210.609087 -60.492834) (xy 210.640644 -60.593845)
			(xy 210.664471 -60.696952) (xy 210.680432 -60.801566) (xy 210.688436 -60.907088) (xy 210.688936 -60.96)
			(xy 210.688436 -61.012912) (xy 210.680432 -61.118434) (xy 210.664471 -61.223048) (xy 210.640644 -61.326155)
			(xy 210.609087 -61.427166) (xy 210.569982 -61.5255) (xy 210.523551 -61.620595) (xy 210.470062 -61.711906)
			(xy 210.40982 -61.79891) (xy 210.34317 -61.88111) (xy 210.270495 -61.958033) (xy 210.192211 -62.029239)
			(xy 210.108765 -62.094321) (xy 210.020636 -62.152906) (xy 209.928329 -62.204658) (xy 209.832372 -62.24928)
			(xy 209.733315 -62.286518) (xy 209.631726 -62.316158) (xy 209.528186 -62.338029) (xy 209.423289 -62.352008)
			(xy 209.317635 -62.358013) (xy 209.211829 -62.35601) (xy 209.106478 -62.346011) (xy 209.002185 -62.328073)
			(xy 208.899547 -62.302299) (xy 208.799152 -62.268837) (xy 208.701575 -62.227877) (xy 208.607376 -62.179655)
			(xy 208.517093 -62.124448) (xy 208.431244 -62.06257) (xy 208.350321 -61.994377) (xy 208.274787 -61.920259)
			(xy 208.205075 -61.840641) (xy 208.141584 -61.755978) (xy 208.084677 -61.666757) (xy 208.034681 -61.573487)
			(xy 207.991883 -61.476703) (xy 207.956526 -61.376959) (xy 207.928815 -61.274827) (xy 207.908906 -61.170892)
			(xy 207.896916 -61.065749) (xy 207.892911 -60.96) (xy 199.512936 -60.96) (xy 199.512436 -61.012912)
			(xy 199.504432 -61.118434) (xy 199.488471 -61.223048) (xy 199.464644 -61.326155) (xy 199.433087 -61.427166)
			(xy 199.393982 -61.5255) (xy 199.347551 -61.620595) (xy 199.294062 -61.711906) (xy 199.23382 -61.79891)
			(xy 199.16717 -61.88111) (xy 199.094495 -61.958033) (xy 199.016211 -62.029239) (xy 198.932765 -62.094321)
			(xy 198.844636 -62.152906) (xy 198.752329 -62.204658) (xy 198.656372 -62.24928) (xy 198.557315 -62.286518)
			(xy 198.455726 -62.316158) (xy 198.352186 -62.338029) (xy 198.247289 -62.352008) (xy 198.141635 -62.358013)
			(xy 198.035829 -62.35601) (xy 197.930478 -62.346011) (xy 197.826185 -62.328073) (xy 197.723547 -62.302299)
			(xy 197.623152 -62.268837) (xy 197.525575 -62.227877) (xy 197.431376 -62.179655) (xy 197.341093 -62.124448)
			(xy 197.255244 -62.06257) (xy 197.174321 -61.994377) (xy 197.098787 -61.920259) (xy 197.029075 -61.840641)
			(xy 196.965584 -61.755978) (xy 196.908677 -61.666757) (xy 196.858681 -61.573487) (xy 196.815883 -61.476703)
			(xy 196.780526 -61.376959) (xy 196.752815 -61.274827) (xy 196.732906 -61.170892) (xy 196.720916 -61.065749)
			(xy 196.716911 -60.96) (xy 188.336936 -60.96) (xy 188.336436 -61.012912) (xy 188.328432 -61.118434)
			(xy 188.312471 -61.223048) (xy 188.288644 -61.326155) (xy 188.257087 -61.427166) (xy 188.217982 -61.5255)
			(xy 188.171551 -61.620595) (xy 188.118062 -61.711906) (xy 188.05782 -61.79891) (xy 187.99117 -61.88111)
			(xy 187.918495 -61.958033) (xy 187.840211 -62.029239) (xy 187.756765 -62.094321) (xy 187.668636 -62.152906)
			(xy 187.576329 -62.204658) (xy 187.480372 -62.24928) (xy 187.381315 -62.286518) (xy 187.279726 -62.316158)
			(xy 187.176186 -62.338029) (xy 187.071289 -62.352008) (xy 186.965635 -62.358013) (xy 186.859829 -62.35601)
			(xy 186.754478 -62.346011) (xy 186.650185 -62.328073) (xy 186.547547 -62.302299) (xy 186.447152 -62.268837)
			(xy 186.349575 -62.227877) (xy 186.255376 -62.179655) (xy 186.165093 -62.124448) (xy 186.079244 -62.06257)
			(xy 185.998321 -61.994377) (xy 185.922787 -61.920259) (xy 185.853075 -61.840641) (xy 185.789584 -61.755978)
			(xy 185.732677 -61.666757) (xy 185.682681 -61.573487) (xy 185.639883 -61.476703) (xy 185.604526 -61.376959)
			(xy 185.576815 -61.274827) (xy 185.556906 -61.170892) (xy 185.544916 -61.065749) (xy 185.540911 -60.96)
			(xy 170.688762 -60.96) (xy 170.688262 -61.012912) (xy 170.680258 -61.118434) (xy 170.664297 -61.223048)
			(xy 170.64047 -61.326155) (xy 170.608913 -61.427166) (xy 170.569808 -61.5255) (xy 170.523377 -61.620595)
			(xy 170.469888 -61.711906) (xy 170.409646 -61.79891) (xy 170.342996 -61.88111) (xy 170.270321 -61.958033)
			(xy 170.192037 -62.029239) (xy 170.108591 -62.094321) (xy 170.020462 -62.152906) (xy 169.928155 -62.204658)
			(xy 169.832198 -62.24928) (xy 169.733141 -62.286518) (xy 169.631552 -62.316158) (xy 169.528012 -62.338029)
			(xy 169.423115 -62.352008) (xy 169.317461 -62.358013) (xy 169.211655 -62.35601) (xy 169.106304 -62.346011)
			(xy 169.002011 -62.328073) (xy 168.899373 -62.302299) (xy 168.798978 -62.268837) (xy 168.701401 -62.227877)
			(xy 168.607202 -62.179655) (xy 168.516919 -62.124448) (xy 168.43107 -62.06257) (xy 168.350147 -61.994377)
			(xy 168.274613 -61.920259) (xy 168.204901 -61.840641) (xy 168.14141 -61.755978) (xy 168.084503 -61.666757)
			(xy 168.034507 -61.573487) (xy 167.991709 -61.476703) (xy 167.956352 -61.376959) (xy 167.928641 -61.274827)
			(xy 167.908732 -61.170892) (xy 167.896742 -61.065749) (xy 167.892737 -60.96) (xy 159.512762 -60.96)
			(xy 159.512262 -61.012912) (xy 159.504258 -61.118434) (xy 159.488297 -61.223048) (xy 159.46447 -61.326155)
			(xy 159.432913 -61.427166) (xy 159.393808 -61.5255) (xy 159.347377 -61.620595) (xy 159.293888 -61.711906)
			(xy 159.233646 -61.79891) (xy 159.166996 -61.88111) (xy 159.094321 -61.958033) (xy 159.016037 -62.029239)
			(xy 158.932591 -62.094321) (xy 158.844462 -62.152906) (xy 158.752155 -62.204658) (xy 158.656198 -62.24928)
			(xy 158.557141 -62.286518) (xy 158.455552 -62.316158) (xy 158.352012 -62.338029) (xy 158.247115 -62.352008)
			(xy 158.141461 -62.358013) (xy 158.035655 -62.35601) (xy 157.930304 -62.346011) (xy 157.826011 -62.328073)
			(xy 157.723373 -62.302299) (xy 157.622978 -62.268837) (xy 157.525401 -62.227877) (xy 157.431202 -62.179655)
			(xy 157.340919 -62.124448) (xy 157.25507 -62.06257) (xy 157.174147 -61.994377) (xy 157.098613 -61.920259)
			(xy 157.028901 -61.840641) (xy 156.96541 -61.755978) (xy 156.908503 -61.666757) (xy 156.858507 -61.573487)
			(xy 156.815709 -61.476703) (xy 156.780352 -61.376959) (xy 156.752641 -61.274827) (xy 156.732732 -61.170892)
			(xy 156.720742 -61.065749) (xy 156.716737 -60.96) (xy 148.336762 -60.96) (xy 148.336262 -61.012912)
			(xy 148.328258 -61.118434) (xy 148.312297 -61.223048) (xy 148.28847 -61.326155) (xy 148.256913 -61.427166)
			(xy 148.217808 -61.5255) (xy 148.171377 -61.620595) (xy 148.117888 -61.711906) (xy 148.057646 -61.79891)
			(xy 147.990996 -61.88111) (xy 147.918321 -61.958033) (xy 147.840037 -62.029239) (xy 147.756591 -62.094321)
			(xy 147.668462 -62.152906) (xy 147.576155 -62.204658) (xy 147.480198 -62.24928) (xy 147.381141 -62.286518)
			(xy 147.279552 -62.316158) (xy 147.176012 -62.338029) (xy 147.071115 -62.352008) (xy 146.965461 -62.358013)
			(xy 146.859655 -62.35601) (xy 146.754304 -62.346011) (xy 146.650011 -62.328073) (xy 146.547373 -62.302299)
			(xy 146.446978 -62.268837) (xy 146.349401 -62.227877) (xy 146.255202 -62.179655) (xy 146.164919 -62.124448)
			(xy 146.07907 -62.06257) (xy 145.998147 -61.994377) (xy 145.922613 -61.920259) (xy 145.852901 -61.840641)
			(xy 145.78941 -61.755978) (xy 145.732503 -61.666757) (xy 145.682507 -61.573487) (xy 145.639709 -61.476703)
			(xy 145.604352 -61.376959) (xy 145.576641 -61.274827) (xy 145.556732 -61.170892) (xy 145.544742 -61.065749)
			(xy 145.540737 -60.96) (xy 132.588762 -60.96) (xy 132.588262 -61.012912) (xy 132.580258 -61.118434)
			(xy 132.564297 -61.223048) (xy 132.54047 -61.326155) (xy 132.508913 -61.427166) (xy 132.469808 -61.5255)
			(xy 132.423377 -61.620595) (xy 132.369888 -61.711906) (xy 132.309646 -61.79891) (xy 132.242996 -61.88111)
			(xy 132.170321 -61.958033) (xy 132.092037 -62.029239) (xy 132.008591 -62.094321) (xy 131.920462 -62.152906)
			(xy 131.828155 -62.204658) (xy 131.732198 -62.24928) (xy 131.633141 -62.286518) (xy 131.531552 -62.316158)
			(xy 131.428012 -62.338029) (xy 131.323115 -62.352008) (xy 131.217461 -62.358013) (xy 131.111655 -62.35601)
			(xy 131.006304 -62.346011) (xy 130.902011 -62.328073) (xy 130.799373 -62.302299) (xy 130.698978 -62.268837)
			(xy 130.601401 -62.227877) (xy 130.507202 -62.179655) (xy 130.416919 -62.124448) (xy 130.33107 -62.06257)
			(xy 130.250147 -61.994377) (xy 130.174613 -61.920259) (xy 130.104901 -61.840641) (xy 130.04141 -61.755978)
			(xy 129.984503 -61.666757) (xy 129.934507 -61.573487) (xy 129.891709 -61.476703) (xy 129.856352 -61.376959)
			(xy 129.828641 -61.274827) (xy 129.808732 -61.170892) (xy 129.796742 -61.065749) (xy 129.792737 -60.96)
			(xy 121.412762 -60.96) (xy 121.412262 -61.012912) (xy 121.404258 -61.118434) (xy 121.388297 -61.223048)
			(xy 121.36447 -61.326155) (xy 121.332913 -61.427166) (xy 121.293808 -61.5255) (xy 121.247377 -61.620595)
			(xy 121.193888 -61.711906) (xy 121.133646 -61.79891) (xy 121.066996 -61.88111) (xy 120.994321 -61.958033)
			(xy 120.916037 -62.029239) (xy 120.832591 -62.094321) (xy 120.744462 -62.152906) (xy 120.652155 -62.204658)
			(xy 120.556198 -62.24928) (xy 120.457141 -62.286518) (xy 120.355552 -62.316158) (xy 120.252012 -62.338029)
			(xy 120.147115 -62.352008) (xy 120.041461 -62.358013) (xy 119.935655 -62.35601) (xy 119.830304 -62.346011)
			(xy 119.726011 -62.328073) (xy 119.623373 -62.302299) (xy 119.522978 -62.268837) (xy 119.425401 -62.227877)
			(xy 119.331202 -62.179655) (xy 119.240919 -62.124448) (xy 119.15507 -62.06257) (xy 119.074147 -61.994377)
			(xy 118.998613 -61.920259) (xy 118.928901 -61.840641) (xy 118.86541 -61.755978) (xy 118.808503 -61.666757)
			(xy 118.758507 -61.573487) (xy 118.715709 -61.476703) (xy 118.680352 -61.376959) (xy 118.652641 -61.274827)
			(xy 118.632732 -61.170892) (xy 118.620742 -61.065749) (xy 118.616737 -60.96) (xy 110.236762 -60.96)
			(xy 110.236262 -61.012912) (xy 110.228258 -61.118434) (xy 110.212297 -61.223048) (xy 110.18847 -61.326155)
			(xy 110.156913 -61.427166) (xy 110.117808 -61.5255) (xy 110.071377 -61.620595) (xy 110.017888 -61.711906)
			(xy 109.957646 -61.79891) (xy 109.890996 -61.88111) (xy 109.818321 -61.958033) (xy 109.740037 -62.029239)
			(xy 109.656591 -62.094321) (xy 109.568462 -62.152906) (xy 109.476155 -62.204658) (xy 109.380198 -62.24928)
			(xy 109.281141 -62.286518) (xy 109.179552 -62.316158) (xy 109.076012 -62.338029) (xy 108.971115 -62.352008)
			(xy 108.865461 -62.358013) (xy 108.759655 -62.35601) (xy 108.654304 -62.346011) (xy 108.550011 -62.328073)
			(xy 108.447373 -62.302299) (xy 108.346978 -62.268837) (xy 108.249401 -62.227877) (xy 108.155202 -62.179655)
			(xy 108.064919 -62.124448) (xy 107.97907 -62.06257) (xy 107.898147 -61.994377) (xy 107.822613 -61.920259)
			(xy 107.752901 -61.840641) (xy 107.68941 -61.755978) (xy 107.632503 -61.666757) (xy 107.582507 -61.573487)
			(xy 107.539709 -61.476703) (xy 107.504352 -61.376959) (xy 107.476641 -61.274827) (xy 107.456732 -61.170892)
			(xy 107.444742 -61.065749) (xy 107.440737 -60.96) (xy 92.075762 -60.96) (xy 92.075262 -61.012912)
			(xy 92.067258 -61.118434) (xy 92.051297 -61.223048) (xy 92.02747 -61.326155) (xy 91.995913 -61.427166)
			(xy 91.956808 -61.5255) (xy 91.910377 -61.620595) (xy 91.856888 -61.711906) (xy 91.796646 -61.79891)
			(xy 91.729996 -61.88111) (xy 91.657321 -61.958033) (xy 91.579037 -62.029239) (xy 91.495591 -62.094321)
			(xy 91.407462 -62.152906) (xy 91.315155 -62.204658) (xy 91.219198 -62.24928) (xy 91.120141 -62.286518)
			(xy 91.018552 -62.316158) (xy 90.915012 -62.338029) (xy 90.810115 -62.352008) (xy 90.704461 -62.358013)
			(xy 90.598655 -62.35601) (xy 90.493304 -62.346011) (xy 90.389011 -62.328073) (xy 90.286373 -62.302299)
			(xy 90.185978 -62.268837) (xy 90.088401 -62.227877) (xy 89.994202 -62.179655) (xy 89.903919 -62.124448)
			(xy 89.81807 -62.06257) (xy 89.737147 -61.994377) (xy 89.661613 -61.920259) (xy 89.591901 -61.840641)
			(xy 89.52841 -61.755978) (xy 89.471503 -61.666757) (xy 89.421507 -61.573487) (xy 89.378709 -61.476703)
			(xy 89.343352 -61.376959) (xy 89.315641 -61.274827) (xy 89.295732 -61.170892) (xy 89.283742 -61.065749)
			(xy 89.279737 -60.96) (xy 80.772762 -60.96) (xy 80.772262 -61.012912) (xy 80.764258 -61.118434) (xy 80.748297 -61.223048)
			(xy 80.72447 -61.326155) (xy 80.692913 -61.427166) (xy 80.653808 -61.5255) (xy 80.607377 -61.620595)
			(xy 80.553888 -61.711906) (xy 80.493646 -61.79891) (xy 80.426996 -61.88111) (xy 80.354321 -61.958033)
			(xy 80.276037 -62.029239) (xy 80.192591 -62.094321) (xy 80.104462 -62.152906) (xy 80.012155 -62.204658)
			(xy 79.916198 -62.24928) (xy 79.817141 -62.286518) (xy 79.715552 -62.316158) (xy 79.612012 -62.338029)
			(xy 79.507115 -62.352008) (xy 79.401461 -62.358013) (xy 79.295655 -62.35601) (xy 79.190304 -62.346011)
			(xy 79.086011 -62.328073) (xy 78.983373 -62.302299) (xy 78.882978 -62.268837) (xy 78.785401 -62.227877)
			(xy 78.691202 -62.179655) (xy 78.600919 -62.124448) (xy 78.51507 -62.06257) (xy 78.434147 -61.994377)
			(xy 78.358613 -61.920259) (xy 78.288901 -61.840641) (xy 78.22541 -61.755978) (xy 78.168503 -61.666757)
			(xy 78.118507 -61.573487) (xy 78.075709 -61.476703) (xy 78.040352 -61.376959) (xy 78.012641 -61.274827)
			(xy 77.992732 -61.170892) (xy 77.980742 -61.065749) (xy 77.976737 -60.96) (xy 69.469762 -60.96) (xy 69.469262 -61.012912)
			(xy 69.461258 -61.118434) (xy 69.445297 -61.223048) (xy 69.42147 -61.326155) (xy 69.389913 -61.427166)
			(xy 69.350808 -61.5255) (xy 69.304377 -61.620595) (xy 69.250888 -61.711906) (xy 69.190646 -61.79891)
			(xy 69.123996 -61.88111) (xy 69.051321 -61.958033) (xy 68.973037 -62.029239) (xy 68.889591 -62.094321)
			(xy 68.801462 -62.152906) (xy 68.709155 -62.204658) (xy 68.613198 -62.24928) (xy 68.514141 -62.286518)
			(xy 68.412552 -62.316158) (xy 68.309012 -62.338029) (xy 68.204115 -62.352008) (xy 68.098461 -62.358013)
			(xy 67.992655 -62.35601) (xy 67.887304 -62.346011) (xy 67.783011 -62.328073) (xy 67.680373 -62.302299)
			(xy 67.579978 -62.268837) (xy 67.482401 -62.227877) (xy 67.388202 -62.179655) (xy 67.297919 -62.124448)
			(xy 67.21207 -62.06257) (xy 67.131147 -61.994377) (xy 67.055613 -61.920259) (xy 66.985901 -61.840641)
			(xy 66.92241 -61.755978) (xy 66.865503 -61.666757) (xy 66.815507 -61.573487) (xy 66.772709 -61.476703)
			(xy 66.737352 -61.376959) (xy 66.709641 -61.274827) (xy 66.689732 -61.170892) (xy 66.677742 -61.065749)
			(xy 66.673737 -60.96) (xy 0.509016 -60.96) (xy 0.509016 -62.203781) (xy 38.440102 -62.203781) (xy 38.440102 -62.119059)
			(xy 38.448155 -62.034722) (xy 38.464189 -61.951532) (xy 38.488057 -61.870242) (xy 38.519545 -61.79159)
			(xy 38.558367 -61.716287) (xy 38.60417 -61.645015) (xy 38.656541 -61.578419) (xy 38.715006 -61.517104)
			(xy 38.779034 -61.461623) (xy 38.848046 -61.41248) (xy 38.921416 -61.37012) (xy 38.998481 -61.334925)
			(xy 39.078543 -61.307216) (xy 39.160876 -61.287242) (xy 39.244735 -61.275185) (xy 39.32936 -61.271154)
			(xy 39.413985 -61.275185) (xy 39.497844 -61.287242) (xy 39.580177 -61.307216) (xy 39.660239 -61.334925)
			(xy 39.737304 -61.37012) (xy 39.810674 -61.41248) (xy 39.879686 -61.461623) (xy 39.943714 -61.517104)
			(xy 40.002179 -61.578419) (xy 40.05455 -61.645015) (xy 40.100353 -61.716287) (xy 40.139175 -61.79159)
			(xy 40.170663 -61.870242) (xy 40.194531 -61.951532) (xy 40.210565 -62.034722) (xy 40.218618 -62.119059)
			(xy 40.219122 -62.16142) (xy 40.218618 -62.203781) (xy 40.210565 -62.288118) (xy 40.194531 -62.371308)
			(xy 40.170663 -62.452598) (xy 40.139175 -62.53125) (xy 40.100353 -62.606553) (xy 40.05455 -62.677825)
			(xy 40.002179 -62.744421) (xy 39.943714 -62.805736) (xy 39.879686 -62.861217) (xy 39.810674 -62.91036)
			(xy 39.737304 -62.95272) (xy 39.660239 -62.987915) (xy 39.580177 -63.015624) (xy 39.497844 -63.035598)
			(xy 39.413985 -63.047655) (xy 39.32936 -63.051687) (xy 39.244735 -63.047655) (xy 39.160876 -63.035598)
			(xy 39.078543 -63.015624) (xy 38.998481 -62.987915) (xy 38.921416 -62.95272) (xy 38.848046 -62.91036)
			(xy 38.779034 -62.861217) (xy 38.715006 -62.805736) (xy 38.656541 -62.744421) (xy 38.60417 -62.677825)
			(xy 38.558367 -62.606553) (xy 38.519545 -62.53125) (xy 38.488057 -62.452598) (xy 38.464189 -62.371308)
			(xy 38.448155 -62.288118) (xy 38.440102 -62.203781) (xy 0.509016 -62.203781) (xy 0.509016 -66.43624)
			(xy 26.694892 -66.43624) (xy 26.695489 -66.389845) (xy 26.70513 -66.297557) (xy 26.724322 -66.206773)
			(xy 26.752856 -66.118479) (xy 26.771092 -66.075814) (xy 26.774874 -66.065864) (xy 26.774889 -66.044608)
			(xy 26.771092 -66.034666) (xy 26.75286 -65.991998) (xy 26.724313 -65.903708) (xy 26.705116 -65.812925)
			(xy 26.695479 -65.720636) (xy 26.694892 -65.67424) (xy 26.695489 -65.627845) (xy 26.70513 -65.535557)
			(xy 26.724322 -65.444773) (xy 26.752856 -65.356479) (xy 26.771092 -65.313814) (xy 26.774874 -65.303864)
			(xy 26.774889 -65.282608) (xy 26.771092 -65.272666) (xy 26.75286 -65.229998) (xy 26.724313 -65.141708)
			(xy 26.705116 -65.050925) (xy 26.695479 -64.958636) (xy 26.694892 -64.91224) (xy 26.69539 -64.871137)
			(xy 26.702972 -64.789283) (xy 26.718074 -64.708477) (xy 26.740567 -64.629409) (xy 26.77026 -64.552754)
			(xy 26.8069 -64.479166) (xy 26.850173 -64.409273) (xy 26.899711 -64.343671) (xy 26.955091 -64.282919)
			(xy 27.01584 -64.227537) (xy 27.08144 -64.177996) (xy 27.151331 -64.13472) (xy 27.224918 -64.098077)
			(xy 27.301571 -64.06838) (xy 27.380638 -64.045883) (xy 27.461443 -64.030777) (xy 27.543298 -64.023192)
			(xy 27.5844 -64.022732) (xy 27.630796 -64.023311) (xy 27.723084 -64.032957) (xy 27.813868 -64.052154)
			(xy 27.902161 -64.080693) (xy 27.944826 -64.098932) (xy 27.954768 -64.102738) (xy 27.976032 -64.102738)
			(xy 27.985974 -64.098932) (xy 28.028637 -64.08069) (xy 28.116929 -64.052144) (xy 28.207714 -64.032951)
			(xy 28.300004 -64.023317) (xy 28.3464 -64.022732) (xy 28.387504 -64.023152) (xy 28.469362 -64.030738)
			(xy 28.550171 -64.045844) (xy 28.629241 -64.068342) (xy 28.705898 -64.09804) (xy 28.779488 -64.134685)
			(xy 28.849383 -64.177963) (xy 28.914986 -64.227506) (xy 28.975737 -64.282891) (xy 29.03112 -64.343645)
			(xy 29.08066 -64.40925) (xy 29.123935 -64.479147) (xy 29.160576 -64.552738) (xy 29.190271 -64.629397)
			(xy 29.212765 -64.708468) (xy 29.227868 -64.789277) (xy 29.23545 -64.871136) (xy 29.235908 -64.91224)
			(xy 29.235304 -64.958635) (xy 29.225665 -65.050923) (xy 29.206475 -65.141707) (xy 29.177943 -65.230001)
			(xy 29.159708 -65.272666) (xy 29.155879 -65.282601) (xy 29.155894 -65.303871) (xy 29.159708 -65.313814)
			(xy 29.177966 -65.356471) (xy 29.206507 -65.444765) (xy 29.224945 -65.532) (xy 268.350492 -65.532)
			(xy 268.351075 -65.485604) (xy 268.36072 -65.393316) (xy 268.379916 -65.302532) (xy 268.408454 -65.214239)
			(xy 268.426692 -65.171574) (xy 268.430498 -65.161632) (xy 268.430498 -65.140368) (xy 268.426692 -65.130426)
			(xy 268.408447 -65.087764) (xy 268.379903 -64.999471) (xy 268.36071 -64.908686) (xy 268.351077 -64.816396)
			(xy 268.350492 -64.77) (xy 268.351075 -64.723604) (xy 268.36072 -64.631316) (xy 268.379916 -64.540532)
			(xy 268.408454 -64.452239) (xy 268.426692 -64.409574) (xy 268.430498 -64.399632) (xy 268.430498 -64.378368)
			(xy 268.426692 -64.368426) (xy 268.408447 -64.325764) (xy 268.379903 -64.237471) (xy 268.36071 -64.146686)
			(xy 268.351077 -64.054396) (xy 268.350492 -64.008) (xy 268.351075 -63.961604) (xy 268.36072 -63.869316)
			(xy 268.379916 -63.778532) (xy 268.408454 -63.690239) (xy 268.426692 -63.647574) (xy 268.430498 -63.637632)
			(xy 268.430498 -63.616368) (xy 268.426692 -63.606426) (xy 268.408447 -63.563764) (xy 268.379903 -63.475471)
			(xy 268.36071 -63.384686) (xy 268.351077 -63.292396) (xy 268.350492 -63.246) (xy 268.351075 -63.199604)
			(xy 268.36072 -63.107316) (xy 268.379916 -63.016532) (xy 268.408454 -62.928239) (xy 268.426692 -62.885574)
			(xy 268.430498 -62.875632) (xy 268.430498 -62.854368) (xy 268.426692 -62.844426) (xy 268.408447 -62.801764)
			(xy 268.379903 -62.713471) (xy 268.36071 -62.622686) (xy 268.351077 -62.530396) (xy 268.350492 -62.484)
			(xy 268.351075 -62.437604) (xy 268.36072 -62.345316) (xy 268.379916 -62.254532) (xy 268.408454 -62.166239)
			(xy 268.426692 -62.123574) (xy 268.430498 -62.113632) (xy 268.430498 -62.092368) (xy 268.426692 -62.082426)
			(xy 268.408447 -62.039764) (xy 268.379903 -61.951471) (xy 268.36071 -61.860686) (xy 268.351077 -61.768396)
			(xy 268.350492 -61.722) (xy 268.350967 -61.680898) (xy 268.358552 -61.599043) (xy 268.373657 -61.518238)
			(xy 268.396153 -61.439171) (xy 268.425849 -61.362517) (xy 268.462491 -61.28893) (xy 268.505766 -61.219038)
			(xy 268.555306 -61.153437) (xy 268.610687 -61.092687) (xy 268.671437 -61.037306) (xy 268.737038 -60.987766)
			(xy 268.80693 -60.944491) (xy 268.880517 -60.907849) (xy 268.957171 -60.878153) (xy 269.036238 -60.855657)
			(xy 269.117043 -60.840552) (xy 269.198898 -60.832967) (xy 269.24 -60.832492) (xy 269.286396 -60.833075)
			(xy 269.378684 -60.84272) (xy 269.469468 -60.861916) (xy 269.557761 -60.890454) (xy 269.600426 -60.908692)
			(xy 269.610368 -60.912498) (xy 269.631632 -60.912498) (xy 269.641574 -60.908692) (xy 269.684236 -60.890447)
			(xy 269.772529 -60.861903) (xy 269.863314 -60.84271) (xy 269.955604 -60.833077) (xy 270.002 -60.832492)
			(xy 270.048396 -60.833075) (xy 270.140684 -60.84272) (xy 270.231468 -60.861916) (xy 270.319761 -60.890454)
			(xy 270.362426 -60.908692) (xy 270.372368 -60.912498) (xy 270.393632 -60.912498) (xy 270.403574 -60.908692)
			(xy 270.446236 -60.890447) (xy 270.534529 -60.861903) (xy 270.625314 -60.84271) (xy 270.717604 -60.833077)
			(xy 270.764 -60.832492) (xy 270.810396 -60.833075) (xy 270.902684 -60.84272) (xy 270.993468 -60.861916)
			(xy 271.081761 -60.890454) (xy 271.124426 -60.908692) (xy 271.134368 -60.912498) (xy 271.155632 -60.912498)
			(xy 271.165574 -60.908692) (xy 271.208236 -60.890447) (xy 271.296529 -60.861903) (xy 271.387314 -60.84271)
			(xy 271.479604 -60.833077) (xy 271.526 -60.832492) (xy 271.572396 -60.833075) (xy 271.664684 -60.84272)
			(xy 271.755468 -60.861916) (xy 271.843761 -60.890454) (xy 271.886426 -60.908692) (xy 271.896368 -60.912498)
			(xy 271.917632 -60.912498) (xy 271.927574 -60.908692) (xy 271.970236 -60.890447) (xy 272.058529 -60.861903)
			(xy 272.149314 -60.84271) (xy 272.241604 -60.833077) (xy 272.288 -60.832492) (xy 272.329102 -60.832967)
			(xy 272.410957 -60.840552) (xy 272.491762 -60.855657) (xy 272.570829 -60.878153) (xy 272.647483 -60.907849)
			(xy 272.72107 -60.944491) (xy 272.790962 -60.987766) (xy 272.856563 -61.037306) (xy 272.917313 -61.092687)
			(xy 272.972694 -61.153437) (xy 273.022234 -61.219038) (xy 273.065509 -61.28893) (xy 273.102151 -61.362517)
			(xy 273.131847 -61.439171) (xy 273.154343 -61.518238) (xy 273.169448 -61.599043) (xy 273.177033 -61.680898)
			(xy 273.177508 -61.722) (xy 273.176925 -61.768396) (xy 273.16728 -61.860684) (xy 273.148084 -61.951468)
			(xy 273.119546 -62.039761) (xy 273.101308 -62.082426) (xy 273.097502 -62.092368) (xy 273.097502 -62.113632)
			(xy 273.101308 -62.123574) (xy 273.119553 -62.166236) (xy 273.148097 -62.254529) (xy 273.16729 -62.345314)
			(xy 273.176923 -62.437604) (xy 273.177508 -62.484) (xy 273.177033 -62.525102) (xy 273.169448 -62.606957)
			(xy 273.154343 -62.687762) (xy 273.131847 -62.766829) (xy 273.102151 -62.843483) (xy 273.065509 -62.91707)
			(xy 273.022234 -62.986962) (xy 272.972694 -63.052563) (xy 272.917313 -63.113313) (xy 272.856563 -63.168694)
			(xy 272.790962 -63.218234) (xy 272.72107 -63.261509) (xy 272.647483 -63.298151) (xy 272.570829 -63.327847)
			(xy 272.491762 -63.350343) (xy 272.410957 -63.365448) (xy 272.329102 -63.373033) (xy 272.288 -63.373508)
			(xy 272.241604 -63.372925) (xy 272.149316 -63.36328) (xy 272.058532 -63.344084) (xy 271.970239 -63.315546)
			(xy 271.927574 -63.297308) (xy 271.917632 -63.293502) (xy 271.896368 -63.293502) (xy 271.886426 -63.297308)
			(xy 271.853507 -63.311537) (xy 271.785822 -63.335257) (xy 271.716442 -63.353437) (xy 271.681194 -63.360046)
			(xy 271.67107 -63.362344) (xy 271.653749 -63.373749) (xy 271.642344 -63.39107) (xy 271.640046 -63.401194)
			(xy 271.633416 -63.436437) (xy 271.61522 -63.50581) (xy 271.591513 -63.573498) (xy 271.577308 -63.606426)
			(xy 271.573502 -63.616368) (xy 271.573502 -63.637632) (xy 271.577308 -63.647574) (xy 271.591537 -63.680493)
			(xy 271.615257 -63.748178) (xy 271.633437 -63.817558) (xy 271.640046 -63.852806) (xy 271.642344 -63.86293)
			(xy 271.653749 -63.880251) (xy 271.67107 -63.891656) (xy 271.681194 -63.893954) (xy 271.716437 -63.900584)
			(xy 271.78581 -63.91878) (xy 271.853498 -63.942487) (xy 271.886426 -63.956692) (xy 271.896368 -63.960498)
			(xy 271.917632 -63.960498) (xy 271.927574 -63.956692) (xy 271.970236 -63.938447) (xy 272.058529 -63.909903)
			(xy 272.149314 -63.89071) (xy 272.241604 -63.881077) (xy 272.288 -63.880492) (xy 272.329102 -63.880967)
			(xy 272.410957 -63.888552) (xy 272.491762 -63.903657) (xy 272.570829 -63.926153) (xy 272.647483 -63.955849)
			(xy 272.72107 -63.992491) (xy 272.790962 -64.035766) (xy 272.856563 -64.085306) (xy 272.917313 -64.140687)
			(xy 272.972694 -64.201437) (xy 273.022234 -64.267038) (xy 273.065509 -64.33693) (xy 273.102151 -64.410517)
			(xy 273.131847 -64.487171) (xy 273.154343 -64.566238) (xy 273.169448 -64.647043) (xy 273.177033 -64.728898)
			(xy 273.177508 -64.77) (xy 273.176925 -64.816396) (xy 273.16728 -64.908684) (xy 273.148084 -64.999468)
			(xy 273.119546 -65.087761) (xy 273.101308 -65.130426) (xy 273.097502 -65.140368) (xy 273.097502 -65.161632)
			(xy 273.101308 -65.171574) (xy 273.119553 -65.214236) (xy 273.148097 -65.302529) (xy 273.16729 -65.393314)
			(xy 273.176923 -65.485604) (xy 273.177508 -65.532) (xy 273.177033 -65.573102) (xy 273.169448 -65.654957)
			(xy 273.154343 -65.735762) (xy 273.131847 -65.814829) (xy 273.102151 -65.891483) (xy 273.065509 -65.96507)
			(xy 273.022234 -66.034962) (xy 272.972694 -66.100563) (xy 272.917313 -66.161313) (xy 272.856563 -66.216694)
			(xy 272.790962 -66.266234) (xy 272.72107 -66.309509) (xy 272.647483 -66.346151) (xy 272.570829 -66.375847)
			(xy 272.491762 -66.398343) (xy 272.410957 -66.413448) (xy 272.329102 -66.421033) (xy 272.288 -66.421508)
			(xy 272.241604 -66.420925) (xy 272.149316 -66.41128) (xy 272.058532 -66.392084) (xy 271.970239 -66.363546)
			(xy 271.927574 -66.345308) (xy 271.917632 -66.341502) (xy 271.896368 -66.341502) (xy 271.886426 -66.345308)
			(xy 271.843764 -66.363553) (xy 271.755471 -66.392097) (xy 271.664686 -66.41129) (xy 271.572396 -66.420923)
			(xy 271.526 -66.421508) (xy 271.479604 -66.420925) (xy 271.387316 -66.41128) (xy 271.296532 -66.392084)
			(xy 271.208239 -66.363546) (xy 271.165574 -66.345308) (xy 271.155632 -66.341502) (xy 271.134368 -66.341502)
			(xy 271.124426 -66.345308) (xy 271.081764 -66.363553) (xy 270.993471 -66.392097) (xy 270.902686 -66.41129)
			(xy 270.810396 -66.420923) (xy 270.764 -66.421508) (xy 270.717604 -66.420925) (xy 270.625316 -66.41128)
			(xy 270.534532 -66.392084) (xy 270.446239 -66.363546) (xy 270.403574 -66.345308) (xy 270.393632 -66.341502)
			(xy 270.372368 -66.341502) (xy 270.362426 -66.345308) (xy 270.319764 -66.363553) (xy 270.231471 -66.392097)
			(xy 270.140686 -66.41129) (xy 270.048396 -66.420923) (xy 270.002 -66.421508) (xy 269.955604 -66.420925)
			(xy 269.863316 -66.41128) (xy 269.772532 -66.392084) (xy 269.684239 -66.363546) (xy 269.641574 -66.345308)
			(xy 269.631632 -66.341502) (xy 269.610368 -66.341502) (xy 269.600426 -66.345308) (xy 269.557764 -66.363553)
			(xy 269.469471 -66.392097) (xy 269.378686 -66.41129) (xy 269.286396 -66.420923) (xy 269.24 -66.421508)
			(xy 269.198898 -66.421033) (xy 269.117043 -66.413448) (xy 269.036238 -66.398343) (xy 268.957171 -66.375847)
			(xy 268.880517 -66.346151) (xy 268.80693 -66.309509) (xy 268.737038 -66.266234) (xy 268.671437 -66.216694)
			(xy 268.610687 -66.161313) (xy 268.555306 -66.100563) (xy 268.505766 -66.034962) (xy 268.462491 -65.96507)
			(xy 268.425849 -65.891483) (xy 268.396153 -65.814829) (xy 268.373657 -65.735762) (xy 268.358552 -65.654957)
			(xy 268.350967 -65.573102) (xy 268.350492 -65.532) (xy 29.224945 -65.532) (xy 29.225696 -65.535552)
			(xy 29.235325 -65.627843) (xy 29.235908 -65.67424) (xy 29.235304 -65.720635) (xy 29.225665 -65.812923)
			(xy 29.206475 -65.903707) (xy 29.177943 -65.992001) (xy 29.159708 -66.034666) (xy 29.155879 -66.044601)
			(xy 29.155894 -66.065871) (xy 29.159708 -66.075814) (xy 29.177966 -66.118471) (xy 29.206507 -66.206765)
			(xy 29.225696 -66.297552) (xy 29.235325 -66.389843) (xy 29.235908 -66.43624) (xy 29.235472 -66.477343)
			(xy 29.227883 -66.559198) (xy 29.212774 -66.640004) (xy 29.190275 -66.719072) (xy 29.160576 -66.795726)
			(xy 29.123931 -66.869313) (xy 29.080653 -66.939205) (xy 29.031111 -67.004806) (xy 28.975727 -67.065555)
			(xy 28.914975 -67.120936) (xy 28.849372 -67.170475) (xy 28.779478 -67.21375) (xy 28.705889 -67.250392)
			(xy 28.629234 -67.280087) (xy 28.550166 -67.302584) (xy 28.469359 -67.317689) (xy 28.387503 -67.325273)
			(xy 28.3464 -67.325748) (xy 28.300004 -67.32517) (xy 28.207716 -67.315524) (xy 28.116932 -67.296327)
			(xy 28.028638 -67.267787) (xy 27.985974 -67.249548) (xy 27.976032 -67.245742) (xy 27.954768 -67.245742)
			(xy 27.944826 -67.249548) (xy 27.902165 -67.267795) (xy 27.813872 -67.296338) (xy 27.723087 -67.31553)
			(xy 27.630796 -67.325163) (xy 27.5844 -67.325748) (xy 27.543299 -67.325233) (xy 27.461447 -67.317649)
			(xy 27.380644 -67.302545) (xy 27.301579 -67.280049) (xy 27.224927 -67.250355) (xy 27.151342 -67.213715)
			(xy 27.081451 -67.170442) (xy 27.015851 -67.120905) (xy 26.955101 -67.065527) (xy 26.89972 -67.00478)
			(xy 26.85018 -66.939182) (xy 26.806904 -66.869293) (xy 26.770261 -66.79571) (xy 26.740563 -66.719059)
			(xy 26.718064 -66.639995) (xy 26.702957 -66.559193) (xy 26.695368 -66.477341) (xy 26.694892 -66.43624)
			(xy 0.509016 -66.43624) (xy 0.509016 -70.939914) (xy 8.478012 -70.939914) (xy 8.478545 -70.885007)
			(xy 8.487299 -70.775543) (xy 8.504775 -70.667129) (xy 8.530863 -70.56046) (xy 8.565395 -70.456217)
			(xy 8.608149 -70.355068) (xy 8.658854 -70.257662) (xy 8.717182 -70.16462) (xy 8.749538 -70.120256)
			(xy 8.755682 -70.111222) (xy 8.760349 -70.089902) (xy 8.755684 -70.068582) (xy 8.749538 -70.05955)
			(xy 8.717186 -70.015184) (xy 8.65886 -69.922141) (xy 8.608158 -69.824733) (xy 8.565404 -69.723585)
			(xy 8.530872 -69.619343) (xy 8.504782 -69.512674) (xy 8.487302 -69.404262) (xy 8.478544 -69.294799)
			(xy 8.478012 -69.239892) (xy 8.478453 -69.188568) (xy 8.486124 -69.086208) (xy 8.501424 -68.984707)
			(xy 8.524266 -68.884633) (xy 8.554522 -68.786547) (xy 8.592024 -68.690995) (xy 8.636562 -68.598513)
			(xy 8.687887 -68.509618) (xy 8.745711 -68.424808) (xy 8.809711 -68.344555) (xy 8.87953 -68.26931)
			(xy 8.954776 -68.199493) (xy 9.03503 -68.135494) (xy 9.119842 -68.077672) (xy 9.208738 -68.026349)
			(xy 9.301221 -67.981813) (xy 9.396773 -67.944313) (xy 9.49486 -67.914058) (xy 9.594935 -67.891218)
			(xy 9.696436 -67.875921) (xy 9.798796 -67.868252) (xy 9.85012 -67.867784) (xy 9.901023 -67.868245)
			(xy 10.00255 -67.875789) (xy 10.103239 -67.890838) (xy 10.202535 -67.913308) (xy 10.299893 -67.943077)
			(xy 10.394776 -67.97998) (xy 10.486663 -68.023815) (xy 10.575047 -68.074339) (xy 10.659444 -68.131276)
			(xy 10.739389 -68.194313) (xy 10.814441 -68.263101) (xy 10.884187 -68.337263) (xy 10.948245 -68.416391)
			(xy 11.006262 -68.500049) (xy 11.03249 -68.543678) (xy 11.039348 -68.555362) (xy 11.062716 -68.56857)
			(xy 11.177524 -68.56857) (xy 11.200892 -68.555362) (xy 11.20775 -68.543678) (xy 11.233971 -68.500045)
			(xy 11.291989 -68.416388) (xy 11.356048 -68.337261) (xy 11.425796 -68.2631) (xy 11.500849 -68.194313)
			(xy 11.580794 -68.131277) (xy 11.665192 -68.074341) (xy 11.753577 -68.023817) (xy 11.845464 -67.979983)
			(xy 11.940347 -67.94308) (xy 12.037705 -67.913311) (xy 12.137001 -67.890841) (xy 12.23769 -67.875792)
			(xy 12.339217 -67.868247) (xy 12.39012 -67.867784) (xy 12.441443 -67.868253) (xy 12.462296 -67.869816)
			(xy 61.553852 -67.869816) (xy 61.554352 -67.818909) (xy 61.56234 -67.71741) (xy 61.578267 -67.61685)
			(xy 61.602035 -67.517849) (xy 61.633497 -67.421019) (xy 61.672459 -67.326956) (xy 61.718682 -67.236239)
			(xy 61.771879 -67.149429) (xy 61.831723 -67.06706) (xy 61.897846 -66.989641) (xy 61.969839 -66.917648)
			(xy 62.047258 -66.851525) (xy 62.129627 -66.791681) (xy 62.216437 -66.738484) (xy 62.307154 -66.692261)
			(xy 62.401217 -66.653299) (xy 62.498047 -66.621837) (xy 62.597048 -66.598069) (xy 62.697608 -66.582142)
			(xy 62.799107 -66.574154) (xy 62.900921 -66.574154) (xy 63.00242 -66.582142) (xy 63.10298 -66.598069)
			(xy 63.201981 -66.621837) (xy 63.298811 -66.653299) (xy 63.392874 -66.692261) (xy 63.483591 -66.738484)
			(xy 63.570401 -66.791681) (xy 63.65277 -66.851525) (xy 63.730189 -66.917648) (xy 63.802182 -66.989641)
			(xy 63.868305 -67.06706) (xy 63.928149 -67.149429) (xy 63.981346 -67.236239) (xy 64.027569 -67.326956)
			(xy 64.066531 -67.421019) (xy 64.097993 -67.517849) (xy 64.121761 -67.61685) (xy 64.137688 -67.71741)
			(xy 64.145676 -67.818909) (xy 64.146176 -67.869816) (xy 101.553772 -67.869816) (xy 101.554272 -67.818909)
			(xy 101.56226 -67.71741) (xy 101.578187 -67.61685) (xy 101.601955 -67.517849) (xy 101.633417 -67.421019)
			(xy 101.672379 -67.326956) (xy 101.718602 -67.236239) (xy 101.771799 -67.149429) (xy 101.831643 -67.06706)
			(xy 101.897766 -66.989641) (xy 101.969759 -66.917648) (xy 102.047178 -66.851525) (xy 102.129547 -66.791681)
			(xy 102.216357 -66.738484) (xy 102.307074 -66.692261) (xy 102.401137 -66.653299) (xy 102.497967 -66.621837)
			(xy 102.596968 -66.598069) (xy 102.697528 -66.582142) (xy 102.799027 -66.574154) (xy 102.900841 -66.574154)
			(xy 103.00234 -66.582142) (xy 103.1029 -66.598069) (xy 103.201901 -66.621837) (xy 103.298731 -66.653299)
			(xy 103.392794 -66.692261) (xy 103.483511 -66.738484) (xy 103.570321 -66.791681) (xy 103.65269 -66.851525)
			(xy 103.730109 -66.917648) (xy 103.802102 -66.989641) (xy 103.868225 -67.06706) (xy 103.928069 -67.149429)
			(xy 103.981266 -67.236239) (xy 104.027489 -67.326956) (xy 104.066451 -67.421019) (xy 104.097913 -67.517849)
			(xy 104.121681 -67.61685) (xy 104.137608 -67.71741) (xy 104.145596 -67.818909) (xy 104.146096 -67.869816)
			(xy 141.5542 -67.869816) (xy 141.554699 -67.818919) (xy 141.562686 -67.71744) (xy 141.57861 -67.616899)
			(xy 141.602373 -67.517918) (xy 141.633829 -67.421107) (xy 141.672784 -67.327062) (xy 141.718997 -67.236364)
			(xy 141.772184 -67.14957) (xy 141.832017 -67.067218) (xy 141.898126 -66.989813) (xy 141.970105 -66.917834)
			(xy 142.04751 -66.851725) (xy 142.129862 -66.791892) (xy 142.216656 -66.738705) (xy 142.307354 -66.692492)
			(xy 142.401399 -66.653537) (xy 142.49821 -66.622081) (xy 142.597191 -66.598318) (xy 142.697732 -66.582394)
			(xy 142.799211 -66.574407) (xy 142.901005 -66.574407) (xy 143.002484 -66.582394) (xy 143.103025 -66.598318)
			(xy 143.202006 -66.622081) (xy 143.298817 -66.653537) (xy 143.392862 -66.692492) (xy 143.48356 -66.738705)
			(xy 143.570354 -66.791892) (xy 143.652706 -66.851725) (xy 143.730111 -66.917834) (xy 143.80209 -66.989813)
			(xy 143.868199 -67.067218) (xy 143.928032 -67.14957) (xy 143.981219 -67.236364) (xy 144.027432 -67.327062)
			(xy 144.066387 -67.421107) (xy 144.097843 -67.517918) (xy 144.121606 -67.616899) (xy 144.13753 -67.71744)
			(xy 144.145517 -67.818919) (xy 144.146016 -67.869816) (xy 181.55412 -67.869816) (xy 181.55462 -67.818909)
			(xy 181.562608 -67.71741) (xy 181.578535 -67.61685) (xy 181.602303 -67.517849) (xy 181.633765 -67.421019)
			(xy 181.672727 -67.326956) (xy 181.71895 -67.236239) (xy 181.772147 -67.149429) (xy 181.831991 -67.06706)
			(xy 181.898114 -66.989641) (xy 181.970107 -66.917648) (xy 182.047526 -66.851525) (xy 182.129895 -66.791681)
			(xy 182.216705 -66.738484) (xy 182.307422 -66.692261) (xy 182.401485 -66.653299) (xy 182.498315 -66.621837)
			(xy 182.597316 -66.598069) (xy 182.697876 -66.582142) (xy 182.799375 -66.574154) (xy 182.901189 -66.574154)
			(xy 183.002688 -66.582142) (xy 183.103248 -66.598069) (xy 183.202249 -66.621837) (xy 183.299079 -66.653299)
			(xy 183.393142 -66.692261) (xy 183.483859 -66.738484) (xy 183.570669 -66.791681) (xy 183.653038 -66.851525)
			(xy 183.730457 -66.917648) (xy 183.80245 -66.989641) (xy 183.868573 -67.06706) (xy 183.928417 -67.149429)
			(xy 183.981614 -67.236239) (xy 184.027837 -67.326956) (xy 184.066799 -67.421019) (xy 184.098261 -67.517849)
			(xy 184.122029 -67.61685) (xy 184.137956 -67.71741) (xy 184.145944 -67.818909) (xy 184.146444 -67.869816)
			(xy 184.145789 -67.929021) (xy 184.134974 -68.046936) (xy 184.124854 -68.105274) (xy 184.122568 -68.117212)
			(xy 184.129172 -68.140072) (xy 184.201308 -68.217796) (xy 184.223406 -68.225924) (xy 184.235598 -68.224654)
			(xy 184.294095 -68.218798) (xy 184.411506 -68.212572) (xy 184.470294 -68.212208) (xy 184.537362 -68.212707)
			(xy 184.671248 -68.220881) (xy 184.804386 -68.237206) (xy 184.936281 -68.26162) (xy 185.066442 -68.294033)
			(xy 185.194383 -68.334324) (xy 185.319629 -68.382343) (xy 185.441713 -68.437912) (xy 185.56018 -68.500822)
			(xy 185.674591 -68.570841) (xy 185.784518 -68.647707) (xy 185.889552 -68.731135) (xy 185.989302 -68.820813)
			(xy 186.083398 -68.916407) (xy 186.171488 -69.017563) (xy 186.253245 -69.123903) (xy 186.29122 -69.179186)
			(xy 186.298332 -69.1896) (xy 186.32043 -69.201538) (xy 186.430158 -69.201538) (xy 186.452256 -69.1896)
			(xy 186.459368 -69.179186) (xy 186.497355 -69.12391) (xy 186.579103 -69.017561) (xy 186.667186 -68.916397)
			(xy 186.761276 -68.820795) (xy 186.861022 -68.731111) (xy 186.966054 -68.647678) (xy 187.07598 -68.570807)
			(xy 187.19039 -68.500785) (xy 187.308858 -68.437873) (xy 187.430944 -68.382304) (xy 187.556192 -68.334287)
			(xy 187.684136 -68.293999) (xy 187.814299 -68.26159) (xy 187.946196 -68.237182) (xy 188.079337 -68.220866)
			(xy 188.213225 -68.212701) (xy 188.280294 -68.212208) (xy 188.346684 -68.212667) (xy 188.479223 -68.220684)
			(xy 188.611036 -68.236689) (xy 188.741642 -68.260623) (xy 188.870565 -68.292399) (xy 188.997333 -68.331901)
			(xy 189.121486 -68.378986) (xy 189.242569 -68.433481) (xy 189.360141 -68.495187) (xy 189.473772 -68.563879)
			(xy 189.583049 -68.639307) (xy 189.687572 -68.721195) (xy 189.702736 -68.734629) (xy 270.306796 -68.734629)
			(xy 270.306796 -68.649907) (xy 270.314849 -68.56557) (xy 270.330883 -68.48238) (xy 270.354751 -68.40109)
			(xy 270.386239 -68.322438) (xy 270.425061 -68.247135) (xy 270.470864 -68.175863) (xy 270.523235 -68.109267)
			(xy 270.5817 -68.047952) (xy 270.645728 -67.992471) (xy 270.71474 -67.943328) (xy 270.78811 -67.900968)
			(xy 270.865175 -67.865773) (xy 270.945237 -67.838064) (xy 271.02757 -67.81809) (xy 271.111429 -67.806033)
			(xy 271.196054 -67.802002) (xy 271.280679 -67.806033) (xy 271.364538 -67.81809) (xy 271.446871 -67.838064)
			(xy 271.526933 -67.865773) (xy 271.603998 -67.900968) (xy 271.677368 -67.943328) (xy 271.74638 -67.992471)
			(xy 271.810408 -68.047952) (xy 271.868873 -68.109267) (xy 271.921244 -68.175863) (xy 271.967047 -68.247135)
			(xy 272.005869 -68.322438) (xy 272.037357 -68.40109) (xy 272.061225 -68.48238) (xy 272.077259 -68.56557)
			(xy 272.085312 -68.649907) (xy 272.085816 -68.692268) (xy 272.085312 -68.734629) (xy 272.077259 -68.818966)
			(xy 272.061225 -68.902156) (xy 272.037357 -68.983446) (xy 272.005869 -69.062098) (xy 271.967047 -69.137401)
			(xy 271.921244 -69.208673) (xy 271.868873 -69.275269) (xy 271.810408 -69.336584) (xy 271.74638 -69.392065)
			(xy 271.677368 -69.441208) (xy 271.603998 -69.483568) (xy 271.526933 -69.518763) (xy 271.446871 -69.546472)
			(xy 271.364538 -69.566446) (xy 271.280679 -69.578503) (xy 271.196054 -69.582535) (xy 271.111429 -69.578503)
			(xy 271.02757 -69.566446) (xy 270.945237 -69.546472) (xy 270.865175 -69.518763) (xy 270.78811 -69.483568)
			(xy 270.71474 -69.441208) (xy 270.645728 -69.392065) (xy 270.5817 -69.336584) (xy 270.523235 -69.275269)
			(xy 270.470864 -69.208673) (xy 270.425061 -69.137401) (xy 270.386239 -69.062098) (xy 270.354751 -68.983446)
			(xy 270.330883 -68.902156) (xy 270.314849 -68.818966) (xy 270.306796 -68.734629) (xy 189.702736 -68.734629)
			(xy 189.78696 -68.809245) (xy 189.880851 -68.903136) (xy 189.968901 -69.002523) (xy 190.050789 -69.107046)
			(xy 190.126218 -69.216323) (xy 190.19491 -69.329954) (xy 190.256617 -69.447526) (xy 190.311112 -69.568609)
			(xy 190.358197 -69.692761) (xy 190.397699 -69.81953) (xy 190.429476 -69.948452) (xy 190.453411 -70.079058)
			(xy 190.469047 -70.207829) (xy 268.757142 -70.207829) (xy 268.757142 -70.123107) (xy 268.765195 -70.03877)
			(xy 268.781229 -69.95558) (xy 268.805097 -69.87429) (xy 268.836585 -69.795638) (xy 268.875407 -69.720335)
			(xy 268.92121 -69.649063) (xy 268.973581 -69.582467) (xy 269.032046 -69.521152) (xy 269.096074 -69.465671)
			(xy 269.165086 -69.416528) (xy 269.238456 -69.374168) (xy 269.315521 -69.338973) (xy 269.395583 -69.311264)
			(xy 269.477916 -69.29129) (xy 269.561775 -69.279233) (xy 269.6464 -69.275202) (xy 269.731025 -69.279233)
			(xy 269.814884 -69.29129) (xy 269.897217 -69.311264) (xy 269.977279 -69.338973) (xy 270.054344 -69.374168)
			(xy 270.127714 -69.416528) (xy 270.196726 -69.465671) (xy 270.260754 -69.521152) (xy 270.319219 -69.582467)
			(xy 270.37159 -69.649063) (xy 270.417393 -69.720335) (xy 270.456215 -69.795638) (xy 270.487703 -69.87429)
			(xy 270.511571 -69.95558) (xy 270.527605 -70.03877) (xy 270.535658 -70.123107) (xy 270.536162 -70.165468)
			(xy 270.535658 -70.207829) (xy 270.527605 -70.292166) (xy 270.511571 -70.375356) (xy 270.487703 -70.456646)
			(xy 270.456215 -70.535298) (xy 270.417393 -70.610601) (xy 270.37159 -70.681873) (xy 270.319219 -70.748469)
			(xy 270.260754 -70.809784) (xy 270.196726 -70.865265) (xy 270.127714 -70.914408) (xy 270.054344 -70.956768)
			(xy 269.977279 -70.991963) (xy 269.897217 -71.019672) (xy 269.814884 -71.039646) (xy 269.731025 -71.051703)
			(xy 269.6464 -71.055735) (xy 269.561775 -71.051703) (xy 269.477916 -71.039646) (xy 269.395583 -71.019672)
			(xy 269.315521 -70.991963) (xy 269.238456 -70.956768) (xy 269.165086 -70.914408) (xy 269.096074 -70.865265)
			(xy 269.032046 -70.809784) (xy 268.973581 -70.748469) (xy 268.92121 -70.681873) (xy 268.875407 -70.610601)
			(xy 268.836585 -70.535298) (xy 268.805097 -70.456646) (xy 268.781229 -70.375356) (xy 268.765195 -70.292166)
			(xy 268.757142 -70.207829) (xy 190.469047 -70.207829) (xy 190.469416 -70.210871) (xy 190.477433 -70.34341)
			(xy 190.477433 -70.47619) (xy 190.469416 -70.608729) (xy 190.453411 -70.740542) (xy 190.429476 -70.871148)
			(xy 190.397699 -71.00007) (xy 190.358197 -71.126839) (xy 190.311112 -71.250991) (xy 190.256617 -71.372074)
			(xy 190.19491 -71.489646) (xy 190.126218 -71.603277) (xy 190.050789 -71.712554) (xy 189.968901 -71.817077)
			(xy 189.880851 -71.916464) (xy 189.78696 -72.010355) (xy 189.687572 -72.098405) (xy 189.583049 -72.180293)
			(xy 189.473772 -72.255721) (xy 189.360141 -72.324413) (xy 189.242569 -72.386119) (xy 189.121486 -72.440614)
			(xy 188.997333 -72.487699) (xy 188.870565 -72.527201) (xy 188.741642 -72.558977) (xy 188.611036 -72.582911)
			(xy 188.479223 -72.598916) (xy 188.346684 -72.606933) (xy 188.280294 -72.607424) (xy 188.213225 -72.606965)
			(xy 188.079338 -72.598789) (xy 187.946198 -72.582463) (xy 187.814302 -72.558047) (xy 187.684141 -72.525633)
			(xy 187.556198 -72.485339) (xy 187.430952 -72.437318) (xy 187.308867 -72.381747) (xy 187.1904 -72.318834)
			(xy 187.075989 -72.248812) (xy 186.966063 -72.171943) (xy 186.861029 -72.088513) (xy 186.76128 -71.998831)
			(xy 186.667185 -71.903233) (xy 186.579097 -71.802074) (xy 186.497342 -71.695731) (xy 186.459368 -71.640446)
			(xy 186.452256 -71.630032) (xy 186.430158 -71.618094) (xy 186.32043 -71.618094) (xy 186.298332 -71.630032)
			(xy 186.29122 -71.640446) (xy 186.253252 -71.695735) (xy 186.171502 -71.802083) (xy 186.083417 -71.903246)
			(xy 185.989326 -71.998848) (xy 185.889577 -72.088531) (xy 185.784544 -72.171964) (xy 185.674617 -72.248833)
			(xy 185.560206 -72.318854) (xy 185.441736 -72.381766) (xy 185.319649 -72.437333) (xy 185.194401 -72.48535)
			(xy 185.066456 -72.525637) (xy 184.936292 -72.558045) (xy 184.804393 -72.582452) (xy 184.671252 -72.598768)
			(xy 184.537363 -72.606931) (xy 184.470294 -72.607424) (xy 184.403901 -72.606967) (xy 184.271357 -72.598949)
			(xy 184.139539 -72.582944) (xy 184.008927 -72.55901) (xy 183.879999 -72.527234) (xy 183.753224 -72.487732)
			(xy 183.629066 -72.440648) (xy 183.507977 -72.386153) (xy 183.390399 -72.324448) (xy 183.276761 -72.255756)
			(xy 183.167477 -72.180329) (xy 183.062946 -72.098441) (xy 182.963551 -72.010392) (xy 182.869652 -71.916502)
			(xy 182.781593 -71.817115) (xy 182.699696 -71.712592) (xy 182.624258 -71.603316) (xy 182.555555 -71.489684)
			(xy 182.493839 -71.372112) (xy 182.439333 -71.251028) (xy 182.392237 -71.126874) (xy 182.352723 -71.000103)
			(xy 182.320934 -70.871178) (xy 182.296987 -70.740569) (xy 182.28097 -70.608752) (xy 182.27294 -70.476209)
			(xy 182.272432 -70.409816) (xy 182.27291 -70.34359) (xy 182.280893 -70.211378) (xy 182.296826 -70.079888)
			(xy 182.32065 -69.949596) (xy 182.35228 -69.820975) (xy 182.391599 -69.694494) (xy 182.438466 -69.57061)
			(xy 182.49271 -69.449775) (xy 182.554135 -69.332426) (xy 182.5879 -69.275452) (xy 182.59425 -69.265038)
			(xy 182.596028 -69.241416) (xy 182.555896 -69.143372) (xy 182.538116 -69.127878) (xy 182.526178 -69.124576)
			(xy 182.477646 -69.111541) (xy 182.382574 -69.078966) (xy 182.290311 -69.039123) (xy 182.201411 -68.992253)
			(xy 182.116409 -68.938637) (xy 182.035816 -68.878598) (xy 181.960117 -68.812496) (xy 181.889765 -68.740729)
			(xy 181.825184 -68.663727) (xy 181.766762 -68.581954) (xy 181.71485 -68.495901) (xy 181.66976 -68.406086)
			(xy 181.631763 -68.313047) (xy 181.601088 -68.217345) (xy 181.577918 -68.119554) (xy 181.562394 -68.020262)
			(xy 181.554607 -67.920065) (xy 181.55412 -67.869816) (xy 144.146016 -67.869816) (xy 144.145413 -67.929016)
			(xy 144.134729 -68.04693) (xy 144.12468 -68.105274) (xy 144.122394 -68.117212) (xy 144.128998 -68.140072)
			(xy 144.201134 -68.217796) (xy 144.223232 -68.225924) (xy 144.235424 -68.224654) (xy 144.293921 -68.218796)
			(xy 144.411332 -68.212571) (xy 144.47012 -68.212208) (xy 144.537188 -68.212686) (xy 144.671075 -68.220862)
			(xy 144.804214 -68.237188) (xy 144.936109 -68.261604) (xy 145.066269 -68.294019) (xy 145.194211 -68.334311)
			(xy 145.319457 -68.382332) (xy 145.441541 -68.437901) (xy 145.560008 -68.500813) (xy 145.674419 -68.570833)
			(xy 145.784345 -68.647701) (xy 145.889379 -68.73113) (xy 145.98913 -68.820809) (xy 146.083225 -68.916405)
			(xy 146.171315 -69.017562) (xy 146.253071 -69.123902) (xy 146.291046 -69.179186) (xy 146.298158 -69.1896)
			(xy 146.320256 -69.201538) (xy 146.429984 -69.201538) (xy 146.452082 -69.1896) (xy 146.459194 -69.179186)
			(xy 146.497163 -69.123898) (xy 146.578913 -69.017549) (xy 146.666997 -68.916385) (xy 146.761088 -68.820783)
			(xy 146.860836 -68.731099) (xy 146.965869 -68.647667) (xy 147.075796 -68.570797) (xy 147.190207 -68.500775)
			(xy 147.308677 -68.437864) (xy 147.430764 -68.382296) (xy 147.556013 -68.334279) (xy 147.683957 -68.293992)
			(xy 147.814122 -68.261585) (xy 147.94602 -68.237179) (xy 148.079162 -68.220863) (xy 148.213051 -68.2127)
			(xy 148.28012 -68.212208) (xy 148.34651 -68.212678) (xy 148.479047 -68.220696) (xy 148.610858 -68.236702)
			(xy 148.741462 -68.260637) (xy 148.870383 -68.292414) (xy 148.99715 -68.331918) (xy 149.1213 -68.379003)
			(xy 149.242381 -68.433498) (xy 149.359951 -68.495204) (xy 149.473581 -68.563897) (xy 149.582855 -68.639324)
			(xy 149.687377 -68.721212) (xy 149.786763 -68.809262) (xy 149.880652 -68.903152) (xy 149.9687 -69.002539)
			(xy 150.050587 -69.107061) (xy 150.126014 -69.216336) (xy 150.194706 -69.329966) (xy 150.256411 -69.447537)
			(xy 150.310905 -69.568618) (xy 150.357989 -69.692769) (xy 150.397491 -69.819537) (xy 150.429267 -69.948458)
			(xy 150.453201 -70.079062) (xy 150.469206 -70.210873) (xy 150.477223 -70.34341) (xy 150.477223 -70.47619)
			(xy 150.469206 -70.608727) (xy 150.453201 -70.740538) (xy 150.429267 -70.871142) (xy 150.397491 -71.000063)
			(xy 150.357989 -71.126831) (xy 150.310905 -71.250982) (xy 150.256411 -71.372063) (xy 150.194706 -71.489634)
			(xy 150.126014 -71.603264) (xy 150.050587 -71.712539) (xy 149.9687 -71.817061) (xy 149.880652 -71.916448)
			(xy 149.786763 -72.010338) (xy 149.687377 -72.098388) (xy 149.582855 -72.180276) (xy 149.473581 -72.255703)
			(xy 149.359951 -72.324396) (xy 149.242381 -72.386102) (xy 149.1213 -72.440597) (xy 148.99715 -72.487682)
			(xy 148.870383 -72.527186) (xy 148.741462 -72.558963) (xy 148.610858 -72.582898) (xy 148.479047 -72.598904)
			(xy 148.34651 -72.606922) (xy 148.28012 -72.607424) (xy 148.213052 -72.606944) (xy 148.079165 -72.59877)
			(xy 147.946025 -72.582446) (xy 147.81413 -72.558031) (xy 147.683968 -72.525618) (xy 147.556026 -72.485326)
			(xy 147.43078 -72.437306) (xy 147.308695 -72.381737) (xy 147.190228 -72.318825) (xy 147.075817 -72.248805)
			(xy 146.96589 -72.171937) (xy 146.860857 -72.088508) (xy 146.761107 -71.998827) (xy 146.667012 -71.90323)
			(xy 146.578923 -71.802072) (xy 146.497168 -71.69573) (xy 146.459194 -71.640446) (xy 146.452082 -71.630032)
			(xy 146.429984 -71.618094) (xy 146.320256 -71.618094) (xy 146.298158 -71.630032) (xy 146.291046 -71.640446)
			(xy 146.253061 -71.695723) (xy 146.171312 -71.802071) (xy 146.083229 -71.903234) (xy 145.989138 -71.998836)
			(xy 145.889391 -72.08852) (xy 145.784359 -72.171952) (xy 145.674433 -72.248823) (xy 145.560023 -72.318844)
			(xy 145.441555 -72.381756) (xy 145.319469 -72.437325) (xy 145.194221 -72.485343) (xy 145.066278 -72.525631)
			(xy 144.936115 -72.55804) (xy 144.804217 -72.582448) (xy 144.671077 -72.598765) (xy 144.537189 -72.606931)
			(xy 144.47012 -72.607424) (xy 144.403731 -72.606897) (xy 144.271194 -72.598882) (xy 144.139383 -72.582878)
			(xy 144.008779 -72.558945) (xy 143.879859 -72.52717) (xy 143.753092 -72.487669) (xy 143.628941 -72.440586)
			(xy 143.50786 -72.386093) (xy 143.39029 -72.324389) (xy 143.27666 -72.255699) (xy 143.167384 -72.180273)
			(xy 143.062862 -72.098386) (xy 142.963475 -72.010339) (xy 142.869586 -71.916451) (xy 142.781537 -71.817065)
			(xy 142.699649 -71.712545) (xy 142.624221 -71.603271) (xy 142.555529 -71.489642) (xy 142.493822 -71.372072)
			(xy 142.439327 -71.250992) (xy 142.392242 -71.126842) (xy 142.352739 -71.000076) (xy 142.320962 -70.871156)
			(xy 142.297027 -70.740552) (xy 142.281022 -70.608742) (xy 142.273004 -70.476205) (xy 142.272512 -70.409816)
			(xy 142.272989 -70.343594) (xy 142.280942 -70.211388) (xy 142.296845 -70.079902) (xy 142.320639 -69.949613)
			(xy 142.352238 -69.820993) (xy 142.391527 -69.694511) (xy 142.438365 -69.570624) (xy 142.492579 -69.449784)
			(xy 142.553975 -69.33243) (xy 142.587726 -69.275452) (xy 142.594076 -69.265038) (xy 142.595854 -69.241416)
			(xy 142.555722 -69.143372) (xy 142.537942 -69.127878) (xy 142.526004 -69.124576) (xy 142.477475 -69.111555)
			(xy 142.382423 -69.078958) (xy 142.29018 -69.039098) (xy 142.201302 -68.992213) (xy 142.116322 -68.938586)
			(xy 142.03575 -68.878538) (xy 141.960071 -68.81243) (xy 141.88974 -68.740659) (xy 141.825178 -68.663658)
			(xy 141.766774 -68.581887) (xy 141.714878 -68.495838) (xy 141.669802 -68.406029) (xy 141.631818 -68.312998)
			(xy 141.601152 -68.217305) (xy 141.57799 -68.119525) (xy 141.562471 -68.020244) (xy 141.554687 -67.920059)
			(xy 141.5542 -67.869816) (xy 104.146096 -67.869816) (xy 104.14544 -67.929021) (xy 104.134626 -68.046936)
			(xy 104.124506 -68.105274) (xy 104.12222 -68.117212) (xy 104.128824 -68.140072) (xy 104.20096 -68.217796)
			(xy 104.223058 -68.225924) (xy 104.23525 -68.224654) (xy 104.293747 -68.218802) (xy 104.411158 -68.212573)
			(xy 104.469946 -68.212208) (xy 104.537013 -68.212745) (xy 104.670898 -68.220917) (xy 104.804036 -68.237238)
			(xy 104.93593 -68.26165) (xy 105.06609 -68.29406) (xy 105.194031 -68.334348) (xy 105.319277 -68.382365)
			(xy 105.441361 -68.43793) (xy 105.559829 -68.500839) (xy 105.674239 -68.570855) (xy 105.784166 -68.647719)
			(xy 105.889201 -68.731144) (xy 105.988952 -68.82082) (xy 106.083048 -68.916412) (xy 106.171139 -69.017566)
			(xy 106.252896 -69.123904) (xy 106.290872 -69.179186) (xy 106.297984 -69.1896) (xy 106.320082 -69.201538)
			(xy 106.42981 -69.201538) (xy 106.451908 -69.1896) (xy 106.45902 -69.179186) (xy 106.496972 -69.123886)
			(xy 106.578722 -69.017537) (xy 106.666808 -68.916373) (xy 106.7609 -68.820772) (xy 106.86065 -68.731088)
			(xy 106.965684 -68.647656) (xy 107.075612 -68.570786) (xy 107.190025 -68.500765) (xy 107.308495 -68.437855)
			(xy 107.430583 -68.382288) (xy 107.555833 -68.334272) (xy 107.683779 -68.293986) (xy 107.813945 -68.26158)
			(xy 107.945844 -68.237175) (xy 108.078987 -68.220861) (xy 108.212877 -68.212699) (xy 108.279946 -68.212208)
			(xy 108.346561 -68.21269) (xy 108.479549 -68.220738) (xy 108.611805 -68.236826) (xy 108.742843 -68.260895)
			(xy 108.872183 -68.292856) (xy 108.99935 -68.332592) (xy 109.123877 -68.379958) (xy 109.245307 -68.434779)
			(xy 109.363193 -68.496853) (xy 109.420406 -68.530978) (xy 109.42955 -68.536566) (xy 109.450632 -68.53936)
			(xy 109.543088 -68.512436) (xy 109.559598 -68.49872) (xy 109.56417 -68.489068) (xy 109.58283 -68.45221)
			(xy 109.625989 -68.381762) (xy 109.675492 -68.315617) (xy 109.730913 -68.254346) (xy 109.791775 -68.198475)
			(xy 109.857554 -68.148486) (xy 109.927683 -68.10481) (xy 110.001559 -68.067822) (xy 110.078545 -68.037842)
			(xy 110.157978 -68.015126) (xy 110.239175 -67.999871) (xy 110.321437 -67.992208) (xy 110.362746 -67.991736)
			(xy 110.405055 -67.992204) (xy 110.489292 -68.000211) (xy 110.572388 -68.016178) (xy 110.653594 -68.039959)
			(xy 110.732177 -68.071342) (xy 110.807426 -68.110041) (xy 110.843314 -68.132452) (xy 110.851703 -68.137335)
			(xy 110.870746 -68.141006) (xy 110.889789 -68.137335) (xy 110.898178 -68.132452) (xy 110.934072 -68.110048)
			(xy 111.009313 -68.071332) (xy 111.087892 -68.039941) (xy 111.169099 -68.01616) (xy 111.252198 -68.000202)
			(xy 111.336437 -67.992213) (xy 111.378746 -67.991736) (xy 111.421055 -67.992204) (xy 111.505292 -68.000211)
			(xy 111.588388 -68.016178) (xy 111.669594 -68.039959) (xy 111.748177 -68.071342) (xy 111.823426 -68.110041)
			(xy 111.859314 -68.132452) (xy 111.867703 -68.137335) (xy 111.886746 -68.141006) (xy 111.905789 -68.137335)
			(xy 111.914178 -68.132452) (xy 111.950072 -68.110048) (xy 112.025313 -68.071332) (xy 112.103892 -68.039941)
			(xy 112.185099 -68.01616) (xy 112.268198 -68.000202) (xy 112.352437 -67.992213) (xy 112.394746 -67.991736)
			(xy 112.435853 -67.992169) (xy 112.517717 -67.999757) (xy 112.598532 -68.014865) (xy 112.677609 -68.037364)
			(xy 112.754273 -68.067061) (xy 112.827871 -68.103704) (xy 112.897774 -68.146979) (xy 112.963387 -68.196519)
			(xy 113.024151 -68.251901) (xy 113.079547 -68.312651) (xy 113.129102 -68.378253) (xy 113.172394 -68.448146)
			(xy 113.209054 -68.521735) (xy 113.23877 -68.598392) (xy 113.261287 -68.677463) (xy 113.276414 -68.758274)
			(xy 113.284022 -68.840137) (xy 113.284508 -68.881244) (xy 113.284026 -68.923559) (xy 113.275992 -69.007808)
			(xy 113.25999 -69.090912) (xy 113.236165 -69.17212) (xy 113.204733 -69.250697) (xy 113.165978 -69.325933)
			(xy 113.143538 -69.361812) (xy 113.138619 -69.370183) (xy 113.134959 -69.389237) (xy 113.138646 -69.408287)
			(xy 113.143538 -69.416676) (xy 113.166016 -69.452532) (xy 113.204764 -69.527773) (xy 113.236192 -69.606354)
			(xy 113.260013 -69.687564) (xy 113.276014 -69.770671) (xy 113.284049 -69.854921) (xy 113.284045 -69.939553)
			(xy 113.276003 -70.023803) (xy 113.259996 -70.106908) (xy 113.236167 -70.188116) (xy 113.204734 -70.266695)
			(xy 113.165979 -70.341932) (xy 113.143538 -70.377812) (xy 113.138619 -70.386183) (xy 113.134959 -70.405237)
			(xy 113.138646 -70.424287) (xy 113.143538 -70.432676) (xy 113.166016 -70.468532) (xy 113.204764 -70.543773)
			(xy 113.236192 -70.622354) (xy 113.260013 -70.703564) (xy 113.276014 -70.786671) (xy 113.284049 -70.870921)
			(xy 113.284045 -70.955553) (xy 113.276003 -71.039803) (xy 113.259996 -71.122908) (xy 113.236167 -71.204116)
			(xy 113.204734 -71.282695) (xy 113.165979 -71.357932) (xy 113.143538 -71.393812) (xy 113.138619 -71.402183)
			(xy 113.134959 -71.421237) (xy 113.138646 -71.440287) (xy 113.143538 -71.448676) (xy 113.165961 -71.484564)
			(xy 113.204707 -71.559802) (xy 113.236134 -71.638378) (xy 113.259957 -71.719584) (xy 113.275962 -71.802685)
			(xy 113.284004 -71.88693) (xy 113.284508 -71.929244) (xy 113.28409 -71.970355) (xy 113.276498 -72.052227)
			(xy 113.261383 -72.133048) (xy 113.238875 -72.21213) (xy 113.209164 -72.288798) (xy 113.172506 -72.362396)
			(xy 113.129212 -72.432297) (xy 113.079652 -72.497905) (xy 113.024249 -72.55866) (xy 112.963476 -72.614042)
			(xy 112.897851 -72.66358) (xy 112.827936 -72.706851) (xy 112.754325 -72.743485) (xy 112.677648 -72.773169)
			(xy 112.598558 -72.795651) (xy 112.517732 -72.810739) (xy 112.435857 -72.818303) (xy 112.394746 -72.818752)
			(xy 112.352437 -72.81829) (xy 112.2682 -72.810282) (xy 112.185103 -72.794314) (xy 112.103897 -72.770532)
			(xy 112.025315 -72.739148) (xy 111.950066 -72.700448) (xy 111.914178 -72.678036) (xy 111.905789 -72.673153)
			(xy 111.886746 -72.669482) (xy 111.867703 -72.673153) (xy 111.859314 -72.678036) (xy 111.823421 -72.700442)
			(xy 111.74818 -72.739158) (xy 111.669601 -72.770548) (xy 111.588394 -72.79433) (xy 111.505295 -72.810287)
			(xy 111.421055 -72.818276) (xy 111.378746 -72.818752) (xy 111.336437 -72.81829) (xy 111.2522 -72.810282)
			(xy 111.169103 -72.794314) (xy 111.087897 -72.770532) (xy 111.009315 -72.739148) (xy 110.934066 -72.700448)
			(xy 110.898178 -72.678036) (xy 110.889789 -72.673153) (xy 110.870746 -72.669482) (xy 110.851703 -72.673153)
			(xy 110.843314 -72.678036) (xy 110.807421 -72.700442) (xy 110.73218 -72.739158) (xy 110.653601 -72.770548)
			(xy 110.572394 -72.79433) (xy 110.489295 -72.810287) (xy 110.405055 -72.818276) (xy 110.362746 -72.818752)
			(xy 110.321736 -72.818307) (xy 110.240064 -72.81076) (xy 110.159434 -72.795726) (xy 110.08053 -72.773333)
			(xy 110.004023 -72.74377) (xy 109.930563 -72.70729) (xy 109.860773 -72.664201) (xy 109.795246 -72.614871)
			(xy 109.734539 -72.559717) (xy 109.679168 -72.499208) (xy 109.629603 -72.433859) (xy 109.586264 -72.364224)
			(xy 109.567472 -72.32777) (xy 109.562392 -72.318118) (xy 109.54639 -72.304656) (xy 109.45368 -72.277986)
			(xy 109.432852 -72.28078) (xy 109.423708 -72.286622) (xy 109.366375 -72.320967) (xy 109.24821 -72.383438)
			(xy 109.126467 -72.438611) (xy 109.001595 -72.486281) (xy 108.874056 -72.526273) (xy 108.744322 -72.558439)
			(xy 108.612872 -72.58266) (xy 108.480194 -72.598845) (xy 108.346777 -72.606936) (xy 108.279946 -72.607424)
			(xy 108.212878 -72.606923) (xy 108.078991 -72.598751) (xy 107.945853 -72.582428) (xy 107.813957 -72.558015)
			(xy 107.683796 -72.525603) (xy 107.555854 -72.485313) (xy 107.430608 -72.437295) (xy 107.308524 -72.381727)
			(xy 107.190056 -72.318816) (xy 107.075645 -72.248797) (xy 106.965718 -72.171931) (xy 106.860684 -72.088503)
			(xy 106.760934 -71.998824) (xy 106.666839 -71.903228) (xy 106.57875 -71.802071) (xy 106.496994 -71.69573)
			(xy 106.45902 -71.640446) (xy 106.451908 -71.630032) (xy 106.42981 -71.618094) (xy 106.320082 -71.618094)
			(xy 106.297984 -71.630032) (xy 106.290872 -71.640446) (xy 106.25287 -71.695711) (xy 106.171122 -71.802059)
			(xy 106.08304 -71.903222) (xy 105.98895 -71.998824) (xy 105.889205 -72.088508) (xy 105.784174 -72.171941)
			(xy 105.674249 -72.248812) (xy 105.55984 -72.318834) (xy 105.441373 -72.381747) (xy 105.319289 -72.437317)
			(xy 105.194042 -72.485335) (xy 105.0661 -72.525625) (xy 104.935938 -72.558035) (xy 104.804041 -72.582444)
			(xy 104.670901 -72.598763) (xy 104.537014 -72.60693) (xy 104.469946 -72.607424) (xy 104.403553 -72.606916)
			(xy 104.27101 -72.598902) (xy 104.139193 -72.5829) (xy 104.008582 -72.558969) (xy 103.879654 -72.527195)
			(xy 103.75288 -72.487696) (xy 103.628722 -72.440614) (xy 103.507633 -72.386123) (xy 103.390055 -72.32442)
			(xy 103.276417 -72.25573) (xy 103.167133 -72.180305) (xy 103.062602 -72.09842) (xy 102.963206 -72.010373)
			(xy 102.869307 -71.916485) (xy 102.781248 -71.817099) (xy 102.69935 -71.712578) (xy 102.623912 -71.603304)
			(xy 102.555209 -71.489673) (xy 102.493492 -71.372103) (xy 102.438986 -71.25102) (xy 102.39189 -71.126868)
			(xy 102.352375 -71.000098) (xy 102.320586 -70.871174) (xy 102.296639 -70.740566) (xy 102.280622 -70.608751)
			(xy 102.272592 -70.476209) (xy 102.272084 -70.409816) (xy 102.272569 -70.34359) (xy 102.280552 -70.211379)
			(xy 102.296484 -70.079888) (xy 102.320308 -69.949596) (xy 102.351937 -69.820976) (xy 102.391256 -69.694495)
			(xy 102.438121 -69.570611) (xy 102.492364 -69.449775) (xy 102.553787 -69.332426) (xy 102.587552 -69.275452)
			(xy 102.593902 -69.265038) (xy 102.59568 -69.241416) (xy 102.555548 -69.143372) (xy 102.537768 -69.127878)
			(xy 102.52583 -69.124576) (xy 102.477308 -69.111506) (xy 102.382235 -69.078934) (xy 102.289972 -69.039095)
			(xy 102.201072 -68.992228) (xy 102.116069 -68.938615) (xy 102.035476 -68.878579) (xy 101.959775 -68.81248)
			(xy 101.889422 -68.740715) (xy 101.82484 -68.663715) (xy 101.766417 -68.581944) (xy 101.714505 -68.495893)
			(xy 101.669414 -68.406079) (xy 101.631417 -68.313042) (xy 101.600741 -68.217341) (xy 101.577571 -68.119551)
			(xy 101.562046 -68.02026) (xy 101.554259 -67.920065) (xy 101.553772 -67.869816) (xy 64.146176 -67.869816)
			(xy 64.14552 -67.929021) (xy 64.134706 -68.046936) (xy 64.124586 -68.105274) (xy 64.1223 -68.117212)
			(xy 64.128904 -68.140072) (xy 64.20104 -68.217796) (xy 64.223138 -68.225924) (xy 64.23533 -68.224654)
			(xy 64.293827 -68.218795) (xy 64.411238 -68.212571) (xy 64.470026 -68.212208) (xy 64.537093 -68.212761)
			(xy 64.670978 -68.220931) (xy 64.804115 -68.237252) (xy 64.936009 -68.261662) (xy 65.066169 -68.294071)
			(xy 65.19411 -68.334358) (xy 65.319355 -68.382374) (xy 65.441439 -68.437938) (xy 65.559907 -68.500845)
			(xy 65.674318 -68.570861) (xy 65.784245 -68.647723) (xy 65.88928 -68.731148) (xy 65.989031 -68.820822)
			(xy 66.083128 -68.916414) (xy 66.171219 -69.017567) (xy 66.252976 -69.123904) (xy 66.290952 -69.179186)
			(xy 66.298064 -69.1896) (xy 66.320162 -69.201538) (xy 66.42989 -69.201538) (xy 66.451988 -69.1896)
			(xy 66.4591 -69.179186) (xy 66.497065 -69.123895) (xy 66.578815 -69.017546) (xy 66.666899 -68.916383)
			(xy 66.760991 -68.820781) (xy 66.860739 -68.731096) (xy 66.965772 -68.647664) (xy 67.0757 -68.570794)
			(xy 67.190111 -68.500773) (xy 67.308581 -68.437862) (xy 67.430668 -68.382294) (xy 67.555917 -68.334278)
			(xy 67.683863 -68.293991) (xy 67.814027 -68.261584) (xy 67.945926 -68.237178) (xy 68.079068 -68.220863)
			(xy 68.212957 -68.2127) (xy 68.280026 -68.212208) (xy 68.348503 -68.212702) (xy 68.485191 -68.22123)
			(xy 68.621084 -68.238252) (xy 68.755653 -68.263701) (xy 68.888376 -68.29748) (xy 69.018739 -68.339456)
			(xy 69.146235 -68.389467) (xy 69.270371 -68.447318) (xy 69.390664 -68.512787) (xy 69.448934 -68.548758)
			(xy 69.458332 -68.5546) (xy 69.480176 -68.557394) (xy 69.575426 -68.52793) (xy 69.591682 -68.512944)
			(xy 69.596254 -68.502784) (xy 69.613781 -68.463304) (xy 69.655415 -68.387612) (xy 69.704189 -68.316312)
			(xy 69.759644 -68.250076) (xy 69.821258 -68.189526) (xy 69.88845 -68.135232) (xy 69.960589 -68.087708)
			(xy 70.036994 -68.047398) (xy 70.116946 -68.014684) (xy 70.199693 -67.989873) (xy 70.284454 -67.9732)
			(xy 70.370433 -67.96482) (xy 70.413626 -67.964304) (xy 70.455934 -67.964787) (xy 70.540171 -67.972792)
			(xy 70.623267 -67.988756) (xy 70.704473 -68.012535) (xy 70.783056 -68.043914) (xy 70.858305 -68.08261)
			(xy 70.894194 -68.10502) (xy 70.902583 -68.109903) (xy 70.921626 -68.113574) (xy 70.940669 -68.109903)
			(xy 70.949058 -68.10502) (xy 70.984929 -68.082579) (xy 71.060175 -68.043869) (xy 71.13876 -68.012484)
			(xy 71.219971 -67.988709) (xy 71.303073 -67.972759) (xy 71.387316 -67.964777) (xy 71.429626 -67.964304)
			(xy 71.471934 -67.964787) (xy 71.556171 -67.972792) (xy 71.639267 -67.988756) (xy 71.720473 -68.012535)
			(xy 71.799056 -68.043914) (xy 71.874305 -68.08261) (xy 71.910194 -68.10502) (xy 71.918583 -68.109903)
			(xy 71.937626 -68.113574) (xy 71.956669 -68.109903) (xy 71.965058 -68.10502) (xy 72.000929 -68.082579)
			(xy 72.076175 -68.043869) (xy 72.15476 -68.012484) (xy 72.235971 -67.988709) (xy 72.319073 -67.972759)
			(xy 72.403316 -67.964777) (xy 72.445626 -67.964304) (xy 72.486732 -67.964788) (xy 72.568594 -67.972374)
			(xy 72.649407 -67.987479) (xy 72.728481 -68.009975) (xy 72.805144 -68.03967) (xy 72.87874 -68.076309)
			(xy 72.948642 -68.119582) (xy 73.014255 -68.169118) (xy 73.075018 -68.224496) (xy 73.130414 -68.285243)
			(xy 73.17997 -68.350841) (xy 73.223263 -68.420731) (xy 73.259924 -68.494317) (xy 73.289641 -68.57097)
			(xy 73.312161 -68.650038) (xy 73.32729 -68.730847) (xy 73.3349 -68.812706) (xy 73.335388 -68.853812)
			(xy 73.334894 -68.896127) (xy 73.326862 -68.980375) (xy 73.310862 -69.063479) (xy 73.28704 -69.144687)
			(xy 73.25561 -69.223265) (xy 73.216858 -69.298501) (xy 73.194418 -69.33438) (xy 73.189526 -69.342764)
			(xy 73.185859 -69.36181) (xy 73.189534 -69.380855) (xy 73.194418 -69.389244) (xy 73.216868 -69.425117)
			(xy 73.255619 -69.500355) (xy 73.287048 -69.578933) (xy 73.310873 -69.660142) (xy 73.326876 -69.743246)
			(xy 73.334913 -69.827495) (xy 73.334912 -69.912126) (xy 73.326873 -69.996374) (xy 73.310868 -70.079478)
			(xy 73.287042 -70.160686) (xy 73.25561 -70.239264) (xy 73.216857 -70.314501) (xy 73.194418 -70.35038)
			(xy 73.189526 -70.358764) (xy 73.185859 -70.37781) (xy 73.189534 -70.396855) (xy 73.194418 -70.405244)
			(xy 73.216868 -70.441117) (xy 73.255619 -70.516355) (xy 73.287048 -70.594933) (xy 73.310873 -70.676142)
			(xy 73.326876 -70.759246) (xy 73.334913 -70.843495) (xy 73.334912 -70.928126) (xy 73.326873 -71.012374)
			(xy 73.310868 -71.095478) (xy 73.287042 -71.176686) (xy 73.25561 -71.255264) (xy 73.216857 -71.330501)
			(xy 73.194418 -71.36638) (xy 73.189526 -71.374764) (xy 73.185859 -71.39381) (xy 73.189534 -71.412855)
			(xy 73.194418 -71.421244) (xy 73.216867 -71.457116) (xy 73.25561 -71.532357) (xy 73.287033 -71.610937)
			(xy 73.310852 -71.692146) (xy 73.326851 -71.77525) (xy 73.334887 -71.859497) (xy 73.335388 -71.901812)
			(xy 73.334959 -71.942923) (xy 73.32737 -72.024795) (xy 73.312258 -72.105617) (xy 73.289751 -72.1847)
			(xy 73.260042 -72.261368) (xy 73.223385 -72.334967) (xy 73.180092 -72.404869) (xy 73.130533 -72.470478)
			(xy 73.075131 -72.531233) (xy 73.014358 -72.586616) (xy 72.948733 -72.636154) (xy 72.878817 -72.679424)
			(xy 72.805206 -72.716058) (xy 72.728529 -72.745742) (xy 72.649439 -72.768223) (xy 72.568612 -72.783309)
			(xy 72.486738 -72.790872) (xy 72.445626 -72.79132) (xy 72.403319 -72.790808) (xy 72.319083 -72.782808)
			(xy 72.235987 -72.766849) (xy 72.154781 -72.743076) (xy 72.076198 -72.711702) (xy 72.000948 -72.673011)
			(xy 71.965058 -72.650604) (xy 71.956669 -72.645721) (xy 71.937626 -72.64205) (xy 71.918583 -72.645721)
			(xy 71.910194 -72.650604) (xy 71.874311 -72.673026) (xy 71.799067 -72.711738) (xy 71.720486 -72.743126)
			(xy 71.639277 -72.766904) (xy 71.556176 -72.782859) (xy 71.471936 -72.790845) (xy 71.429626 -72.79132)
			(xy 71.387319 -72.790808) (xy 71.303083 -72.782808) (xy 71.219987 -72.766849) (xy 71.138781 -72.743076)
			(xy 71.060198 -72.711702) (xy 70.984948 -72.673011) (xy 70.949058 -72.650604) (xy 70.940669 -72.645721)
			(xy 70.921626 -72.64205) (xy 70.902583 -72.645721) (xy 70.894194 -72.650604) (xy 70.858311 -72.673026)
			(xy 70.783067 -72.711738) (xy 70.704486 -72.743126) (xy 70.623277 -72.766904) (xy 70.540176 -72.782859)
			(xy 70.455936 -72.790845) (xy 70.413626 -72.79132) (xy 70.372474 -72.790836) (xy 70.290522 -72.783244)
			(xy 70.209621 -72.768112) (xy 70.130464 -72.745571) (xy 70.053729 -72.715814) (xy 69.980071 -72.679093)
			(xy 69.91012 -72.635725) (xy 69.844476 -72.58608) (xy 69.783699 -72.530582) (xy 69.728309 -72.469706)
			(xy 69.678781 -72.403973) (xy 69.635537 -72.333946) (xy 69.616828 -72.29729) (xy 69.611748 -72.287384)
			(xy 69.595492 -72.273922) (xy 69.501004 -72.24776) (xy 69.479922 -72.251062) (xy 69.470778 -72.257158)
			(xy 69.411715 -72.294571) (xy 69.2896 -72.362684) (xy 69.163401 -72.422894) (xy 69.033629 -72.474957)
			(xy 68.900809 -72.518663) (xy 68.765478 -72.553834) (xy 68.628185 -72.580329) (xy 68.489485 -72.59804)
			(xy 68.349939 -72.606894) (xy 68.280026 -72.607424) (xy 68.212958 -72.606939) (xy 68.079071 -72.598766)
			(xy 67.945932 -72.582442) (xy 67.814036 -72.558028) (xy 67.683875 -72.525615) (xy 67.555933 -72.485323)
			(xy 67.430686 -72.437304) (xy 67.308602 -72.381735) (xy 67.190134 -72.318823) (xy 67.075724 -72.248803)
			(xy 66.965797 -72.171935) (xy 66.860763 -72.088506) (xy 66.761013 -71.998827) (xy 66.666918 -71.90323)
			(xy 66.57883 -71.802072) (xy 66.497074 -71.69573) (xy 66.4591 -71.640446) (xy 66.451988 -71.630032)
			(xy 66.42989 -71.618094) (xy 66.320162 -71.618094) (xy 66.298064 -71.630032) (xy 66.290952 -71.640446)
			(xy 66.252963 -71.695721) (xy 66.171215 -71.802068) (xy 66.083131 -71.903231) (xy 65.989041 -71.998833)
			(xy 65.889294 -72.088517) (xy 65.784262 -72.17195) (xy 65.674337 -72.24882) (xy 65.559927 -72.318842)
			(xy 65.441459 -72.381754) (xy 65.319374 -72.437323) (xy 65.194126 -72.485341) (xy 65.066183 -72.525629)
			(xy 64.93602 -72.558038) (xy 64.804123 -72.582447) (xy 64.670982 -72.598765) (xy 64.537094 -72.60693)
			(xy 64.470026 -72.607424) (xy 64.403633 -72.606935) (xy 64.27109 -72.59892) (xy 64.139272 -72.582917)
			(xy 64.008661 -72.558985) (xy 63.879733 -72.52721) (xy 63.752959 -72.48771) (xy 63.628801 -72.440627)
			(xy 63.507712 -72.386135) (xy 63.390133 -72.32443) (xy 63.276495 -72.25574) (xy 63.167211 -72.180314)
			(xy 63.062681 -72.098428) (xy 62.963285 -72.01038) (xy 62.869386 -71.916492) (xy 62.781327 -71.817105)
			(xy 62.699429 -71.712584) (xy 62.623991 -71.603308) (xy 62.555288 -71.489678) (xy 62.493571 -71.372106)
			(xy 62.439065 -71.251023) (xy 62.391969 -71.12687) (xy 62.352455 -71.0001) (xy 62.320666 -70.871176)
			(xy 62.296719 -70.740567) (xy 62.280702 -70.608751) (xy 62.272672 -70.476209) (xy 62.272164 -70.409816)
			(xy 62.272637 -70.34359) (xy 62.280621 -70.211378) (xy 62.296554 -70.079887) (xy 62.320379 -69.949595)
			(xy 62.352008 -69.820975) (xy 62.391329 -69.694493) (xy 62.438196 -69.57061) (xy 62.492441 -69.449774)
			(xy 62.553866 -69.332426) (xy 62.587632 -69.275452) (xy 62.593982 -69.265038) (xy 62.59576 -69.241416)
			(xy 62.555628 -69.143372) (xy 62.537848 -69.127878) (xy 62.52591 -69.124576) (xy 62.477384 -69.111519)
			(xy 62.382312 -69.078946) (xy 62.290048 -69.039106) (xy 62.201148 -68.992238) (xy 62.116146 -68.938624)
			(xy 62.035553 -68.878586) (xy 61.959852 -68.812486) (xy 61.8895 -68.74072) (xy 61.824919 -68.66372)
			(xy 61.766496 -68.581948) (xy 61.714584 -68.495896) (xy 61.669493 -68.406082) (xy 61.631496 -68.313044)
			(xy 61.60082 -68.217342) (xy 61.577651 -68.119552) (xy 61.562126 -68.020261) (xy 61.554339 -67.920065)
			(xy 61.553852 -67.869816) (xy 12.462296 -67.869816) (xy 12.543801 -67.875925) (xy 12.6453 -67.891224)
			(xy 12.745372 -67.914066) (xy 12.843457 -67.944323) (xy 12.939007 -67.981824) (xy 13.031487 -68.026361)
			(xy 13.12038 -68.077685) (xy 13.205189 -68.135508) (xy 13.28544 -68.199507) (xy 13.360685 -68.269324)
			(xy 13.430501 -68.344569) (xy 13.494499 -68.42482) (xy 13.552321 -68.50963) (xy 13.603644 -68.598524)
			(xy 13.64818 -68.691004) (xy 13.685681 -68.786554) (xy 13.715937 -68.88464) (xy 13.738778 -68.984712)
			(xy 13.754077 -69.086211) (xy 13.761748 -69.188569) (xy 13.762228 -69.239892) (xy 13.761691 -69.294799)
			(xy 13.752937 -69.404262) (xy 13.73546 -69.512676) (xy 13.709373 -69.619345) (xy 13.674841 -69.723588)
			(xy 13.632088 -69.824737) (xy 13.581385 -69.922144) (xy 13.523057 -70.015186) (xy 13.490702 -70.05955)
			(xy 13.484624 -70.068604) (xy 13.480031 -70.089902) (xy 13.484626 -70.1112) (xy 13.490702 -70.120256)
			(xy 13.523049 -70.164626) (xy 13.581374 -70.257669) (xy 13.632076 -70.355076) (xy 13.67483 -70.456223)
			(xy 13.709363 -70.560465) (xy 13.735454 -70.667133) (xy 13.752935 -70.775545) (xy 13.761695 -70.885008)
			(xy 13.762228 -70.939914) (xy 13.761756 -70.99124) (xy 13.754085 -71.093606) (xy 13.738787 -71.195112)
			(xy 13.715947 -71.295192) (xy 13.685693 -71.393285) (xy 13.648194 -71.488843) (xy 13.603659 -71.581332)
			(xy 13.552338 -71.670235) (xy 13.494518 -71.755054) (xy 13.430521 -71.835316) (xy 13.360706 -71.910572)
			(xy 13.285463 -71.9804) (xy 13.205212 -72.044411) (xy 13.120403 -72.102247) (xy 13.031509 -72.153584)
			(xy 12.939028 -72.198135) (xy 12.843477 -72.235652) (xy 12.745389 -72.265924) (xy 12.645314 -72.288782)
			(xy 12.54381 -72.304098) (xy 12.441446 -72.311787) (xy 12.39012 -72.312276) (xy 12.339213 -72.311802)
			(xy 12.23768 -72.304233) (xy 12.136987 -72.28916) (xy 12.037688 -72.266667) (xy 11.940329 -72.236876)
			(xy 11.845446 -72.199952) (xy 11.75356 -72.156098) (xy 11.665176 -72.105555) (xy 11.580782 -72.048601)
			(xy 11.50084 -71.98555) (xy 11.42579 -71.916747) (xy 11.356046 -71.842572) (xy 11.291991 -71.763431)
			(xy 11.233977 -71.679762) (xy 11.20775 -71.636128) (xy 11.200892 -71.624444) (xy 11.177524 -71.611236)
			(xy 11.062716 -71.611236) (xy 11.039348 -71.624444) (xy 11.03249 -71.636128) (xy 11.006274 -71.679769)
			(xy 10.948263 -71.763443) (xy 10.88421 -71.842586) (xy 10.814467 -71.916765) (xy 10.739418 -71.98557)
			(xy 10.659476 -72.048624) (xy 10.57508 -72.105579) (xy 10.486695 -72.156122) (xy 10.394806 -72.199975)
			(xy 10.299921 -72.236897) (xy 10.202559 -72.266684) (xy 10.103258 -72.289173) (xy 10.002563 -72.304241)
			(xy 9.901028 -72.311804) (xy 9.85012 -72.312276) (xy 9.798791 -72.311809) (xy 9.696419 -72.304137)
			(xy 9.594908 -72.288835) (xy 9.494824 -72.265988) (xy 9.396727 -72.235726) (xy 9.301167 -72.198216)
			(xy 9.208677 -72.153669) (xy 9.119776 -72.102335) (xy 9.034959 -72.044499) (xy 8.954703 -71.980486)
			(xy 8.879455 -71.910654) (xy 8.809637 -71.835393) (xy 8.745639 -71.755125) (xy 8.687819 -71.670298)
			(xy 8.636501 -71.581386) (xy 8.591972 -71.488888) (xy 8.55448 -71.393321) (xy 8.524235 -71.295219)
			(xy 8.501408 -71.195131) (xy 8.486124 -71.093616) (xy 8.478471 -70.991243) (xy 8.478012 -70.939914)
			(xy 0.509016 -70.939914) (xy 0.509016 -76.019914) (xy 8.478012 -76.019914) (xy 8.478545 -75.965007)
			(xy 8.487299 -75.855543) (xy 8.504775 -75.747129) (xy 8.530863 -75.64046) (xy 8.565395 -75.536217)
			(xy 8.608149 -75.435068) (xy 8.658854 -75.337662) (xy 8.717182 -75.24462) (xy 8.749538 -75.200256)
			(xy 8.755682 -75.191222) (xy 8.760349 -75.169902) (xy 8.755684 -75.148582) (xy 8.749538 -75.13955)
			(xy 8.717186 -75.095184) (xy 8.65886 -75.002141) (xy 8.608158 -74.904733) (xy 8.565404 -74.803585)
			(xy 8.530872 -74.699343) (xy 8.504782 -74.592674) (xy 8.487302 -74.484262) (xy 8.478544 -74.374799)
			(xy 8.478012 -74.319892) (xy 8.478453 -74.268568) (xy 8.486124 -74.166208) (xy 8.501424 -74.064707)
			(xy 8.524266 -73.964633) (xy 8.554522 -73.866547) (xy 8.592024 -73.770995) (xy 8.636562 -73.678513)
			(xy 8.687887 -73.589618) (xy 8.745711 -73.504808) (xy 8.809711 -73.424555) (xy 8.87953 -73.34931)
			(xy 8.954776 -73.279493) (xy 9.03503 -73.215494) (xy 9.119842 -73.157672) (xy 9.208738 -73.106349)
			(xy 9.301221 -73.061813) (xy 9.396773 -73.024313) (xy 9.49486 -72.994058) (xy 9.594935 -72.971218)
			(xy 9.696436 -72.955921) (xy 9.798796 -72.948252) (xy 9.85012 -72.947784) (xy 9.901023 -72.948245)
			(xy 10.00255 -72.955789) (xy 10.103239 -72.970838) (xy 10.202535 -72.993308) (xy 10.299893 -73.023077)
			(xy 10.394776 -73.05998) (xy 10.486663 -73.103815) (xy 10.575047 -73.154339) (xy 10.659444 -73.211276)
			(xy 10.739389 -73.274313) (xy 10.814441 -73.343101) (xy 10.884187 -73.417263) (xy 10.948245 -73.496391)
			(xy 11.006262 -73.580049) (xy 11.03249 -73.623678) (xy 11.039348 -73.635362) (xy 11.062716 -73.64857)
			(xy 11.177524 -73.64857) (xy 11.200892 -73.635362) (xy 11.20775 -73.623678) (xy 11.233971 -73.580045)
			(xy 11.291989 -73.496388) (xy 11.356048 -73.417261) (xy 11.425796 -73.3431) (xy 11.500849 -73.274313)
			(xy 11.580794 -73.211277) (xy 11.665192 -73.154341) (xy 11.753577 -73.103817) (xy 11.845464 -73.059983)
			(xy 11.940347 -73.02308) (xy 12.037705 -72.993311) (xy 12.137001 -72.970841) (xy 12.23769 -72.955792)
			(xy 12.339217 -72.948247) (xy 12.39012 -72.947784) (xy 12.441443 -72.948253) (xy 12.543801 -72.955925)
			(xy 12.6453 -72.971224) (xy 12.745372 -72.994066) (xy 12.843457 -73.024323) (xy 12.939007 -73.061824)
			(xy 13.031487 -73.106361) (xy 13.12038 -73.157685) (xy 13.205189 -73.215508) (xy 13.28544 -73.279507)
			(xy 13.360685 -73.349324) (xy 13.430501 -73.424569) (xy 13.494499 -73.50482) (xy 13.552321 -73.58963)
			(xy 13.603644 -73.678524) (xy 13.64818 -73.771004) (xy 13.685681 -73.866554) (xy 13.715937 -73.96464)
			(xy 13.738778 -74.064712) (xy 13.754077 -74.166211) (xy 13.761748 -74.268569) (xy 13.762228 -74.319892)
			(xy 13.761691 -74.374799) (xy 13.752937 -74.484262) (xy 13.73546 -74.592676) (xy 13.709373 -74.699345)
			(xy 13.674841 -74.803588) (xy 13.632088 -74.904737) (xy 13.581385 -75.002144) (xy 13.523057 -75.095186)
			(xy 13.490702 -75.13955) (xy 13.484624 -75.148604) (xy 13.480031 -75.169902) (xy 13.484626 -75.1912)
			(xy 13.490702 -75.200256) (xy 13.523049 -75.244626) (xy 13.581374 -75.337669) (xy 13.632076 -75.435076)
			(xy 13.67483 -75.536223) (xy 13.709363 -75.640465) (xy 13.735454 -75.747133) (xy 13.752935 -75.855545)
			(xy 13.761695 -75.965008) (xy 13.762228 -76.019914) (xy 13.761756 -76.07124) (xy 13.754085 -76.173606)
			(xy 13.738787 -76.275112) (xy 13.715947 -76.375192) (xy 13.685693 -76.473285) (xy 13.648194 -76.568843)
			(xy 13.603659 -76.661332) (xy 13.552338 -76.750235) (xy 13.494518 -76.835054) (xy 13.430521 -76.915316)
			(xy 13.360706 -76.990572) (xy 13.285463 -77.0604) (xy 13.205212 -77.124411) (xy 13.120403 -77.182247)
			(xy 13.031509 -77.233584) (xy 12.939028 -77.278135) (xy 12.843477 -77.315652) (xy 12.745389 -77.345924)
			(xy 12.645314 -77.368782) (xy 12.54381 -77.384098) (xy 12.441446 -77.391787) (xy 12.39012 -77.392276)
			(xy 12.339213 -77.391802) (xy 12.23768 -77.384233) (xy 12.136987 -77.36916) (xy 12.037688 -77.346667)
			(xy 11.940329 -77.316876) (xy 11.845446 -77.279952) (xy 11.75356 -77.236098) (xy 11.665176 -77.185555)
			(xy 11.580782 -77.128601) (xy 11.50084 -77.06555) (xy 11.42579 -76.996747) (xy 11.356046 -76.922572)
			(xy 11.291991 -76.843431) (xy 11.233977 -76.759762) (xy 11.20775 -76.716128) (xy 11.200892 -76.704444)
			(xy 11.177524 -76.691236) (xy 11.062716 -76.691236) (xy 11.039348 -76.704444) (xy 11.03249 -76.716128)
			(xy 11.006274 -76.759769) (xy 10.948263 -76.843443) (xy 10.88421 -76.922586) (xy 10.814467 -76.996765)
			(xy 10.739418 -77.06557) (xy 10.659476 -77.128624) (xy 10.57508 -77.185579) (xy 10.486695 -77.236122)
			(xy 10.394806 -77.279975) (xy 10.299921 -77.316897) (xy 10.202559 -77.346684) (xy 10.103258 -77.369173)
			(xy 10.002563 -77.384241) (xy 9.901028 -77.391804) (xy 9.85012 -77.392276) (xy 9.798791 -77.391809)
			(xy 9.696419 -77.384137) (xy 9.594908 -77.368835) (xy 9.494824 -77.345988) (xy 9.396727 -77.315726)
			(xy 9.301167 -77.278216) (xy 9.208677 -77.233669) (xy 9.119776 -77.182335) (xy 9.034959 -77.124499)
			(xy 8.954703 -77.060486) (xy 8.879455 -76.990654) (xy 8.809637 -76.915393) (xy 8.745639 -76.835125)
			(xy 8.687819 -76.750298) (xy 8.636501 -76.661386) (xy 8.591972 -76.568888) (xy 8.55448 -76.473321)
			(xy 8.524235 -76.375219) (xy 8.501408 -76.275131) (xy 8.486124 -76.173616) (xy 8.478471 -76.071243)
			(xy 8.478012 -76.019914) (xy 0.509016 -76.019914) (xy 0.509016 -77.760011) (xy 61.960756 -77.760011)
			(xy 61.960756 -77.675289) (xy 61.968809 -77.590952) (xy 61.984843 -77.507762) (xy 62.008711 -77.426472)
			(xy 62.040199 -77.34782) (xy 62.079021 -77.272517) (xy 62.124824 -77.201245) (xy 62.177195 -77.134649)
			(xy 62.23566 -77.073334) (xy 62.299688 -77.017853) (xy 62.3687 -76.96871) (xy 62.44207 -76.92635)
			(xy 62.519135 -76.891155) (xy 62.599197 -76.863446) (xy 62.68153 -76.843472) (xy 62.765389 -76.831415)
			(xy 62.850014 -76.827384) (xy 62.934639 -76.831415) (xy 63.018498 -76.843472) (xy 63.100831 -76.863446)
			(xy 63.180893 -76.891155) (xy 63.257958 -76.92635) (xy 63.331328 -76.96871) (xy 63.40034 -77.017853)
			(xy 63.464368 -77.073334) (xy 63.522833 -77.134649) (xy 63.575204 -77.201245) (xy 63.621007 -77.272517)
			(xy 63.659829 -77.34782) (xy 63.691317 -77.426472) (xy 63.715185 -77.507762) (xy 63.731219 -77.590952)
			(xy 63.739272 -77.675289) (xy 63.739776 -77.71765) (xy 63.739272 -77.760011) (xy 101.960676 -77.760011)
			(xy 101.960676 -77.675289) (xy 101.968729 -77.590952) (xy 101.984763 -77.507762) (xy 102.008631 -77.426472)
			(xy 102.040119 -77.34782) (xy 102.078941 -77.272517) (xy 102.124744 -77.201245) (xy 102.177115 -77.134649)
			(xy 102.23558 -77.073334) (xy 102.299608 -77.017853) (xy 102.36862 -76.96871) (xy 102.44199 -76.92635)
			(xy 102.519055 -76.891155) (xy 102.599117 -76.863446) (xy 102.68145 -76.843472) (xy 102.765309 -76.831415)
			(xy 102.849934 -76.827384) (xy 102.934559 -76.831415) (xy 103.018418 -76.843472) (xy 103.100751 -76.863446)
			(xy 103.180813 -76.891155) (xy 103.257878 -76.92635) (xy 103.331248 -76.96871) (xy 103.40026 -77.017853)
			(xy 103.464288 -77.073334) (xy 103.522753 -77.134649) (xy 103.575124 -77.201245) (xy 103.620927 -77.272517)
			(xy 103.659749 -77.34782) (xy 103.691237 -77.426472) (xy 103.715105 -77.507762) (xy 103.731139 -77.590952)
			(xy 103.739192 -77.675289) (xy 103.739696 -77.71765) (xy 103.739192 -77.760011) (xy 141.96085 -77.760011)
			(xy 141.96085 -77.675289) (xy 141.968903 -77.590952) (xy 141.984937 -77.507762) (xy 142.008805 -77.426472)
			(xy 142.040293 -77.34782) (xy 142.079115 -77.272517) (xy 142.124918 -77.201245) (xy 142.177289 -77.134649)
			(xy 142.235754 -77.073334) (xy 142.299782 -77.017853) (xy 142.368794 -76.96871) (xy 142.442164 -76.92635)
			(xy 142.519229 -76.891155) (xy 142.599291 -76.863446) (xy 142.681624 -76.843472) (xy 142.765483 -76.831415)
			(xy 142.850108 -76.827384) (xy 142.934733 -76.831415) (xy 143.018592 -76.843472) (xy 143.100925 -76.863446)
			(xy 143.180987 -76.891155) (xy 143.258052 -76.92635) (xy 143.331422 -76.96871) (xy 143.400434 -77.017853)
			(xy 143.464462 -77.073334) (xy 143.522927 -77.134649) (xy 143.575298 -77.201245) (xy 143.621101 -77.272517)
			(xy 143.659923 -77.34782) (xy 143.691411 -77.426472) (xy 143.715279 -77.507762) (xy 143.731313 -77.590952)
			(xy 143.739366 -77.675289) (xy 143.73987 -77.71765) (xy 143.739366 -77.760011) (xy 181.961024 -77.760011)
			(xy 181.961024 -77.675289) (xy 181.969077 -77.590952) (xy 181.985111 -77.507762) (xy 182.008979 -77.426472)
			(xy 182.040467 -77.34782) (xy 182.079289 -77.272517) (xy 182.125092 -77.201245) (xy 182.177463 -77.134649)
			(xy 182.235928 -77.073334) (xy 182.299956 -77.017853) (xy 182.368968 -76.96871) (xy 182.442338 -76.92635)
			(xy 182.519403 -76.891155) (xy 182.599465 -76.863446) (xy 182.681798 -76.843472) (xy 182.765657 -76.831415)
			(xy 182.850282 -76.827384) (xy 182.934907 -76.831415) (xy 183.018766 -76.843472) (xy 183.101099 -76.863446)
			(xy 183.181161 -76.891155) (xy 183.258226 -76.92635) (xy 183.331596 -76.96871) (xy 183.400608 -77.017853)
			(xy 183.464636 -77.073334) (xy 183.523101 -77.134649) (xy 183.575472 -77.201245) (xy 183.621275 -77.272517)
			(xy 183.660097 -77.34782) (xy 183.691585 -77.426472) (xy 183.715453 -77.507762) (xy 183.731487 -77.590952)
			(xy 183.732064 -77.597) (xy 268.350492 -77.597) (xy 268.351075 -77.550604) (xy 268.36072 -77.458316)
			(xy 268.379916 -77.367532) (xy 268.408454 -77.279239) (xy 268.426692 -77.236574) (xy 268.430498 -77.226632)
			(xy 268.430498 -77.205368) (xy 268.426692 -77.195426) (xy 268.408447 -77.152764) (xy 268.379903 -77.064471)
			(xy 268.36071 -76.973686) (xy 268.351077 -76.881396) (xy 268.350492 -76.835) (xy 268.351075 -76.788604)
			(xy 268.36072 -76.696316) (xy 268.379916 -76.605532) (xy 268.408454 -76.517239) (xy 268.426692 -76.474574)
			(xy 268.430498 -76.464632) (xy 268.430498 -76.443368) (xy 268.426692 -76.433426) (xy 268.408447 -76.390764)
			(xy 268.379903 -76.302471) (xy 268.36071 -76.211686) (xy 268.351077 -76.119396) (xy 268.350492 -76.073)
			(xy 268.351075 -76.026604) (xy 268.36072 -75.934316) (xy 268.379916 -75.843532) (xy 268.408454 -75.755239)
			(xy 268.426692 -75.712574) (xy 268.430498 -75.702632) (xy 268.430498 -75.681368) (xy 268.426692 -75.671426)
			(xy 268.408447 -75.628764) (xy 268.379903 -75.540471) (xy 268.36071 -75.449686) (xy 268.351077 -75.357396)
			(xy 268.350492 -75.311) (xy 268.351075 -75.264604) (xy 268.36072 -75.172316) (xy 268.379916 -75.081532)
			(xy 268.408454 -74.993239) (xy 268.426692 -74.950574) (xy 268.430498 -74.940632) (xy 268.430498 -74.919368)
			(xy 268.426692 -74.909426) (xy 268.408447 -74.866764) (xy 268.379903 -74.778471) (xy 268.36071 -74.687686)
			(xy 268.351077 -74.595396) (xy 268.350492 -74.549) (xy 268.351075 -74.502604) (xy 268.36072 -74.410316)
			(xy 268.379916 -74.319532) (xy 268.408454 -74.231239) (xy 268.426692 -74.188574) (xy 268.430498 -74.178632)
			(xy 268.430498 -74.157368) (xy 268.426692 -74.147426) (xy 268.408447 -74.104764) (xy 268.379903 -74.016471)
			(xy 268.36071 -73.925686) (xy 268.351077 -73.833396) (xy 268.350492 -73.787) (xy 268.350967 -73.745898)
			(xy 268.358552 -73.664043) (xy 268.373657 -73.583238) (xy 268.396153 -73.504171) (xy 268.425849 -73.427517)
			(xy 268.462491 -73.35393) (xy 268.505766 -73.284038) (xy 268.555306 -73.218437) (xy 268.610687 -73.157687)
			(xy 268.671437 -73.102306) (xy 268.737038 -73.052766) (xy 268.80693 -73.009491) (xy 268.880517 -72.972849)
			(xy 268.957171 -72.943153) (xy 269.036238 -72.920657) (xy 269.117043 -72.905552) (xy 269.198898 -72.897967)
			(xy 269.24 -72.897492) (xy 269.286396 -72.898075) (xy 269.378684 -72.90772) (xy 269.469468 -72.926916)
			(xy 269.557761 -72.955454) (xy 269.600426 -72.973692) (xy 269.610368 -72.977498) (xy 269.631632 -72.977498)
			(xy 269.641574 -72.973692) (xy 269.684236 -72.955447) (xy 269.772529 -72.926903) (xy 269.863314 -72.90771)
			(xy 269.955604 -72.898077) (xy 270.002 -72.897492) (xy 270.048396 -72.898075) (xy 270.140684 -72.90772)
			(xy 270.231468 -72.926916) (xy 270.319761 -72.955454) (xy 270.362426 -72.973692) (xy 270.372368 -72.977498)
			(xy 270.393632 -72.977498) (xy 270.403574 -72.973692) (xy 270.446236 -72.955447) (xy 270.534529 -72.926903)
			(xy 270.625314 -72.90771) (xy 270.717604 -72.898077) (xy 270.764 -72.897492) (xy 270.810396 -72.898075)
			(xy 270.902684 -72.90772) (xy 270.993468 -72.926916) (xy 271.081761 -72.955454) (xy 271.124426 -72.973692)
			(xy 271.134368 -72.977498) (xy 271.155632 -72.977498) (xy 271.165574 -72.973692) (xy 271.208236 -72.955447)
			(xy 271.296529 -72.926903) (xy 271.387314 -72.90771) (xy 271.479604 -72.898077) (xy 271.526 -72.897492)
			(xy 271.572396 -72.898075) (xy 271.664684 -72.90772) (xy 271.755468 -72.926916) (xy 271.843761 -72.955454)
			(xy 271.886426 -72.973692) (xy 271.896368 -72.977498) (xy 271.917632 -72.977498) (xy 271.927574 -72.973692)
			(xy 271.970236 -72.955447) (xy 272.058529 -72.926903) (xy 272.149314 -72.90771) (xy 272.241604 -72.898077)
			(xy 272.288 -72.897492) (xy 272.329102 -72.897967) (xy 272.410957 -72.905552) (xy 272.491762 -72.920657)
			(xy 272.570829 -72.943153) (xy 272.647483 -72.972849) (xy 272.72107 -73.009491) (xy 272.790962 -73.052766)
			(xy 272.856563 -73.102306) (xy 272.917313 -73.157687) (xy 272.972694 -73.218437) (xy 273.022234 -73.284038)
			(xy 273.065509 -73.35393) (xy 273.102151 -73.427517) (xy 273.131847 -73.504171) (xy 273.154343 -73.583238)
			(xy 273.169448 -73.664043) (xy 273.177033 -73.745898) (xy 273.177508 -73.787) (xy 273.176925 -73.833396)
			(xy 273.16728 -73.925684) (xy 273.148084 -74.016468) (xy 273.119546 -74.104761) (xy 273.101308 -74.147426)
			(xy 273.097502 -74.157368) (xy 273.097502 -74.178632) (xy 273.101308 -74.188574) (xy 273.119553 -74.231236)
			(xy 273.148097 -74.319529) (xy 273.16729 -74.410314) (xy 273.176923 -74.502604) (xy 273.177508 -74.549)
			(xy 273.177033 -74.590102) (xy 273.169448 -74.671957) (xy 273.154343 -74.752762) (xy 273.131847 -74.831829)
			(xy 273.102151 -74.908483) (xy 273.065509 -74.98207) (xy 273.022234 -75.051962) (xy 272.972694 -75.117563)
			(xy 272.917313 -75.178313) (xy 272.856563 -75.233694) (xy 272.790962 -75.283234) (xy 272.72107 -75.326509)
			(xy 272.647483 -75.363151) (xy 272.570829 -75.392847) (xy 272.491762 -75.415343) (xy 272.410957 -75.430448)
			(xy 272.329102 -75.438033) (xy 272.288 -75.438508) (xy 272.241604 -75.437925) (xy 272.149316 -75.42828)
			(xy 272.058532 -75.409084) (xy 271.970239 -75.380546) (xy 271.927574 -75.362308) (xy 271.917632 -75.358502)
			(xy 271.896368 -75.358502) (xy 271.886426 -75.362308) (xy 271.853507 -75.376537) (xy 271.785822 -75.400257)
			(xy 271.716442 -75.418437) (xy 271.681194 -75.425046) (xy 271.67107 -75.427344) (xy 271.653749 -75.438749)
			(xy 271.642344 -75.45607) (xy 271.640046 -75.466194) (xy 271.633416 -75.501437) (xy 271.61522 -75.57081)
			(xy 271.591513 -75.638498) (xy 271.577308 -75.671426) (xy 271.573502 -75.681368) (xy 271.573502 -75.702632)
			(xy 271.577308 -75.712574) (xy 271.591537 -75.745493) (xy 271.615257 -75.813178) (xy 271.633437 -75.882558)
			(xy 271.640046 -75.917806) (xy 271.642344 -75.92793) (xy 271.653749 -75.945251) (xy 271.67107 -75.956656)
			(xy 271.681194 -75.958954) (xy 271.716437 -75.965584) (xy 271.78581 -75.98378) (xy 271.853498 -76.007487)
			(xy 271.886426 -76.021692) (xy 271.896368 -76.025498) (xy 271.917632 -76.025498) (xy 271.927574 -76.021692)
			(xy 271.970236 -76.003447) (xy 272.058529 -75.974903) (xy 272.149314 -75.95571) (xy 272.241604 -75.946077)
			(xy 272.288 -75.945492) (xy 272.329102 -75.945967) (xy 272.410957 -75.953552) (xy 272.491762 -75.968657)
			(xy 272.570829 -75.991153) (xy 272.647483 -76.020849) (xy 272.72107 -76.057491) (xy 272.790962 -76.100766)
			(xy 272.856563 -76.150306) (xy 272.917313 -76.205687) (xy 272.972694 -76.266437) (xy 273.022234 -76.332038)
			(xy 273.065509 -76.40193) (xy 273.102151 -76.475517) (xy 273.131847 -76.552171) (xy 273.154343 -76.631238)
			(xy 273.169448 -76.712043) (xy 273.177033 -76.793898) (xy 273.177508 -76.835) (xy 273.176925 -76.881396)
			(xy 273.16728 -76.973684) (xy 273.148084 -77.064468) (xy 273.119546 -77.152761) (xy 273.101308 -77.195426)
			(xy 273.097502 -77.205368) (xy 273.097502 -77.226632) (xy 273.101308 -77.236574) (xy 273.119553 -77.279236)
			(xy 273.148097 -77.367529) (xy 273.16729 -77.458314) (xy 273.176923 -77.550604) (xy 273.177508 -77.597)
			(xy 273.177033 -77.638102) (xy 273.169448 -77.719957) (xy 273.154343 -77.800762) (xy 273.131847 -77.879829)
			(xy 273.102151 -77.956483) (xy 273.065509 -78.03007) (xy 273.022234 -78.099962) (xy 272.972694 -78.165563)
			(xy 272.917313 -78.226313) (xy 272.856563 -78.281694) (xy 272.790962 -78.331234) (xy 272.72107 -78.374509)
			(xy 272.647483 -78.411151) (xy 272.570829 -78.440847) (xy 272.491762 -78.463343) (xy 272.410957 -78.478448)
			(xy 272.329102 -78.486033) (xy 272.288 -78.486508) (xy 272.241604 -78.485925) (xy 272.149316 -78.47628)
			(xy 272.058532 -78.457084) (xy 271.970239 -78.428546) (xy 271.927574 -78.410308) (xy 271.917632 -78.406502)
			(xy 271.896368 -78.406502) (xy 271.886426 -78.410308) (xy 271.843764 -78.428553) (xy 271.755471 -78.457097)
			(xy 271.664686 -78.47629) (xy 271.572396 -78.485923) (xy 271.526 -78.486508) (xy 271.479604 -78.485925)
			(xy 271.387316 -78.47628) (xy 271.296532 -78.457084) (xy 271.208239 -78.428546) (xy 271.165574 -78.410308)
			(xy 271.155632 -78.406502) (xy 271.134368 -78.406502) (xy 271.124426 -78.410308) (xy 271.081764 -78.428553)
			(xy 270.993471 -78.457097) (xy 270.902686 -78.47629) (xy 270.810396 -78.485923) (xy 270.764 -78.486508)
			(xy 270.717604 -78.485925) (xy 270.625316 -78.47628) (xy 270.534532 -78.457084) (xy 270.446239 -78.428546)
			(xy 270.403574 -78.410308) (xy 270.393632 -78.406502) (xy 270.372368 -78.406502) (xy 270.362426 -78.410308)
			(xy 270.319764 -78.428553) (xy 270.231471 -78.457097) (xy 270.140686 -78.47629) (xy 270.048396 -78.485923)
			(xy 270.002 -78.486508) (xy 269.955604 -78.485925) (xy 269.863316 -78.47628) (xy 269.772532 -78.457084)
			(xy 269.684239 -78.428546) (xy 269.641574 -78.410308) (xy 269.631632 -78.406502) (xy 269.610368 -78.406502)
			(xy 269.600426 -78.410308) (xy 269.557764 -78.428553) (xy 269.469471 -78.457097) (xy 269.378686 -78.47629)
			(xy 269.286396 -78.485923) (xy 269.24 -78.486508) (xy 269.198898 -78.486033) (xy 269.117043 -78.478448)
			(xy 269.036238 -78.463343) (xy 268.957171 -78.440847) (xy 268.880517 -78.411151) (xy 268.80693 -78.374509)
			(xy 268.737038 -78.331234) (xy 268.671437 -78.281694) (xy 268.610687 -78.226313) (xy 268.555306 -78.165563)
			(xy 268.505766 -78.099962) (xy 268.462491 -78.03007) (xy 268.425849 -77.956483) (xy 268.396153 -77.879829)
			(xy 268.373657 -77.800762) (xy 268.358552 -77.719957) (xy 268.350967 -77.638102) (xy 268.350492 -77.597)
			(xy 183.732064 -77.597) (xy 183.73954 -77.675289) (xy 183.740044 -77.71765) (xy 183.73954 -77.760011)
			(xy 183.731487 -77.844348) (xy 183.715453 -77.927538) (xy 183.691585 -78.008828) (xy 183.660097 -78.08748)
			(xy 183.621275 -78.162783) (xy 183.575472 -78.234055) (xy 183.523101 -78.300651) (xy 183.464636 -78.361966)
			(xy 183.400608 -78.417447) (xy 183.331596 -78.46659) (xy 183.258226 -78.50895) (xy 183.181161 -78.544145)
			(xy 183.101099 -78.571854) (xy 183.018766 -78.591828) (xy 182.934907 -78.603885) (xy 182.850282 -78.607917)
			(xy 182.765657 -78.603885) (xy 182.681798 -78.591828) (xy 182.599465 -78.571854) (xy 182.519403 -78.544145)
			(xy 182.442338 -78.50895) (xy 182.368968 -78.46659) (xy 182.299956 -78.417447) (xy 182.235928 -78.361966)
			(xy 182.177463 -78.300651) (xy 182.125092 -78.234055) (xy 182.079289 -78.162783) (xy 182.040467 -78.08748)
			(xy 182.008979 -78.008828) (xy 181.985111 -77.927538) (xy 181.969077 -77.844348) (xy 181.961024 -77.760011)
			(xy 143.739366 -77.760011) (xy 143.731313 -77.844348) (xy 143.715279 -77.927538) (xy 143.691411 -78.008828)
			(xy 143.659923 -78.08748) (xy 143.621101 -78.162783) (xy 143.575298 -78.234055) (xy 143.522927 -78.300651)
			(xy 143.464462 -78.361966) (xy 143.400434 -78.417447) (xy 143.331422 -78.46659) (xy 143.258052 -78.50895)
			(xy 143.180987 -78.544145) (xy 143.100925 -78.571854) (xy 143.018592 -78.591828) (xy 142.934733 -78.603885)
			(xy 142.850108 -78.607917) (xy 142.765483 -78.603885) (xy 142.681624 -78.591828) (xy 142.599291 -78.571854)
			(xy 142.519229 -78.544145) (xy 142.442164 -78.50895) (xy 142.368794 -78.46659) (xy 142.299782 -78.417447)
			(xy 142.235754 -78.361966) (xy 142.177289 -78.300651) (xy 142.124918 -78.234055) (xy 142.079115 -78.162783)
			(xy 142.040293 -78.08748) (xy 142.008805 -78.008828) (xy 141.984937 -77.927538) (xy 141.968903 -77.844348)
			(xy 141.96085 -77.760011) (xy 103.739192 -77.760011) (xy 103.731139 -77.844348) (xy 103.715105 -77.927538)
			(xy 103.691237 -78.008828) (xy 103.659749 -78.08748) (xy 103.620927 -78.162783) (xy 103.575124 -78.234055)
			(xy 103.522753 -78.300651) (xy 103.464288 -78.361966) (xy 103.40026 -78.417447) (xy 103.331248 -78.46659)
			(xy 103.257878 -78.50895) (xy 103.180813 -78.544145) (xy 103.100751 -78.571854) (xy 103.018418 -78.591828)
			(xy 102.934559 -78.603885) (xy 102.849934 -78.607917) (xy 102.765309 -78.603885) (xy 102.68145 -78.591828)
			(xy 102.599117 -78.571854) (xy 102.519055 -78.544145) (xy 102.44199 -78.50895) (xy 102.36862 -78.46659)
			(xy 102.299608 -78.417447) (xy 102.23558 -78.361966) (xy 102.177115 -78.300651) (xy 102.124744 -78.234055)
			(xy 102.078941 -78.162783) (xy 102.040119 -78.08748) (xy 102.008631 -78.008828) (xy 101.984763 -77.927538)
			(xy 101.968729 -77.844348) (xy 101.960676 -77.760011) (xy 63.739272 -77.760011) (xy 63.731219 -77.844348)
			(xy 63.715185 -77.927538) (xy 63.691317 -78.008828) (xy 63.659829 -78.08748) (xy 63.621007 -78.162783)
			(xy 63.575204 -78.234055) (xy 63.522833 -78.300651) (xy 63.464368 -78.361966) (xy 63.40034 -78.417447)
			(xy 63.331328 -78.46659) (xy 63.257958 -78.50895) (xy 63.180893 -78.544145) (xy 63.100831 -78.571854)
			(xy 63.018498 -78.591828) (xy 62.934639 -78.603885) (xy 62.850014 -78.607917) (xy 62.765389 -78.603885)
			(xy 62.68153 -78.591828) (xy 62.599197 -78.571854) (xy 62.519135 -78.544145) (xy 62.44207 -78.50895)
			(xy 62.3687 -78.46659) (xy 62.299688 -78.417447) (xy 62.23566 -78.361966) (xy 62.177195 -78.300651)
			(xy 62.124824 -78.234055) (xy 62.079021 -78.162783) (xy 62.040199 -78.08748) (xy 62.008711 -78.008828)
			(xy 61.984843 -77.927538) (xy 61.968809 -77.844348) (xy 61.960756 -77.760011) (xy 0.509016 -77.760011)
			(xy 0.509016 -80.799629) (xy 270.301208 -80.799629) (xy 270.301208 -80.714907) (xy 270.309261 -80.63057)
			(xy 270.325295 -80.54738) (xy 270.349163 -80.46609) (xy 270.380651 -80.387438) (xy 270.419473 -80.312135)
			(xy 270.465276 -80.240863) (xy 270.517647 -80.174267) (xy 270.576112 -80.112952) (xy 270.64014 -80.057471)
			(xy 270.709152 -80.008328) (xy 270.782522 -79.965968) (xy 270.859587 -79.930773) (xy 270.939649 -79.903064)
			(xy 271.021982 -79.88309) (xy 271.105841 -79.871033) (xy 271.190466 -79.867002) (xy 271.275091 -79.871033)
			(xy 271.35895 -79.88309) (xy 271.441283 -79.903064) (xy 271.521345 -79.930773) (xy 271.59841 -79.965968)
			(xy 271.67178 -80.008328) (xy 271.740792 -80.057471) (xy 271.80482 -80.112952) (xy 271.863285 -80.174267)
			(xy 271.915656 -80.240863) (xy 271.961459 -80.312135) (xy 272.000281 -80.387438) (xy 272.031769 -80.46609)
			(xy 272.055637 -80.54738) (xy 272.071671 -80.63057) (xy 272.079724 -80.714907) (xy 272.080228 -80.757268)
			(xy 272.079724 -80.799629) (xy 272.071671 -80.883966) (xy 272.055637 -80.967156) (xy 272.031769 -81.048446)
			(xy 272.000281 -81.127098) (xy 271.961459 -81.202401) (xy 271.915656 -81.273673) (xy 271.863285 -81.340269)
			(xy 271.80482 -81.401584) (xy 271.740792 -81.457065) (xy 271.67178 -81.506208) (xy 271.59841 -81.548568)
			(xy 271.521345 -81.583763) (xy 271.441283 -81.611472) (xy 271.35895 -81.631446) (xy 271.275091 -81.643503)
			(xy 271.190466 -81.647535) (xy 271.105841 -81.643503) (xy 271.021982 -81.631446) (xy 270.939649 -81.611472)
			(xy 270.859587 -81.583763) (xy 270.782522 -81.548568) (xy 270.709152 -81.506208) (xy 270.64014 -81.457065)
			(xy 270.576112 -81.401584) (xy 270.517647 -81.340269) (xy 270.465276 -81.273673) (xy 270.419473 -81.202401)
			(xy 270.380651 -81.127098) (xy 270.349163 -81.048446) (xy 270.325295 -80.967156) (xy 270.309261 -80.883966)
			(xy 270.301208 -80.799629) (xy 0.509016 -80.799629) (xy 0.509016 -82.272829) (xy 268.757142 -82.272829)
			(xy 268.757142 -82.188107) (xy 268.765195 -82.10377) (xy 268.781229 -82.02058) (xy 268.805097 -81.93929)
			(xy 268.836585 -81.860638) (xy 268.875407 -81.785335) (xy 268.92121 -81.714063) (xy 268.973581 -81.647467)
			(xy 269.032046 -81.586152) (xy 269.096074 -81.530671) (xy 269.165086 -81.481528) (xy 269.238456 -81.439168)
			(xy 269.315521 -81.403973) (xy 269.395583 -81.376264) (xy 269.477916 -81.35629) (xy 269.561775 -81.344233)
			(xy 269.6464 -81.340202) (xy 269.731025 -81.344233) (xy 269.814884 -81.35629) (xy 269.897217 -81.376264)
			(xy 269.977279 -81.403973) (xy 270.054344 -81.439168) (xy 270.127714 -81.481528) (xy 270.196726 -81.530671)
			(xy 270.260754 -81.586152) (xy 270.319219 -81.647467) (xy 270.37159 -81.714063) (xy 270.417393 -81.785335)
			(xy 270.456215 -81.860638) (xy 270.487703 -81.93929) (xy 270.511571 -82.02058) (xy 270.527605 -82.10377)
			(xy 270.535658 -82.188107) (xy 270.536162 -82.230468) (xy 270.535658 -82.272829) (xy 270.527605 -82.357166)
			(xy 270.511571 -82.440356) (xy 270.487703 -82.521646) (xy 270.456215 -82.600298) (xy 270.417393 -82.675601)
			(xy 270.37159 -82.746873) (xy 270.319219 -82.813469) (xy 270.260754 -82.874784) (xy 270.196726 -82.930265)
			(xy 270.127714 -82.979408) (xy 270.054344 -83.021768) (xy 269.977279 -83.056963) (xy 269.897217 -83.084672)
			(xy 269.814884 -83.104646) (xy 269.731025 -83.116703) (xy 269.6464 -83.120735) (xy 269.561775 -83.116703)
			(xy 269.477916 -83.104646) (xy 269.395583 -83.084672) (xy 269.315521 -83.056963) (xy 269.238456 -83.021768)
			(xy 269.165086 -82.979408) (xy 269.096074 -82.930265) (xy 269.032046 -82.874784) (xy 268.973581 -82.813469)
			(xy 268.92121 -82.746873) (xy 268.875407 -82.675601) (xy 268.836585 -82.600298) (xy 268.805097 -82.521646)
			(xy 268.781229 -82.440356) (xy 268.765195 -82.357166) (xy 268.757142 -82.272829) (xy 0.509016 -82.272829)
			(xy 0.509016 -83.749896) (xy 11.118856 -83.749896) (xy 11.122874 -83.648894) (xy 11.134905 -83.54853)
			(xy 11.154871 -83.44944) (xy 11.182647 -83.352249) (xy 11.218058 -83.257572) (xy 11.260878 -83.166008)
			(xy 11.310838 -83.078135) (xy 11.367621 -82.994509) (xy 11.430869 -82.91566) (xy 11.500181 -82.842084)
			(xy 11.57512 -82.774248) (xy 11.655212 -82.71258) (xy 11.73995 -82.657471) (xy 11.828799 -82.609268)
			(xy 11.921196 -82.568277) (xy 12.016559 -82.534756) (xy 12.114283 -82.508918) (xy 12.21375 -82.490925)
			(xy 12.314333 -82.480893) (xy 12.415396 -82.478883) (xy 12.516298 -82.484909) (xy 12.616402 -82.498932)
			(xy 12.715076 -82.520865) (xy 12.811696 -82.550568) (xy 12.90565 -82.587854) (xy 12.996345 -82.632486)
			(xy 13.083207 -82.684183) (xy 13.165687 -82.742618) (xy 13.243264 -82.807421) (xy 13.315446 -82.878183)
			(xy 13.381779 -82.954456) (xy 13.441842 -83.035758) (xy 13.495256 -83.121575) (xy 13.541683 -83.211364)
			(xy 13.580829 -83.304558) (xy 13.612447 -83.400568) (xy 13.636337 -83.498786) (xy 13.652348 -83.598592)
			(xy 13.660379 -83.699355) (xy 13.660882 -83.749896) (xy 13.660379 -83.800437) (xy 13.652348 -83.9012)
			(xy 13.636337 -84.001006) (xy 13.612447 -84.099224) (xy 13.580829 -84.195234) (xy 13.541683 -84.288428)
			(xy 13.495256 -84.378217) (xy 13.441842 -84.464034) (xy 13.381779 -84.545336) (xy 13.315446 -84.621609)
			(xy 13.243264 -84.692371) (xy 13.165687 -84.757174) (xy 13.083207 -84.815609) (xy 12.996345 -84.867306)
			(xy 12.90565 -84.911938) (xy 12.811696 -84.949224) (xy 12.715076 -84.978927) (xy 12.616402 -85.00086)
			(xy 12.516298 -85.014883) (xy 12.415396 -85.020909) (xy 12.314333 -85.018899) (xy 12.21375 -85.008867)
			(xy 12.114283 -84.990874) (xy 12.016559 -84.965036) (xy 11.921196 -84.931515) (xy 11.828799 -84.890524)
			(xy 11.73995 -84.842321) (xy 11.655212 -84.787212) (xy 11.57512 -84.725544) (xy 11.500181 -84.657708)
			(xy 11.430869 -84.584132) (xy 11.367621 -84.505283) (xy 11.310838 -84.421657) (xy 11.260878 -84.333784)
			(xy 11.218058 -84.24222) (xy 11.182647 -84.147543) (xy 11.154871 -84.050352) (xy 11.134905 -83.951262)
			(xy 11.122874 -83.850898) (xy 11.118856 -83.749896) (xy 0.509016 -83.749896) (xy 0.509016 -87.559896)
			(xy 9.849612 -87.559896) (xy 9.850066 -87.509996) (xy 9.857896 -87.410503) (xy 9.873509 -87.311931)
			(xy 9.896807 -87.214889) (xy 9.927648 -87.119973) (xy 9.96584 -87.02777) (xy 10.011149 -86.938847)
			(xy 10.063296 -86.853754) (xy 10.121957 -86.773014) (xy 10.186773 -86.697126) (xy 10.257344 -86.626557)
			(xy 10.333233 -86.561743) (xy 10.413974 -86.503082) (xy 10.499068 -86.450938) (xy 10.587992 -86.40563)
			(xy 10.680196 -86.36744) (xy 10.775112 -86.336601) (xy 10.872155 -86.313304) (xy 10.970727 -86.297693)
			(xy 11.07022 -86.289865) (xy 11.12012 -86.289388) (xy 11.17137 -86.289896) (xy 11.273537 -86.298164)
			(xy 11.374705 -86.314636) (xy 11.474217 -86.339204) (xy 11.571427 -86.371709) (xy 11.665703 -86.411939)
			(xy 11.756431 -86.459633) (xy 11.843023 -86.514481) (xy 11.924914 -86.576126) (xy 12.001573 -86.644168)
			(xy 12.072502 -86.718164) (xy 12.13724 -86.797634) (xy 12.195365 -86.88206) (xy 12.2465 -86.970895)
			(xy 12.290312 -87.06356) (xy 12.326518 -87.159453) (xy 12.35488 -87.257951) (xy 12.375216 -87.358414)
			(xy 12.387393 -87.460189) (xy 12.389866 -87.511382) (xy 12.390707 -87.520861) (xy 12.398315 -87.538282)
			(xy 12.411745 -87.551735) (xy 12.429153 -87.559373) (xy 12.438634 -87.56015) (xy 12.489829 -87.562618)
			(xy 12.59161 -87.574781) (xy 12.692079 -87.595106) (xy 12.790584 -87.623459) (xy 12.886484 -87.659657)
			(xy 12.979156 -87.703465) (xy 13.067997 -87.754597) (xy 13.152429 -87.812721) (xy 13.231903 -87.877459)
			(xy 13.305903 -87.94839) (xy 13.373947 -88.025052) (xy 13.435592 -88.106949) (xy 13.490439 -88.193546)
			(xy 13.53813 -88.28428) (xy 13.578355 -88.378562) (xy 13.610852 -88.475779) (xy 13.635411 -88.575298)
			(xy 13.651871 -88.676472) (xy 13.660126 -88.778644) (xy 13.660628 -88.829896) (xy 13.660114 -88.879795)
			(xy 13.652285 -88.979284) (xy 13.636673 -89.077853) (xy 13.613377 -89.174893) (xy 13.582538 -89.269806)
			(xy 13.544348 -89.362006) (xy 13.499042 -89.450927) (xy 13.446898 -89.536018) (xy 13.38824 -89.616756)
			(xy 13.349598 -89.662) (xy 268.350492 -89.662) (xy 268.351075 -89.615604) (xy 268.36072 -89.523316)
			(xy 268.379916 -89.432532) (xy 268.408454 -89.344239) (xy 268.426692 -89.301574) (xy 268.430498 -89.291632)
			(xy 268.430498 -89.270368) (xy 268.426692 -89.260426) (xy 268.408447 -89.217764) (xy 268.379903 -89.129471)
			(xy 268.36071 -89.038686) (xy 268.351077 -88.946396) (xy 268.350492 -88.9) (xy 268.351075 -88.853604)
			(xy 268.36072 -88.761316) (xy 268.379916 -88.670532) (xy 268.408454 -88.582239) (xy 268.426692 -88.539574)
			(xy 268.430498 -88.529632) (xy 268.430498 -88.508368) (xy 268.426692 -88.498426) (xy 268.408447 -88.455764)
			(xy 268.379903 -88.367471) (xy 268.36071 -88.276686) (xy 268.351077 -88.184396) (xy 268.350492 -88.138)
			(xy 268.351075 -88.091604) (xy 268.36072 -87.999316) (xy 268.379916 -87.908532) (xy 268.408454 -87.820239)
			(xy 268.426692 -87.777574) (xy 268.430498 -87.767632) (xy 268.430498 -87.746368) (xy 268.426692 -87.736426)
			(xy 268.408447 -87.693764) (xy 268.379903 -87.605471) (xy 268.36071 -87.514686) (xy 268.351077 -87.422396)
			(xy 268.350492 -87.376) (xy 268.351075 -87.329604) (xy 268.36072 -87.237316) (xy 268.379916 -87.146532)
			(xy 268.408454 -87.058239) (xy 268.426692 -87.015574) (xy 268.430498 -87.005632) (xy 268.430498 -86.984368)
			(xy 268.426692 -86.974426) (xy 268.408447 -86.931764) (xy 268.379903 -86.843471) (xy 268.36071 -86.752686)
			(xy 268.351077 -86.660396) (xy 268.350492 -86.614) (xy 268.351075 -86.567604) (xy 268.36072 -86.475316)
			(xy 268.379916 -86.384532) (xy 268.408454 -86.296239) (xy 268.426692 -86.253574) (xy 268.430498 -86.243632)
			(xy 268.430498 -86.222368) (xy 268.426692 -86.212426) (xy 268.408447 -86.169764) (xy 268.379903 -86.081471)
			(xy 268.36071 -85.990686) (xy 268.351077 -85.898396) (xy 268.350492 -85.852) (xy 268.350967 -85.810898)
			(xy 268.358552 -85.729043) (xy 268.373657 -85.648238) (xy 268.396153 -85.569171) (xy 268.425849 -85.492517)
			(xy 268.462491 -85.41893) (xy 268.505766 -85.349038) (xy 268.555306 -85.283437) (xy 268.610687 -85.222687)
			(xy 268.671437 -85.167306) (xy 268.737038 -85.117766) (xy 268.80693 -85.074491) (xy 268.880517 -85.037849)
			(xy 268.957171 -85.008153) (xy 269.036238 -84.985657) (xy 269.117043 -84.970552) (xy 269.198898 -84.962967)
			(xy 269.24 -84.962492) (xy 269.286396 -84.963075) (xy 269.378684 -84.97272) (xy 269.469468 -84.991916)
			(xy 269.557761 -85.020454) (xy 269.600426 -85.038692) (xy 269.610368 -85.042498) (xy 269.631632 -85.042498)
			(xy 269.641574 -85.038692) (xy 269.684236 -85.020447) (xy 269.772529 -84.991903) (xy 269.863314 -84.97271)
			(xy 269.955604 -84.963077) (xy 270.002 -84.962492) (xy 270.048396 -84.963075) (xy 270.140684 -84.97272)
			(xy 270.231468 -84.991916) (xy 270.319761 -85.020454) (xy 270.362426 -85.038692) (xy 270.372368 -85.042498)
			(xy 270.393632 -85.042498) (xy 270.403574 -85.038692) (xy 270.446236 -85.020447) (xy 270.534529 -84.991903)
			(xy 270.625314 -84.97271) (xy 270.717604 -84.963077) (xy 270.764 -84.962492) (xy 270.810396 -84.963075)
			(xy 270.902684 -84.97272) (xy 270.993468 -84.991916) (xy 271.081761 -85.020454) (xy 271.124426 -85.038692)
			(xy 271.134368 -85.042498) (xy 271.155632 -85.042498) (xy 271.165574 -85.038692) (xy 271.208236 -85.020447)
			(xy 271.296529 -84.991903) (xy 271.387314 -84.97271) (xy 271.479604 -84.963077) (xy 271.526 -84.962492)
			(xy 271.572396 -84.963075) (xy 271.664684 -84.97272) (xy 271.755468 -84.991916) (xy 271.843761 -85.020454)
			(xy 271.886426 -85.038692) (xy 271.896368 -85.042498) (xy 271.917632 -85.042498) (xy 271.927574 -85.038692)
			(xy 271.970236 -85.020447) (xy 272.058529 -84.991903) (xy 272.149314 -84.97271) (xy 272.241604 -84.963077)
			(xy 272.288 -84.962492) (xy 272.329102 -84.962967) (xy 272.410957 -84.970552) (xy 272.491762 -84.985657)
			(xy 272.570829 -85.008153) (xy 272.647483 -85.037849) (xy 272.72107 -85.074491) (xy 272.790962 -85.117766)
			(xy 272.856563 -85.167306) (xy 272.917313 -85.222687) (xy 272.972694 -85.283437) (xy 273.022234 -85.349038)
			(xy 273.065509 -85.41893) (xy 273.102151 -85.492517) (xy 273.131847 -85.569171) (xy 273.154343 -85.648238)
			(xy 273.169448 -85.729043) (xy 273.177033 -85.810898) (xy 273.177508 -85.852) (xy 273.176925 -85.898396)
			(xy 273.16728 -85.990684) (xy 273.148084 -86.081468) (xy 273.119546 -86.169761) (xy 273.101308 -86.212426)
			(xy 273.097502 -86.222368) (xy 273.097502 -86.243632) (xy 273.101308 -86.253574) (xy 273.119553 -86.296236)
			(xy 273.148097 -86.384529) (xy 273.16729 -86.475314) (xy 273.176923 -86.567604) (xy 273.177508 -86.614)
			(xy 273.177033 -86.655102) (xy 273.169448 -86.736957) (xy 273.154343 -86.817762) (xy 273.131847 -86.896829)
			(xy 273.102151 -86.973483) (xy 273.065509 -87.04707) (xy 273.022234 -87.116962) (xy 272.972694 -87.182563)
			(xy 272.917313 -87.243313) (xy 272.856563 -87.298694) (xy 272.790962 -87.348234) (xy 272.72107 -87.391509)
			(xy 272.647483 -87.428151) (xy 272.570829 -87.457847) (xy 272.491762 -87.480343) (xy 272.410957 -87.495448)
			(xy 272.329102 -87.503033) (xy 272.288 -87.503508) (xy 272.241604 -87.502925) (xy 272.149316 -87.49328)
			(xy 272.058532 -87.474084) (xy 271.970239 -87.445546) (xy 271.927574 -87.427308) (xy 271.917632 -87.423502)
			(xy 271.896368 -87.423502) (xy 271.886426 -87.427308) (xy 271.853507 -87.441537) (xy 271.785822 -87.465257)
			(xy 271.716442 -87.483437) (xy 271.681194 -87.490046) (xy 271.67107 -87.492344) (xy 271.653749 -87.503749)
			(xy 271.642344 -87.52107) (xy 271.640046 -87.531194) (xy 271.633416 -87.566437) (xy 271.61522 -87.63581)
			(xy 271.591513 -87.703498) (xy 271.577308 -87.736426) (xy 271.573502 -87.746368) (xy 271.573502 -87.767632)
			(xy 271.577308 -87.777574) (xy 271.591537 -87.810493) (xy 271.615257 -87.878178) (xy 271.633437 -87.947558)
			(xy 271.640046 -87.982806) (xy 271.642344 -87.99293) (xy 271.653749 -88.010251) (xy 271.67107 -88.021656)
			(xy 271.681194 -88.023954) (xy 271.716437 -88.030584) (xy 271.78581 -88.04878) (xy 271.853498 -88.072487)
			(xy 271.886426 -88.086692) (xy 271.896368 -88.090498) (xy 271.917632 -88.090498) (xy 271.927574 -88.086692)
			(xy 271.970236 -88.068447) (xy 272.058529 -88.039903) (xy 272.149314 -88.02071) (xy 272.241604 -88.011077)
			(xy 272.288 -88.010492) (xy 272.329102 -88.010967) (xy 272.410957 -88.018552) (xy 272.491762 -88.033657)
			(xy 272.570829 -88.056153) (xy 272.647483 -88.085849) (xy 272.72107 -88.122491) (xy 272.790962 -88.165766)
			(xy 272.856563 -88.215306) (xy 272.917313 -88.270687) (xy 272.972694 -88.331437) (xy 273.022234 -88.397038)
			(xy 273.065509 -88.46693) (xy 273.102151 -88.540517) (xy 273.131847 -88.617171) (xy 273.154343 -88.696238)
			(xy 273.169448 -88.777043) (xy 273.177033 -88.858898) (xy 273.177508 -88.9) (xy 273.176925 -88.946396)
			(xy 273.16728 -89.038684) (xy 273.148084 -89.129468) (xy 273.119546 -89.217761) (xy 273.101308 -89.260426)
			(xy 273.097502 -89.270368) (xy 273.097502 -89.291632) (xy 273.101308 -89.301574) (xy 273.119553 -89.344236)
			(xy 273.148097 -89.432529) (xy 273.16729 -89.523314) (xy 273.176923 -89.615604) (xy 273.177508 -89.662)
			(xy 273.177033 -89.703102) (xy 273.169448 -89.784957) (xy 273.154343 -89.865762) (xy 273.131847 -89.944829)
			(xy 273.102151 -90.021483) (xy 273.065509 -90.09507) (xy 273.022234 -90.164962) (xy 272.972694 -90.230563)
			(xy 272.917313 -90.291313) (xy 272.856563 -90.346694) (xy 272.790962 -90.396234) (xy 272.72107 -90.439509)
			(xy 272.667144 -90.466361) (xy 275.081742 -90.466361) (xy 275.081742 -90.381639) (xy 275.089795 -90.297302)
			(xy 275.105829 -90.214112) (xy 275.129697 -90.132822) (xy 275.161185 -90.05417) (xy 275.200007 -89.978867)
			(xy 275.24581 -89.907595) (xy 275.298181 -89.840999) (xy 275.356646 -89.779684) (xy 275.420674 -89.724203)
			(xy 275.489686 -89.67506) (xy 275.563056 -89.6327) (xy 275.640121 -89.597505) (xy 275.720183 -89.569796)
			(xy 275.802516 -89.549822) (xy 275.886375 -89.537765) (xy 275.971 -89.533734) (xy 276.055625 -89.537765)
			(xy 276.139484 -89.549822) (xy 276.221817 -89.569796) (xy 276.301879 -89.597505) (xy 276.378944 -89.6327)
			(xy 276.452314 -89.67506) (xy 276.521326 -89.724203) (xy 276.585354 -89.779684) (xy 276.643819 -89.840999)
			(xy 276.69619 -89.907595) (xy 276.741993 -89.978867) (xy 276.780815 -90.05417) (xy 276.812303 -90.132822)
			(xy 276.836171 -90.214112) (xy 276.852205 -90.297302) (xy 276.860258 -90.381639) (xy 276.860762 -90.424)
			(xy 276.860258 -90.466361) (xy 276.852205 -90.550698) (xy 276.836171 -90.633888) (xy 276.812303 -90.715178)
			(xy 276.780815 -90.79383) (xy 276.741993 -90.869133) (xy 276.69619 -90.940405) (xy 276.643819 -91.007001)
			(xy 276.585354 -91.068316) (xy 276.521326 -91.123797) (xy 276.452314 -91.17294) (xy 276.378944 -91.2153)
			(xy 276.301879 -91.250495) (xy 276.221817 -91.278204) (xy 276.139484 -91.298178) (xy 276.055625 -91.310235)
			(xy 275.971 -91.314267) (xy 275.886375 -91.310235) (xy 275.802516 -91.298178) (xy 275.720183 -91.278204)
			(xy 275.640121 -91.250495) (xy 275.563056 -91.2153) (xy 275.489686 -91.17294) (xy 275.420674 -91.123797)
			(xy 275.356646 -91.068316) (xy 275.298181 -91.007001) (xy 275.24581 -90.940405) (xy 275.200007 -90.869133)
			(xy 275.161185 -90.79383) (xy 275.129697 -90.715178) (xy 275.105829 -90.633888) (xy 275.089795 -90.550698)
			(xy 275.081742 -90.466361) (xy 272.667144 -90.466361) (xy 272.647483 -90.476151) (xy 272.570829 -90.505847)
			(xy 272.491762 -90.528343) (xy 272.410957 -90.543448) (xy 272.329102 -90.551033) (xy 272.288 -90.551508)
			(xy 272.241604 -90.550925) (xy 272.149316 -90.54128) (xy 272.058532 -90.522084) (xy 271.970239 -90.493546)
			(xy 271.927574 -90.475308) (xy 271.917632 -90.471502) (xy 271.896368 -90.471502) (xy 271.886426 -90.475308)
			(xy 271.843764 -90.493553) (xy 271.755471 -90.522097) (xy 271.664686 -90.54129) (xy 271.572396 -90.550923)
			(xy 271.526 -90.551508) (xy 271.479604 -90.550925) (xy 271.387316 -90.54128) (xy 271.296532 -90.522084)
			(xy 271.208239 -90.493546) (xy 271.165574 -90.475308) (xy 271.155632 -90.471502) (xy 271.134368 -90.471502)
			(xy 271.124426 -90.475308) (xy 271.081764 -90.493553) (xy 270.993471 -90.522097) (xy 270.902686 -90.54129)
			(xy 270.810396 -90.550923) (xy 270.764 -90.551508) (xy 270.717604 -90.550925) (xy 270.625316 -90.54128)
			(xy 270.534532 -90.522084) (xy 270.446239 -90.493546) (xy 270.403574 -90.475308) (xy 270.393632 -90.471502)
			(xy 270.372368 -90.471502) (xy 270.362426 -90.475308) (xy 270.340242 -90.484956) (xy 270.295004 -90.502108)
			(xy 270.272002 -90.509598) (xy 270.258794 -90.513916) (xy 270.24076 -90.533982) (xy 270.21663 -90.64752)
			(xy 270.225266 -90.673428) (xy 270.23568 -90.682572) (xy 270.266746 -90.710632) (xy 270.323976 -90.771738)
			(xy 270.375209 -90.837953) (xy 270.419991 -90.90869) (xy 270.457926 -90.983323) (xy 270.488678 -91.061192)
			(xy 270.511974 -91.141606) (xy 270.527609 -91.223854) (xy 270.535444 -91.307207) (xy 270.535908 -91.349068)
			(xy 270.535404 -91.391416) (xy 270.527353 -91.47573) (xy 270.511324 -91.558896) (xy 270.487463 -91.640163)
			(xy 270.455984 -91.718793) (xy 270.417173 -91.794074) (xy 270.371383 -91.865326) (xy 270.319027 -91.931902)
			(xy 270.260579 -91.9932) (xy 270.196569 -92.048665) (xy 270.127577 -92.097794) (xy 270.054227 -92.140143)
			(xy 269.977184 -92.175327) (xy 269.897145 -92.203029) (xy 269.814836 -92.222997) (xy 269.731001 -92.23505)
			(xy 269.6464 -92.239081) (xy 269.561799 -92.23505) (xy 269.477964 -92.222997) (xy 269.395655 -92.203029)
			(xy 269.315616 -92.175327) (xy 269.238573 -92.140143) (xy 269.165223 -92.097794) (xy 269.096231 -92.048665)
			(xy 269.032221 -91.9932) (xy 268.973773 -91.931902) (xy 268.921417 -91.865326) (xy 268.875627 -91.794074)
			(xy 268.836816 -91.718793) (xy 268.805337 -91.640163) (xy 268.781476 -91.558896) (xy 268.765447 -91.47573)
			(xy 268.757396 -91.391416) (xy 268.756892 -91.349068) (xy 268.757344 -91.308052) (xy 268.764906 -91.226369)
			(xy 268.779953 -91.145729) (xy 268.802357 -91.066816) (xy 268.831929 -90.990299) (xy 268.868417 -90.916829)
			(xy 268.911512 -90.847029) (xy 268.960847 -90.781491) (xy 269.016005 -90.720771) (xy 269.045944 -90.692732)
			(xy 269.056104 -90.683334) (xy 269.064232 -90.656918) (xy 269.0368 -90.54338) (xy 269.01775 -90.523568)
			(xy 269.004288 -90.519758) (xy 268.964497 -90.508355) (xy 268.88706 -90.47909) (xy 268.812678 -90.442758)
			(xy 268.741992 -90.399673) (xy 268.675615 -90.350208) (xy 268.61412 -90.29479) (xy 268.55804 -90.233898)
			(xy 268.507859 -90.16806) (xy 268.464012 -90.097845) (xy 268.426877 -90.02386) (xy 268.396777 -89.946745)
			(xy 268.373971 -89.867167) (xy 268.358656 -89.785814) (xy 268.350965 -89.703391) (xy 268.350492 -89.662)
			(xy 13.349598 -89.662) (xy 13.323427 -89.692643) (xy 13.252861 -89.763211) (xy 13.176975 -89.828025)
			(xy 13.096238 -89.886685) (xy 13.011148 -89.93883) (xy 12.922228 -89.984138) (xy 12.830028 -90.02233)
			(xy 12.735116 -90.05317) (xy 12.638076 -90.076469) (xy 12.539508 -90.092082) (xy 12.440019 -90.099913)
			(xy 12.39012 -90.100404) (xy 12.33887 -90.099894) (xy 12.236704 -90.091626) (xy 12.135535 -90.075154)
			(xy 12.036023 -90.050586) (xy 11.938813 -90.018081) (xy 11.844537 -89.977851) (xy 11.753809 -89.930157)
			(xy 11.667218 -89.875309) (xy 11.585327 -89.813664) (xy 11.508667 -89.745623) (xy 11.437738 -89.671626)
			(xy 11.373001 -89.592157) (xy 11.314876 -89.507731) (xy 11.263741 -89.418896) (xy 11.219928 -89.326232)
			(xy 11.183723 -89.230338) (xy 11.15536 -89.13184) (xy 11.135024 -89.031377) (xy 11.122847 -88.929603)
			(xy 11.120374 -88.87841) (xy 11.119594 -88.868921) (xy 11.111973 -88.851491) (xy 11.098523 -88.838037)
			(xy 11.081095 -88.830409) (xy 11.071606 -88.829642) (xy 11.020411 -88.827172) (xy 10.918631 -88.815009)
			(xy 10.818161 -88.794684) (xy 10.719656 -88.766331) (xy 10.623756 -88.730133) (xy 10.531084 -88.686326)
			(xy 10.442244 -88.635194) (xy 10.357812 -88.57707) (xy 10.278337 -88.512332) (xy 10.204338 -88.441401)
			(xy 10.136294 -88.364738) (xy 10.074648 -88.282842) (xy 10.019802 -88.196246) (xy 9.972111 -88.105511)
			(xy 9.931886 -88.011229) (xy 9.899388 -87.914013) (xy 9.87483 -87.814494) (xy 9.858369 -87.71332)
			(xy 9.850114 -87.611148) (xy 9.849612 -87.559896) (xy 0.509016 -87.559896) (xy 0.509016 -93.399864)
			(xy 3.446023 -93.399864) (xy 3.450044 -93.286002) (xy 3.462086 -93.172708) (xy 3.482091 -93.060546)
			(xy 3.509957 -92.950074) (xy 3.545546 -92.841842) (xy 3.588681 -92.736391) (xy 3.639147 -92.634245)
			(xy 3.696693 -92.535914) (xy 3.761032 -92.441886) (xy 3.831843 -92.352631) (xy 3.908773 -92.268594)
			(xy 3.99144 -92.190192) (xy 4.079431 -92.117817) (xy 4.172308 -92.051829) (xy 4.269609 -91.992557)
			(xy 4.370848 -91.940296) (xy 4.475522 -91.895306) (xy 4.583108 -91.857812) (xy 4.693071 -91.828001)
			(xy 4.804864 -91.80602) (xy 4.917928 -91.79198) (xy 5.0317 -91.78595) (xy 5.145615 -91.787961) (xy 5.259104 -91.798002)
			(xy 5.371603 -91.816024) (xy 5.482549 -91.841936) (xy 5.591392 -91.87561) (xy 5.697588 -91.916877)
			(xy 5.800608 -91.965533) (xy 5.89994 -92.021334) (xy 5.995089 -92.084003) (xy 6.085579 -92.153228)
			(xy 6.170961 -92.228663) (xy 6.25081 -92.309934) (xy 6.324727 -92.396634) (xy 6.392343 -92.488332)
			(xy 6.453324 -92.584571) (xy 6.507363 -92.684873) (xy 6.554193 -92.788736) (xy 6.582153 -92.864629)
			(xy 270.30832 -92.864629) (xy 270.30832 -92.779907) (xy 270.316373 -92.69557) (xy 270.332407 -92.61238)
			(xy 270.356275 -92.53109) (xy 270.387763 -92.452438) (xy 270.426585 -92.377135) (xy 270.472388 -92.305863)
			(xy 270.524759 -92.239267) (xy 270.583224 -92.177952) (xy 270.647252 -92.122471) (xy 270.716264 -92.073328)
			(xy 270.789634 -92.030968) (xy 270.866699 -91.995773) (xy 270.946761 -91.968064) (xy 271.029094 -91.94809)
			(xy 271.112953 -91.936033) (xy 271.197578 -91.932002) (xy 271.282203 -91.936033) (xy 271.366062 -91.94809)
			(xy 271.448395 -91.968064) (xy 271.528457 -91.995773) (xy 271.605522 -92.030968) (xy 271.678892 -92.073328)
			(xy 271.747904 -92.122471) (xy 271.811932 -92.177952) (xy 271.870397 -92.239267) (xy 271.922768 -92.305863)
			(xy 271.968571 -92.377135) (xy 272.007393 -92.452438) (xy 272.038881 -92.53109) (xy 272.062749 -92.61238)
			(xy 272.078783 -92.69557) (xy 272.086836 -92.779907) (xy 272.08734 -92.822268) (xy 272.086836 -92.864629)
			(xy 272.078783 -92.948966) (xy 272.062749 -93.032156) (xy 272.038881 -93.113446) (xy 272.007393 -93.192098)
			(xy 271.968571 -93.267401) (xy 271.922768 -93.338673) (xy 271.870397 -93.405269) (xy 271.811932 -93.466584)
			(xy 271.747904 -93.522065) (xy 271.678892 -93.571208) (xy 271.605522 -93.613568) (xy 271.528457 -93.648763)
			(xy 271.448395 -93.676472) (xy 271.366062 -93.696446) (xy 271.282203 -93.708503) (xy 271.197578 -93.712535)
			(xy 271.112953 -93.708503) (xy 271.029094 -93.696446) (xy 270.946761 -93.676472) (xy 270.866699 -93.648763)
			(xy 270.789634 -93.613568) (xy 270.716264 -93.571208) (xy 270.647252 -93.522065) (xy 270.583224 -93.466584)
			(xy 270.524759 -93.405269) (xy 270.472388 -93.338673) (xy 270.426585 -93.267401) (xy 270.387763 -93.192098)
			(xy 270.356275 -93.113446) (xy 270.332407 -93.032156) (xy 270.316373 -92.948966) (xy 270.30832 -92.864629)
			(xy 6.582153 -92.864629) (xy 6.59358 -92.895644) (xy 6.625327 -93.005064) (xy 6.649277 -93.11645)
			(xy 6.665311 -93.229249) (xy 6.673347 -93.342898) (xy 6.67385 -93.399864) (xy 6.673347 -93.45683)
			(xy 6.665311 -93.570479) (xy 6.649277 -93.683278) (xy 6.625327 -93.794664) (xy 6.59358 -93.904084)
			(xy 6.554193 -94.010992) (xy 6.507363 -94.114855) (xy 6.453324 -94.215157) (xy 6.392343 -94.311396)
			(xy 6.324727 -94.403094) (xy 6.25081 -94.489794) (xy 6.170961 -94.571065) (xy 6.085579 -94.6465)
			(xy 5.995089 -94.715725) (xy 5.89994 -94.778394) (xy 5.800608 -94.834195) (xy 5.697588 -94.882851)
			(xy 5.591392 -94.924118) (xy 5.550527 -94.936761) (xy 273.536914 -94.936761) (xy 273.536914 -94.852039)
			(xy 273.544967 -94.767702) (xy 273.561001 -94.684512) (xy 273.584869 -94.603222) (xy 273.616357 -94.52457)
			(xy 273.655179 -94.449267) (xy 273.700982 -94.377995) (xy 273.753353 -94.311399) (xy 273.811818 -94.250084)
			(xy 273.875846 -94.194603) (xy 273.944858 -94.14546) (xy 274.018228 -94.1031) (xy 274.095293 -94.067905)
			(xy 274.175355 -94.040196) (xy 274.257688 -94.020222) (xy 274.341547 -94.008165) (xy 274.426172 -94.004134)
			(xy 274.510797 -94.008165) (xy 274.594656 -94.020222) (xy 274.676989 -94.040196) (xy 274.757051 -94.067905)
			(xy 274.834116 -94.1031) (xy 274.907486 -94.14546) (xy 274.976498 -94.194603) (xy 275.040526 -94.250084)
			(xy 275.098991 -94.311399) (xy 275.151362 -94.377995) (xy 275.197165 -94.449267) (xy 275.235987 -94.52457)
			(xy 275.267475 -94.603222) (xy 275.291343 -94.684512) (xy 275.307377 -94.767702) (xy 275.31543 -94.852039)
			(xy 275.315934 -94.8944) (xy 275.31543 -94.936761) (xy 275.307377 -95.021098) (xy 275.291343 -95.104288)
			(xy 275.267475 -95.185578) (xy 275.235987 -95.26423) (xy 275.197165 -95.339533) (xy 275.151362 -95.410805)
			(xy 275.098991 -95.477401) (xy 275.040526 -95.538716) (xy 274.976498 -95.594197) (xy 274.907486 -95.64334)
			(xy 274.834116 -95.6857) (xy 274.757051 -95.720895) (xy 274.676989 -95.748604) (xy 274.594656 -95.768578)
			(xy 274.510797 -95.780635) (xy 274.426172 -95.784667) (xy 274.341547 -95.780635) (xy 274.257688 -95.768578)
			(xy 274.175355 -95.748604) (xy 274.095293 -95.720895) (xy 274.018228 -95.6857) (xy 273.944858 -95.64334)
			(xy 273.875846 -95.594197) (xy 273.811818 -95.538716) (xy 273.753353 -95.477401) (xy 273.700982 -95.410805)
			(xy 273.655179 -95.339533) (xy 273.616357 -95.26423) (xy 273.584869 -95.185578) (xy 273.561001 -95.104288)
			(xy 273.544967 -95.021098) (xy 273.536914 -94.936761) (xy 5.550527 -94.936761) (xy 5.482549 -94.957792)
			(xy 5.371603 -94.983704) (xy 5.259104 -95.001726) (xy 5.145615 -95.011767) (xy 5.0317 -95.013778)
			(xy 4.917928 -95.007748) (xy 4.804864 -94.993708) (xy 4.693071 -94.971727) (xy 4.583108 -94.941916)
			(xy 4.475522 -94.904422) (xy 4.370848 -94.859432) (xy 4.269609 -94.807171) (xy 4.172308 -94.747899)
			(xy 4.079431 -94.681911) (xy 3.99144 -94.609536) (xy 3.908773 -94.531134) (xy 3.831843 -94.447097)
			(xy 3.761032 -94.357842) (xy 3.696693 -94.263814) (xy 3.639147 -94.165483) (xy 3.588681 -94.063337)
			(xy 3.545546 -93.957886) (xy 3.509957 -93.849654) (xy 3.482091 -93.739182) (xy 3.462086 -93.62702)
			(xy 3.450044 -93.513726) (xy 3.446023 -93.399864) (xy 0.509016 -93.399864) (xy 0.509016 -98.013)
			(xy 214.347099 -98.013) (xy 214.351129 -97.928402) (xy 214.363182 -97.844571) (xy 214.383149 -97.762265)
			(xy 214.410848 -97.682229) (xy 214.44603 -97.605189) (xy 214.488376 -97.531842) (xy 214.537502 -97.462852)
			(xy 214.592963 -97.398843) (xy 214.654257 -97.340397) (xy 214.720829 -97.288041) (xy 214.792077 -97.24225)
			(xy 214.867354 -97.203439) (xy 214.94598 -97.171959) (xy 215.027241 -97.148095) (xy 215.110404 -97.132064)
			(xy 215.194713 -97.124009) (xy 215.23706 -97.123504) (xy 215.283455 -97.1241) (xy 215.375743 -97.133741)
			(xy 215.466527 -97.152933) (xy 215.554821 -97.181468) (xy 215.597486 -97.199704) (xy 215.607428 -97.20351)
			(xy 215.628692 -97.20351) (xy 215.638634 -97.199704) (xy 215.681302 -97.181473) (xy 215.769592 -97.152925)
			(xy 215.860375 -97.133728) (xy 215.952664 -97.124091) (xy 215.99906 -97.123504) (xy 216.041067 -97.12399)
			(xy 216.124708 -97.131906) (xy 216.207231 -97.14767) (xy 216.2879 -97.171143) (xy 216.365997 -97.202116)
			(xy 216.440827 -97.240312) (xy 216.511723 -97.285392) (xy 216.578055 -97.336953) (xy 216.639231 -97.394538)
			(xy 216.667334 -97.425764) (xy 216.6747 -97.434146) (xy 216.694512 -97.443036) (xy 216.79281 -97.443036)
			(xy 216.812622 -97.434146) (xy 216.819988 -97.425764) (xy 216.848079 -97.394524) (xy 216.909243 -97.33692)
			(xy 216.975568 -97.285342) (xy 217.046463 -97.240252) (xy 217.121295 -97.202051) (xy 217.199398 -97.171081)
			(xy 217.280074 -97.147616) (xy 217.362604 -97.131868) (xy 217.446252 -97.123975) (xy 217.488262 -97.123504)
			(xy 217.534657 -97.124099) (xy 217.626945 -97.133741) (xy 217.717729 -97.152933) (xy 217.806023 -97.181468)
			(xy 217.848688 -97.199704) (xy 217.85863 -97.20351) (xy 217.879894 -97.20351) (xy 217.889836 -97.199704)
			(xy 217.932504 -97.181473) (xy 218.020794 -97.152925) (xy 218.111577 -97.133728) (xy 218.203866 -97.124091)
			(xy 218.250262 -97.123504) (xy 218.291199 -97.124004) (xy 218.372725 -97.13153) (xy 218.453216 -97.146514)
			(xy 218.531989 -97.168828) (xy 218.60838 -97.198285) (xy 218.681742 -97.234633) (xy 218.751455 -97.277567)
			(xy 218.81693 -97.326724) (xy 218.877611 -97.381687) (xy 218.932988 -97.441992) (xy 218.95816 -97.474278)
			(xy 218.965526 -97.48393) (xy 218.987116 -97.494344) (xy 219.093542 -97.492566) (xy 219.114878 -97.48139)
			(xy 219.12199 -97.471484) (xy 219.146898 -97.437102) (xy 219.202355 -97.372809) (xy 219.263686 -97.314092)
			(xy 219.330332 -97.261485) (xy 219.401687 -97.215468) (xy 219.477102 -97.176458) (xy 219.55589 -97.144811)
			(xy 219.637335 -97.120815) (xy 219.720696 -97.104688) (xy 219.805215 -97.096576) (xy 219.847668 -97.096072)
			(xy 219.894071 -97.096675) (xy 219.986369 -97.106372) (xy 220.077154 -97.125633) (xy 220.165439 -97.154247)
			(xy 220.208094 -97.172526) (xy 220.218036 -97.176332) (xy 220.2393 -97.176332) (xy 220.249242 -97.172526)
			(xy 220.291907 -97.154274) (xy 220.380194 -97.125678) (xy 220.470975 -97.106418) (xy 220.563267 -97.096703)
			(xy 220.609668 -97.096072) (xy 220.651684 -97.096525) (xy 220.73534 -97.104457) (xy 220.817875 -97.120244)
			(xy 220.898554 -97.143744) (xy 220.976656 -97.174749) (xy 221.051486 -97.212982) (xy 221.122376 -97.258102)
			(xy 221.188695 -97.309707) (xy 221.249851 -97.367337) (xy 221.277942 -97.398586) (xy 221.285308 -97.406968)
			(xy 221.30512 -97.415858) (xy 221.403418 -97.415858) (xy 221.42323 -97.406968) (xy 221.430596 -97.398586)
			(xy 221.458694 -97.367348) (xy 221.519864 -97.309741) (xy 221.586191 -97.258156) (xy 221.657084 -97.213051)
			(xy 221.731912 -97.174827) (xy 221.81001 -97.143825) (xy 221.890681 -97.120321) (xy 221.973209 -97.104524)
			(xy 222.056857 -97.096575) (xy 222.09887 -97.096072) (xy 222.145273 -97.096675) (xy 222.237571 -97.106372)
			(xy 222.328356 -97.125632) (xy 222.416641 -97.154247) (xy 222.459296 -97.172526) (xy 222.469238 -97.176332)
			(xy 222.490502 -97.176332) (xy 222.500444 -97.172526) (xy 222.543109 -97.154273) (xy 222.631395 -97.125678)
			(xy 222.722177 -97.106418) (xy 222.814469 -97.096703) (xy 222.86087 -97.096072) (xy 222.903898 -97.096585)
			(xy 222.989549 -97.104908) (xy 223.073998 -97.12146) (xy 223.156454 -97.146086) (xy 223.236148 -97.178557)
			(xy 223.312336 -97.218569) (xy 223.384305 -97.265748) (xy 223.451385 -97.319654) (xy 223.512948 -97.379783)
			(xy 223.568419 -97.445574) (xy 223.61728 -97.516413) (xy 223.638618 -97.55378) (xy 223.643347 -97.561498)
			(xy 223.657067 -97.573284) (xy 223.674025 -97.579573) (xy 223.683068 -97.579942) (xy 223.771714 -97.579942)
			(xy 223.78076 -97.579567) (xy 223.797731 -97.573298) (xy 223.811459 -97.561515) (xy 223.816164 -97.55378)
			(xy 223.837459 -97.516385) (xy 223.88631 -97.445532) (xy 223.941777 -97.379729) (xy 224.003339 -97.319589)
			(xy 224.070421 -97.265677) (xy 224.142397 -97.218495) (xy 224.218592 -97.178485) (xy 224.298296 -97.146021)
			(xy 224.380763 -97.121407) (xy 224.465221 -97.104872) (xy 224.550881 -97.096571) (xy 224.593912 -97.096072)
			(xy 224.640314 -97.096695) (xy 224.732612 -97.106386) (xy 224.823397 -97.125641) (xy 224.911682 -97.15425)
			(xy 224.954338 -97.172526) (xy 224.96428 -97.176332) (xy 224.985544 -97.176332) (xy 224.995486 -97.172526)
			(xy 225.038145 -97.154259) (xy 225.126434 -97.125668) (xy 225.217217 -97.106412) (xy 225.309511 -97.0967)
			(xy 225.355912 -97.096072) (xy 225.397927 -97.096565) (xy 225.481582 -97.104491) (xy 225.564116 -97.120273)
			(xy 225.644794 -97.143768) (xy 225.722896 -97.174768) (xy 225.797726 -97.212997) (xy 225.868618 -97.258112)
			(xy 225.934937 -97.309713) (xy 225.996095 -97.367339) (xy 226.024186 -97.398586) (xy 226.031552 -97.406968)
			(xy 226.051364 -97.415858) (xy 226.149662 -97.415858) (xy 226.169474 -97.406968) (xy 226.17684 -97.398586)
			(xy 226.204915 -97.367326) (xy 226.266088 -97.309721) (xy 226.332418 -97.258137) (xy 226.403314 -97.213033)
			(xy 226.478146 -97.174812) (xy 226.556246 -97.143813) (xy 226.63692 -97.120312) (xy 226.71945 -97.104518)
			(xy 226.8031 -97.096573) (xy 226.845114 -97.096072) (xy 226.891516 -97.096694) (xy 226.983814 -97.106386)
			(xy 227.074599 -97.125641) (xy 227.162884 -97.15425) (xy 227.20554 -97.172526) (xy 227.215482 -97.176332)
			(xy 227.236746 -97.176332) (xy 227.246688 -97.172526) (xy 227.289347 -97.154259) (xy 227.377636 -97.125667)
			(xy 227.468419 -97.106411) (xy 227.560713 -97.0967) (xy 227.607114 -97.096072) (xy 227.649476 -97.096509)
			(xy 227.733816 -97.104563) (xy 227.817008 -97.120598) (xy 227.898299 -97.144469) (xy 227.976953 -97.175958)
			(xy 228.052258 -97.214782) (xy 228.123532 -97.260588) (xy 228.190129 -97.312961) (xy 228.251445 -97.371427)
			(xy 228.306927 -97.435457) (xy 228.356071 -97.504471) (xy 228.398433 -97.577844) (xy 228.433628 -97.654912)
			(xy 228.461338 -97.734976) (xy 228.481312 -97.817311) (xy 228.493369 -97.901172) (xy 228.497401 -97.9858)
			(xy 228.496115 -98.0128) (xy 228.639776 -98.0128) (xy 228.643808 -97.928166) (xy 228.655866 -97.844299)
			(xy 228.675843 -97.761958) (xy 228.703556 -97.681889) (xy 228.738755 -97.604817) (xy 228.781121 -97.53144)
			(xy 228.830271 -97.462422) (xy 228.885758 -97.398389) (xy 228.947082 -97.339921) (xy 229.013685 -97.287547)
			(xy 229.084966 -97.241741) (xy 229.160278 -97.202918) (xy 229.238939 -97.171431) (xy 229.320238 -97.147563)
			(xy 229.403437 -97.131532) (xy 229.487783 -97.123482) (xy 229.530148 -97.122996) (xy 229.576551 -97.123604)
			(xy 229.668849 -97.133299) (xy 229.759634 -97.152558) (xy 229.847919 -97.181172) (xy 229.890574 -97.19945)
			(xy 229.900516 -97.203256) (xy 229.92178 -97.203256) (xy 229.931722 -97.19945) (xy 229.974377 -97.181173)
			(xy 230.062667 -97.152584) (xy 230.153452 -97.13333) (xy 230.245746 -97.123623) (xy 230.292148 -97.122996)
			(xy 230.334163 -97.123489) (xy 230.417817 -97.131418) (xy 230.50035 -97.147202) (xy 230.581028 -97.170698)
			(xy 230.659129 -97.201699) (xy 230.733959 -97.239927) (xy 230.80485 -97.285041) (xy 230.871171 -97.336641)
			(xy 230.93233 -97.394264) (xy 230.960422 -97.42551) (xy 230.967788 -97.433892) (xy 230.9876 -97.442782)
			(xy 231.085898 -97.442782) (xy 231.10571 -97.433892) (xy 231.113076 -97.42551) (xy 231.14119 -97.394286)
			(xy 231.202357 -97.336679) (xy 231.268682 -97.285092) (xy 231.339573 -97.239985) (xy 231.414399 -97.201759)
			(xy 231.492495 -97.170756) (xy 231.573164 -97.14725) (xy 231.65569 -97.131451) (xy 231.739338 -97.123499)
			(xy 231.78135 -97.122996) (xy 231.827753 -97.123604) (xy 231.920051 -97.133299) (xy 232.010836 -97.152558)
			(xy 232.099121 -97.181171) (xy 232.141776 -97.19945) (xy 232.151718 -97.203256) (xy 232.172982 -97.203256)
			(xy 232.182924 -97.19945) (xy 232.225592 -97.181205) (xy 232.313877 -97.152607) (xy 232.404658 -97.133345)
			(xy 232.49695 -97.123628) (xy 232.54335 -97.122996) (xy 232.586931 -97.123531) (xy 232.673673 -97.132067)
			(xy 232.759165 -97.149043) (xy 232.842588 -97.174296) (xy 232.923142 -97.207584) (xy 233.000056 -97.248588)
			(xy 233.072592 -97.296916) (xy 233.140056 -97.352103) (xy 233.201801 -97.413622) (xy 233.257236 -97.480883)
			(xy 233.30583 -97.553242) (xy 233.32694 -97.591372) (xy 233.333798 -97.604072) (xy 233.357928 -97.618296)
			(xy 233.477054 -97.616518) (xy 233.50093 -97.601532) (xy 233.50728 -97.588578) (xy 233.526 -97.552008)
			(xy 233.569301 -97.482183) (xy 233.618856 -97.416648) (xy 233.674243 -97.355962) (xy 233.734989 -97.300641)
			(xy 233.800577 -97.251157) (xy 233.870449 -97.207932) (xy 233.944009 -97.171333) (xy 234.02063 -97.141673)
			(xy 234.099659 -97.119205) (xy 234.180424 -97.104119) (xy 234.262235 -97.096545) (xy 234.303316 -97.096072)
			(xy 234.349718 -97.096694) (xy 234.442016 -97.106385) (xy 234.532801 -97.12564) (xy 234.621086 -97.15425)
			(xy 234.663742 -97.172526) (xy 234.673684 -97.176332) (xy 234.694948 -97.176332) (xy 234.70489 -97.172526)
			(xy 234.747548 -97.154258) (xy 234.835837 -97.125667) (xy 234.926621 -97.106411) (xy 235.018915 -97.0967)
			(xy 235.065316 -97.096072) (xy 235.107331 -97.096562) (xy 235.190986 -97.104489) (xy 235.27352 -97.120271)
			(xy 235.354198 -97.143767) (xy 235.4323 -97.174767) (xy 235.507131 -97.212996) (xy 235.578022 -97.258112)
			(xy 235.644341 -97.309713) (xy 235.705499 -97.367339) (xy 235.73359 -97.398586) (xy 235.740956 -97.406968)
			(xy 235.760768 -97.415858) (xy 235.859066 -97.415858) (xy 235.878878 -97.406968) (xy 235.886244 -97.398586)
			(xy 235.914369 -97.367373) (xy 235.975536 -97.309766) (xy 236.041859 -97.258179) (xy 236.112748 -97.213071)
			(xy 236.187573 -97.174845) (xy 236.265667 -97.14384) (xy 236.346335 -97.120332) (xy 236.42886 -97.104531)
			(xy 236.512506 -97.096577) (xy 236.554518 -97.096072) (xy 236.60092 -97.096693) (xy 236.693218 -97.106385)
			(xy 236.784003 -97.12564) (xy 236.872288 -97.154249) (xy 236.914944 -97.172526) (xy 236.924886 -97.176332)
			(xy 236.94615 -97.176332) (xy 236.956092 -97.172526) (xy 236.99875 -97.154257) (xy 237.087039 -97.125666)
			(xy 237.177823 -97.106411) (xy 237.270117 -97.0967) (xy 237.316518 -97.096072) (xy 237.357615 -97.096505)
			(xy 237.439458 -97.104088) (xy 237.520253 -97.119186) (xy 237.599312 -97.141671) (xy 237.675959 -97.171353)
			(xy 237.749543 -97.207976) (xy 237.819435 -97.251231) (xy 237.88504 -97.300747) (xy 237.945798 -97.356102)
			(xy 238.001192 -97.416825) (xy 238.05075 -97.482399) (xy 238.094048 -97.552263) (xy 238.112808 -97.588832)
			(xy 238.119158 -97.601786) (xy 238.143034 -97.616772) (xy 238.261906 -97.61855) (xy 238.28629 -97.604326)
			(xy 238.293148 -97.591626) (xy 238.314222 -97.553465) (xy 238.362786 -97.481062) (xy 238.4182 -97.413758)
			(xy 238.479934 -97.352199) (xy 238.547395 -97.296976) (xy 238.619936 -97.248619) (xy 238.69686 -97.207592)
			(xy 238.77743 -97.174288) (xy 238.860871 -97.149028) (xy 238.946384 -97.132052) (xy 239.033147 -97.123526)
			(xy 239.076738 -97.122996) (xy 239.123141 -97.123608) (xy 239.215438 -97.133302) (xy 239.306224 -97.15256)
			(xy 239.394509 -97.181172) (xy 239.437164 -97.19945) (xy 239.447106 -97.203256) (xy 239.46837 -97.203256)
			(xy 239.478312 -97.19945) (xy 239.520968 -97.181176) (xy 239.609258 -97.152586) (xy 239.700042 -97.133332)
			(xy 239.792337 -97.123623) (xy 239.838738 -97.122996) (xy 239.880752 -97.123496) (xy 239.964406 -97.131425)
			(xy 240.04694 -97.147207) (xy 240.127617 -97.170703) (xy 240.205719 -97.201702) (xy 240.280549 -97.239929)
			(xy 240.35144 -97.285043) (xy 240.417761 -97.336642) (xy 240.47892 -97.394265) (xy 240.507012 -97.42551)
			(xy 240.514378 -97.433892) (xy 240.53419 -97.442782) (xy 240.632488 -97.442782) (xy 240.6523 -97.433892)
			(xy 240.659666 -97.42551) (xy 240.687785 -97.394291) (xy 240.748952 -97.336683) (xy 240.815276 -97.285096)
			(xy 240.886166 -97.239989) (xy 240.960991 -97.201763) (xy 241.039086 -97.170759) (xy 241.119755 -97.147252)
			(xy 241.202281 -97.131452) (xy 241.285928 -97.1235) (xy 241.32794 -97.122996) (xy 241.374343 -97.123607)
			(xy 241.46664 -97.133301) (xy 241.557426 -97.15256) (xy 241.645711 -97.181172) (xy 241.688366 -97.19945)
			(xy 241.698308 -97.203256) (xy 241.719572 -97.203256) (xy 241.729514 -97.19945) (xy 241.77217 -97.181176)
			(xy 241.86046 -97.152585) (xy 241.951244 -97.133332) (xy 242.043539 -97.123623) (xy 242.08994 -97.122996)
			(xy 242.132297 -97.123586) (xy 242.216628 -97.131642) (xy 242.299811 -97.147678) (xy 242.381094 -97.171547)
			(xy 242.459739 -97.203035) (xy 242.535035 -97.241856) (xy 242.606301 -97.287659) (xy 242.67289 -97.340028)
			(xy 242.734199 -97.398489) (xy 242.789674 -97.462513) (xy 242.838812 -97.531521) (xy 242.881169 -97.604886)
			(xy 242.916359 -97.681946) (xy 242.944066 -97.762002) (xy 242.964038 -97.844329) (xy 242.976094 -97.928181)
			(xy 242.980125 -98.0128) (xy 242.976094 -98.097419) (xy 242.964038 -98.181271) (xy 242.944066 -98.263598)
			(xy 242.916359 -98.343654) (xy 242.881169 -98.420714) (xy 242.838812 -98.494079) (xy 242.789674 -98.563087)
			(xy 242.734199 -98.627111) (xy 242.67289 -98.685572) (xy 242.606301 -98.737941) (xy 242.535035 -98.783744)
			(xy 242.459739 -98.822565) (xy 242.381094 -98.854053) (xy 242.299811 -98.877922) (xy 242.216628 -98.893958)
			(xy 242.132297 -98.902014) (xy 242.08994 -98.90252) (xy 242.043537 -98.901915) (xy 241.951239 -98.892218)
			(xy 241.860454 -98.872958) (xy 241.772169 -98.844345) (xy 241.729514 -98.826066) (xy 241.719572 -98.82226)
			(xy 241.698308 -98.82226) (xy 241.688366 -98.826066) (xy 241.6457 -98.844315) (xy 241.557414 -98.872912)
			(xy 241.466632 -98.892172) (xy 241.374341 -98.901889) (xy 241.32794 -98.90252) (xy 241.285924 -98.902064)
			(xy 241.202268 -98.894132) (xy 241.119733 -98.878347) (xy 241.039054 -98.854846) (xy 240.960952 -98.823842)
			(xy 240.886122 -98.785609) (xy 240.815232 -98.740489) (xy 240.748913 -98.688884) (xy 240.687757 -98.631255)
			(xy 240.659666 -98.600006) (xy 240.6523 -98.591624) (xy 240.632488 -98.582734) (xy 240.53419 -98.582734)
			(xy 240.514378 -98.591624) (xy 240.507012 -98.600006) (xy 240.478908 -98.631239) (xy 240.417739 -98.688846)
			(xy 240.351413 -98.740432) (xy 240.280521 -98.785537) (xy 240.205693 -98.823762) (xy 240.127596 -98.854764)
			(xy 240.046926 -98.878269) (xy 239.964399 -98.894067) (xy 239.88075 -98.902017) (xy 239.838738 -98.90252)
			(xy 239.792335 -98.901915) (xy 239.700037 -98.892219) (xy 239.609252 -98.872959) (xy 239.520967 -98.844345)
			(xy 239.478312 -98.826066) (xy 239.46837 -98.82226) (xy 239.447106 -98.82226) (xy 239.437164 -98.826066)
			(xy 239.394498 -98.844316) (xy 239.306212 -98.872912) (xy 239.215431 -98.892173) (xy 239.123139 -98.901889)
			(xy 239.076738 -98.90252) (xy 239.035642 -98.902044) (xy 238.9538 -98.894466) (xy 238.873006 -98.879373)
			(xy 238.793948 -98.856892) (xy 238.7173 -98.827215) (xy 238.643717 -98.790595) (xy 238.573825 -98.747345)
			(xy 238.508219 -98.697833) (xy 238.44746 -98.64248) (xy 238.392066 -98.58176) (xy 238.342507 -98.516189)
			(xy 238.299208 -98.446327) (xy 238.280448 -98.40976) (xy 238.274098 -98.396806) (xy 238.250222 -98.38182)
			(xy 238.13135 -98.380042) (xy 238.106966 -98.394266) (xy 238.100108 -98.406966) (xy 238.079063 -98.445144)
			(xy 238.030497 -98.517548) (xy 237.97508 -98.584852) (xy 237.913343 -98.64641) (xy 237.845879 -98.701633)
			(xy 237.773335 -98.749989) (xy 237.696408 -98.791014) (xy 237.615835 -98.824316) (xy 237.532391 -98.849574)
			(xy 237.446875 -98.866545) (xy 237.36011 -98.875068) (xy 237.316518 -98.875596) (xy 237.270115 -98.875)
			(xy 237.177817 -98.865302) (xy 237.087031 -98.846039) (xy 236.998747 -98.817422) (xy 236.956092 -98.799142)
			(xy 236.94615 -98.795336) (xy 236.924886 -98.795336) (xy 236.914944 -98.799142) (xy 236.87228 -98.817397)
			(xy 236.783993 -98.845992) (xy 236.693211 -98.865251) (xy 236.600919 -98.874966) (xy 236.554518 -98.875596)
			(xy 236.512503 -98.875129) (xy 236.428848 -98.867197) (xy 236.346313 -98.85141) (xy 236.265636 -98.827911)
			(xy 236.187534 -98.796907) (xy 236.112704 -98.758676) (xy 236.041813 -98.713558) (xy 235.975493 -98.661956)
			(xy 235.914336 -98.604329) (xy 235.886244 -98.573082) (xy 235.878878 -98.5647) (xy 235.859066 -98.55581)
			(xy 235.760768 -98.55581) (xy 235.740956 -98.5647) (xy 235.73359 -98.573082) (xy 235.705492 -98.604321)
			(xy 235.644323 -98.661928) (xy 235.577996 -98.713514) (xy 235.507103 -98.75862) (xy 235.432275 -98.796844)
			(xy 235.354177 -98.827845) (xy 235.273506 -98.851349) (xy 235.190978 -98.867146) (xy 235.107329 -98.875094)
			(xy 235.065316 -98.875596) (xy 235.018913 -98.875001) (xy 234.926615 -98.865302) (xy 234.835829 -98.846039)
			(xy 234.747545 -98.817422) (xy 234.70489 -98.799142) (xy 234.694948 -98.795336) (xy 234.673684 -98.795336)
			(xy 234.663742 -98.799142) (xy 234.621078 -98.817397) (xy 234.532791 -98.845993) (xy 234.442009 -98.865252)
			(xy 234.349717 -98.874966) (xy 234.303316 -98.875596) (xy 234.259735 -98.875093) (xy 234.172991 -98.866554)
			(xy 234.087498 -98.849575) (xy 234.004075 -98.824318) (xy 233.92352 -98.791027) (xy 233.846606 -98.750019)
			(xy 233.77407 -98.701689) (xy 233.706607 -98.646498) (xy 233.644862 -98.584976) (xy 233.589428 -98.517712)
			(xy 233.540836 -98.445351) (xy 233.519726 -98.40722) (xy 233.512868 -98.39452) (xy 233.488738 -98.380296)
			(xy 233.369612 -98.382074) (xy 233.345736 -98.39706) (xy 233.339386 -98.410014) (xy 233.320611 -98.446555)
			(xy 233.277315 -98.516379) (xy 233.227765 -98.581914) (xy 233.172384 -98.6426) (xy 233.111643 -98.697922)
			(xy 233.04606 -98.747408) (xy 232.976193 -98.790636) (xy 232.902638 -98.827237) (xy 232.826022 -98.856901)
			(xy 232.746997 -98.879374) (xy 232.666237 -98.894464) (xy 232.584429 -98.902044) (xy 232.54335 -98.90252)
			(xy 232.496947 -98.901911) (xy 232.40465 -98.892216) (xy 232.313864 -98.872957) (xy 232.225579 -98.844344)
			(xy 232.182924 -98.826066) (xy 232.172982 -98.82226) (xy 232.151718 -98.82226) (xy 232.141776 -98.826066)
			(xy 232.099108 -98.844312) (xy 232.010823 -98.872909) (xy 231.920042 -98.892171) (xy 231.82775 -98.901888)
			(xy 231.78135 -98.90252) (xy 231.739335 -98.902057) (xy 231.655679 -98.894126) (xy 231.573143 -98.878341)
			(xy 231.492465 -98.854842) (xy 231.414363 -98.823839) (xy 231.339533 -98.785607) (xy 231.268642 -98.740488)
			(xy 231.202323 -98.688883) (xy 231.141167 -98.631254) (xy 231.113076 -98.600006) (xy 231.10571 -98.591624)
			(xy 231.085898 -98.582734) (xy 230.9876 -98.582734) (xy 230.967788 -98.591624) (xy 230.960422 -98.600006)
			(xy 230.932313 -98.631234) (xy 230.871144 -98.688841) (xy 230.804819 -98.740427) (xy 230.733927 -98.785534)
			(xy 230.659101 -98.823758) (xy 230.581005 -98.854761) (xy 230.500334 -98.878267) (xy 230.417808 -98.894066)
			(xy 230.33416 -98.902017) (xy 230.292148 -98.90252) (xy 230.245745 -98.901912) (xy 230.153448 -98.892216)
			(xy 230.062662 -98.872957) (xy 229.974377 -98.844344) (xy 229.931722 -98.826066) (xy 229.92178 -98.82226)
			(xy 229.900516 -98.82226) (xy 229.890574 -98.826066) (xy 229.847907 -98.844312) (xy 229.759621 -98.87291)
			(xy 229.66884 -98.892171) (xy 229.576548 -98.901889) (xy 229.530148 -98.90252) (xy 229.487783 -98.902118)
			(xy 229.403437 -98.894068) (xy 229.320238 -98.878037) (xy 229.238939 -98.854169) (xy 229.160278 -98.822682)
			(xy 229.084966 -98.783859) (xy 229.013685 -98.738053) (xy 228.947082 -98.685679) (xy 228.885758 -98.627211)
			(xy 228.830271 -98.563178) (xy 228.781121 -98.49416) (xy 228.738755 -98.420783) (xy 228.703556 -98.343711)
			(xy 228.675843 -98.263642) (xy 228.655866 -98.181301) (xy 228.643808 -98.097434) (xy 228.639776 -98.0128)
			(xy 228.496115 -98.0128) (xy 228.493369 -98.070428) (xy 228.481312 -98.154289) (xy 228.461338 -98.236624)
			(xy 228.433628 -98.316688) (xy 228.398433 -98.393756) (xy 228.356071 -98.467129) (xy 228.306927 -98.536143)
			(xy 228.251445 -98.600173) (xy 228.190129 -98.658639) (xy 228.123532 -98.711012) (xy 228.052258 -98.756818)
			(xy 227.976953 -98.795642) (xy 227.898299 -98.827131) (xy 227.817008 -98.851002) (xy 227.733816 -98.867037)
			(xy 227.649476 -98.875091) (xy 227.607114 -98.875596) (xy 227.560711 -98.875002) (xy 227.468413 -98.865303)
			(xy 227.377627 -98.84604) (xy 227.289343 -98.817422) (xy 227.246688 -98.799142) (xy 227.236746 -98.795336)
			(xy 227.215482 -98.795336) (xy 227.20554 -98.799142) (xy 227.162877 -98.817398) (xy 227.07459 -98.845993)
			(xy 226.983807 -98.865252) (xy 226.891515 -98.874966) (xy 226.845114 -98.875596) (xy 226.803099 -98.875132)
			(xy 226.719443 -98.867199) (xy 226.636909 -98.851412) (xy 226.556231 -98.827912) (xy 226.47813 -98.796908)
			(xy 226.4033 -98.758677) (xy 226.332409 -98.713559) (xy 226.266089 -98.661956) (xy 226.204932 -98.604329)
			(xy 226.17684 -98.573082) (xy 226.169474 -98.5647) (xy 226.149662 -98.55581) (xy 226.051364 -98.55581)
			(xy 226.031552 -98.5647) (xy 226.024186 -98.573082) (xy 225.996091 -98.604322) (xy 225.93492 -98.66193)
			(xy 225.868594 -98.713516) (xy 225.7977 -98.758621) (xy 225.722872 -98.796845) (xy 225.644774 -98.827847)
			(xy 225.564102 -98.85135) (xy 225.481574 -98.867146) (xy 225.397925 -98.875094) (xy 225.355912 -98.875596)
			(xy 225.309509 -98.875003) (xy 225.217211 -98.865303) (xy 225.126425 -98.84604) (xy 225.038141 -98.817423)
			(xy 224.995486 -98.799142) (xy 224.985544 -98.795336) (xy 224.96428 -98.795336) (xy 224.954338 -98.799142)
			(xy 224.911675 -98.817399) (xy 224.823388 -98.845994) (xy 224.732606 -98.865252) (xy 224.640313 -98.874966)
			(xy 224.593912 -98.875596) (xy 224.550884 -98.875115) (xy 224.46523 -98.866789) (xy 224.380781 -98.850235)
			(xy 224.298323 -98.825606) (xy 224.218628 -98.793132) (xy 224.14244 -98.753118) (xy 224.070471 -98.705935)
			(xy 224.003392 -98.652026) (xy 223.94183 -98.591893) (xy 223.88636 -98.526099) (xy 223.837501 -98.455257)
			(xy 223.816164 -98.417888) (xy 223.811456 -98.410156) (xy 223.797725 -98.398375) (xy 223.78076 -98.392092)
			(xy 223.771714 -98.391726) (xy 223.683068 -98.391726) (xy 223.674022 -98.392104) (xy 223.657053 -98.398374)
			(xy 223.643325 -98.410155) (xy 223.638618 -98.417888) (xy 223.61725 -98.45524) (xy 223.568406 -98.526093)
			(xy 223.512948 -98.591898) (xy 223.451394 -98.652039) (xy 223.38432 -98.705954) (xy 223.312352 -98.753139)
			(xy 223.236163 -98.793153) (xy 223.156466 -98.825623) (xy 223.074006 -98.850243) (xy 222.989554 -98.866785)
			(xy 222.903899 -98.875093) (xy 222.86087 -98.875596) (xy 222.814467 -98.874982) (xy 222.72217 -98.865289)
			(xy 222.631384 -98.846031) (xy 222.5431 -98.81742) (xy 222.500444 -98.799142) (xy 222.490502 -98.795336)
			(xy 222.469238 -98.795336) (xy 222.459296 -98.799142) (xy 222.416639 -98.817413) (xy 222.328349 -98.846004)
			(xy 222.237565 -98.865259) (xy 222.145271 -98.874969) (xy 222.09887 -98.875596) (xy 222.056856 -98.875093)
			(xy 221.973202 -98.867165) (xy 221.890668 -98.851383) (xy 221.809991 -98.827888) (xy 221.731889 -98.796889)
			(xy 221.657059 -98.758662) (xy 221.586168 -98.713549) (xy 221.519847 -98.66195) (xy 221.458688 -98.604327)
			(xy 221.430596 -98.573082) (xy 221.42323 -98.5647) (xy 221.403418 -98.55581) (xy 221.30512 -98.55581)
			(xy 221.285308 -98.5647) (xy 221.277942 -98.573082) (xy 221.249817 -98.604295) (xy 221.188651 -98.661904)
			(xy 221.122328 -98.713491) (xy 221.051439 -98.758599) (xy 220.976614 -98.796826) (xy 220.89852 -98.827831)
			(xy 220.817851 -98.851338) (xy 220.735326 -98.867139) (xy 220.65168 -98.875092) (xy 220.609668 -98.875596)
			(xy 220.563265 -98.874983) (xy 220.470968 -98.865289) (xy 220.380182 -98.846032) (xy 220.291898 -98.81742)
			(xy 220.249242 -98.799142) (xy 220.2393 -98.795336) (xy 220.218036 -98.795336) (xy 220.208094 -98.799142)
			(xy 220.165437 -98.817413) (xy 220.077147 -98.846004) (xy 219.986363 -98.865259) (xy 219.894069 -98.874969)
			(xy 219.847668 -98.875596) (xy 219.806723 -98.875148) (xy 219.725182 -98.867601) (xy 219.644679 -98.852594)
			(xy 219.565896 -98.830252) (xy 219.489499 -98.800765) (xy 219.416135 -98.764383) (xy 219.346425 -98.721413)
			(xy 219.280958 -98.672219) (xy 219.220289 -98.617217) (xy 219.164931 -98.556873) (xy 219.13977 -98.524568)
			(xy 219.132404 -98.514916) (xy 219.110814 -98.504502) (xy 219.004388 -98.50628) (xy 218.983052 -98.517456)
			(xy 218.97594 -98.527362) (xy 218.950986 -98.561702) (xy 218.895528 -98.625977) (xy 218.834198 -98.684675)
			(xy 218.767553 -98.737261) (xy 218.6962 -98.783257) (xy 218.620789 -98.822245) (xy 218.542006 -98.853868)
			(xy 218.460568 -98.87784) (xy 218.377216 -98.893943) (xy 218.292709 -98.902029) (xy 218.250262 -98.90252)
			(xy 218.203867 -98.901914) (xy 218.111579 -98.892276) (xy 218.020796 -98.873086) (xy 217.932501 -98.844555)
			(xy 217.889836 -98.82632) (xy 217.879894 -98.822514) (xy 217.85863 -98.822514) (xy 217.848688 -98.82632)
			(xy 217.806031 -98.844578) (xy 217.717737 -98.873118) (xy 217.62695 -98.892308) (xy 217.534659 -98.901937)
			(xy 217.488262 -98.90252) (xy 217.446255 -98.90201) (xy 217.362615 -98.894097) (xy 217.280094 -98.878335)
			(xy 217.199425 -98.854865) (xy 217.121328 -98.823895) (xy 217.046498 -98.785702) (xy 216.975601 -98.740625)
			(xy 216.909269 -98.689066) (xy 216.848092 -98.631484) (xy 216.819988 -98.60026) (xy 216.812622 -98.591878)
			(xy 216.79281 -98.582988) (xy 216.694512 -98.582988) (xy 216.6747 -98.591878) (xy 216.667334 -98.60026)
			(xy 216.639237 -98.631494) (xy 216.578074 -98.689098) (xy 216.511749 -98.740675) (xy 216.440855 -98.785766)
			(xy 216.366023 -98.823967) (xy 216.287921 -98.854938) (xy 216.207246 -98.878404) (xy 216.124717 -98.894154)
			(xy 216.04107 -98.902048) (xy 215.99906 -98.90252) (xy 215.952665 -98.901915) (xy 215.860377 -98.892276)
			(xy 215.769594 -98.873087) (xy 215.681299 -98.844555) (xy 215.638634 -98.82632) (xy 215.628692 -98.822514)
			(xy 215.607428 -98.822514) (xy 215.597486 -98.82632) (xy 215.55483 -98.844579) (xy 215.466535 -98.873119)
			(xy 215.375748 -98.892308) (xy 215.283457 -98.901937) (xy 215.23706 -98.90252) (xy 215.194713 -98.901991)
			(xy 215.110404 -98.893936) (xy 215.027241 -98.877905) (xy 214.94598 -98.854041) (xy 214.867354 -98.822561)
			(xy 214.792077 -98.78375) (xy 214.720829 -98.737959) (xy 214.654257 -98.685603) (xy 214.592963 -98.627157)
			(xy 214.537502 -98.563148) (xy 214.488376 -98.494158) (xy 214.44603 -98.420811) (xy 214.410848 -98.343771)
			(xy 214.383149 -98.263735) (xy 214.363182 -98.181429) (xy 214.351129 -98.097598) (xy 214.347099 -98.013)
			(xy 0.509016 -98.013) (xy 0.509016 -101.388361) (xy 214.756742 -101.388361) (xy 214.756742 -101.303639)
			(xy 214.764795 -101.219302) (xy 214.780829 -101.136112) (xy 214.804697 -101.054822) (xy 214.836185 -100.97617)
			(xy 214.875007 -100.900867) (xy 214.92081 -100.829595) (xy 214.973181 -100.762999) (xy 215.031646 -100.701684)
			(xy 215.095674 -100.646203) (xy 215.164686 -100.59706) (xy 215.238056 -100.5547) (xy 215.315121 -100.519505)
			(xy 215.395183 -100.491796) (xy 215.477516 -100.471822) (xy 215.561375 -100.459765) (xy 215.646 -100.455734)
			(xy 215.730625 -100.459765) (xy 215.814484 -100.471822) (xy 215.896817 -100.491796) (xy 215.976879 -100.519505)
			(xy 216.053944 -100.5547) (xy 216.127314 -100.59706) (xy 216.196326 -100.646203) (xy 216.260354 -100.701684)
			(xy 216.318819 -100.762999) (xy 216.37119 -100.829595) (xy 216.416993 -100.900867) (xy 216.455815 -100.97617)
			(xy 216.487303 -101.054822) (xy 216.511171 -101.136112) (xy 216.527205 -101.219302) (xy 216.535258 -101.303639)
			(xy 216.535762 -101.346) (xy 216.535258 -101.388361) (xy 216.527205 -101.472698) (xy 216.511171 -101.555888)
			(xy 216.487303 -101.637178) (xy 216.455815 -101.71583) (xy 216.450056 -101.727) (xy 268.350492 -101.727)
			(xy 268.351075 -101.680604) (xy 268.36072 -101.588316) (xy 268.379916 -101.497532) (xy 268.408454 -101.409239)
			(xy 268.426692 -101.366574) (xy 268.430498 -101.356632) (xy 268.430498 -101.335368) (xy 268.426692 -101.325426)
			(xy 268.408447 -101.282764) (xy 268.379903 -101.194471) (xy 268.36071 -101.103686) (xy 268.351077 -101.011396)
			(xy 268.350492 -100.965) (xy 268.351075 -100.918604) (xy 268.36072 -100.826316) (xy 268.379916 -100.735532)
			(xy 268.408454 -100.647239) (xy 268.426692 -100.604574) (xy 268.430498 -100.594632) (xy 268.430498 -100.573368)
			(xy 268.426692 -100.563426) (xy 268.408447 -100.520764) (xy 268.379903 -100.432471) (xy 268.36071 -100.341686)
			(xy 268.351077 -100.249396) (xy 268.350492 -100.203) (xy 268.351075 -100.156604) (xy 268.36072 -100.064316)
			(xy 268.379916 -99.973532) (xy 268.408454 -99.885239) (xy 268.426692 -99.842574) (xy 268.430498 -99.832632)
			(xy 268.430498 -99.811368) (xy 268.426692 -99.801426) (xy 268.408447 -99.758764) (xy 268.379903 -99.670471)
			(xy 268.36071 -99.579686) (xy 268.351077 -99.487396) (xy 268.350492 -99.441) (xy 268.351075 -99.394604)
			(xy 268.36072 -99.302316) (xy 268.379916 -99.211532) (xy 268.408454 -99.123239) (xy 268.426692 -99.080574)
			(xy 268.430498 -99.070632) (xy 268.430498 -99.049368) (xy 268.426692 -99.039426) (xy 268.408447 -98.996764)
			(xy 268.379903 -98.908471) (xy 268.36071 -98.817686) (xy 268.351077 -98.725396) (xy 268.350492 -98.679)
			(xy 268.351075 -98.632604) (xy 268.36072 -98.540316) (xy 268.379916 -98.449532) (xy 268.408454 -98.361239)
			(xy 268.426692 -98.318574) (xy 268.430498 -98.308632) (xy 268.430498 -98.287368) (xy 268.426692 -98.277426)
			(xy 268.408447 -98.234764) (xy 268.379903 -98.146471) (xy 268.36071 -98.055686) (xy 268.351077 -97.963396)
			(xy 268.350492 -97.917) (xy 268.350967 -97.875898) (xy 268.358552 -97.794043) (xy 268.373657 -97.713238)
			(xy 268.396153 -97.634171) (xy 268.425849 -97.557517) (xy 268.462491 -97.48393) (xy 268.505766 -97.414038)
			(xy 268.555306 -97.348437) (xy 268.610687 -97.287687) (xy 268.671437 -97.232306) (xy 268.737038 -97.182766)
			(xy 268.80693 -97.139491) (xy 268.880517 -97.102849) (xy 268.957171 -97.073153) (xy 269.036238 -97.050657)
			(xy 269.117043 -97.035552) (xy 269.198898 -97.027967) (xy 269.24 -97.027492) (xy 269.286396 -97.028075)
			(xy 269.378684 -97.03772) (xy 269.469468 -97.056916) (xy 269.557761 -97.085454) (xy 269.600426 -97.103692)
			(xy 269.610368 -97.107498) (xy 269.631632 -97.107498) (xy 269.641574 -97.103692) (xy 269.684236 -97.085447)
			(xy 269.772529 -97.056903) (xy 269.863314 -97.03771) (xy 269.955604 -97.028077) (xy 270.002 -97.027492)
			(xy 270.048396 -97.028075) (xy 270.140684 -97.03772) (xy 270.231468 -97.056916) (xy 270.319761 -97.085454)
			(xy 270.362426 -97.103692) (xy 270.372368 -97.107498) (xy 270.393632 -97.107498) (xy 270.403574 -97.103692)
			(xy 270.446236 -97.085447) (xy 270.534529 -97.056903) (xy 270.625314 -97.03771) (xy 270.717604 -97.028077)
			(xy 270.764 -97.027492) (xy 270.810396 -97.028075) (xy 270.902684 -97.03772) (xy 270.993468 -97.056916)
			(xy 271.081761 -97.085454) (xy 271.124426 -97.103692) (xy 271.134368 -97.107498) (xy 271.155632 -97.107498)
			(xy 271.165574 -97.103692) (xy 271.208236 -97.085447) (xy 271.296529 -97.056903) (xy 271.387314 -97.03771)
			(xy 271.479604 -97.028077) (xy 271.526 -97.027492) (xy 271.572396 -97.028075) (xy 271.664684 -97.03772)
			(xy 271.755468 -97.056916) (xy 271.843761 -97.085454) (xy 271.886426 -97.103692) (xy 271.896368 -97.107498)
			(xy 271.917632 -97.107498) (xy 271.927574 -97.103692) (xy 271.970236 -97.085447) (xy 272.058529 -97.056903)
			(xy 272.149314 -97.03771) (xy 272.241604 -97.028077) (xy 272.288 -97.027492) (xy 272.329102 -97.027967)
			(xy 272.410957 -97.035552) (xy 272.491762 -97.050657) (xy 272.570829 -97.073153) (xy 272.647483 -97.102849)
			(xy 272.72107 -97.139491) (xy 272.790962 -97.182766) (xy 272.856563 -97.232306) (xy 272.917313 -97.287687)
			(xy 272.972694 -97.348437) (xy 273.022234 -97.414038) (xy 273.065509 -97.48393) (xy 273.102151 -97.557517)
			(xy 273.131847 -97.634171) (xy 273.154343 -97.713238) (xy 273.169448 -97.794043) (xy 273.177033 -97.875898)
			(xy 273.177508 -97.917) (xy 273.176925 -97.963396) (xy 273.16728 -98.055684) (xy 273.148084 -98.146468)
			(xy 273.119546 -98.234761) (xy 273.101308 -98.277426) (xy 273.097502 -98.287368) (xy 273.097502 -98.308632)
			(xy 273.101308 -98.318574) (xy 273.119553 -98.361236) (xy 273.148097 -98.449529) (xy 273.16729 -98.540314)
			(xy 273.176923 -98.632604) (xy 273.177508 -98.679) (xy 273.177033 -98.720102) (xy 273.169448 -98.801957)
			(xy 273.154343 -98.882762) (xy 273.131847 -98.961829) (xy 273.102151 -99.038483) (xy 273.065509 -99.11207)
			(xy 273.022234 -99.181962) (xy 272.972694 -99.247563) (xy 272.917313 -99.308313) (xy 272.856563 -99.363694)
			(xy 272.790962 -99.413234) (xy 272.72107 -99.456509) (xy 272.647483 -99.493151) (xy 272.570829 -99.522847)
			(xy 272.491762 -99.545343) (xy 272.410957 -99.560448) (xy 272.329102 -99.568033) (xy 272.288 -99.568508)
			(xy 272.241604 -99.567925) (xy 272.149316 -99.55828) (xy 272.058532 -99.539084) (xy 271.970239 -99.510546)
			(xy 271.927574 -99.492308) (xy 271.917632 -99.488502) (xy 271.896368 -99.488502) (xy 271.886426 -99.492308)
			(xy 271.853507 -99.506537) (xy 271.785822 -99.530257) (xy 271.716442 -99.548437) (xy 271.681194 -99.555046)
			(xy 271.67107 -99.557344) (xy 271.653749 -99.568749) (xy 271.642344 -99.58607) (xy 271.640046 -99.596194)
			(xy 271.633416 -99.631437) (xy 271.61522 -99.70081) (xy 271.591513 -99.768498) (xy 271.577308 -99.801426)
			(xy 271.573502 -99.811368) (xy 271.573502 -99.832632) (xy 271.577308 -99.842574) (xy 271.591537 -99.875493)
			(xy 271.615257 -99.943178) (xy 271.633437 -100.012558) (xy 271.640046 -100.047806) (xy 271.642344 -100.05793)
			(xy 271.653749 -100.075251) (xy 271.67107 -100.086656) (xy 271.681194 -100.088954) (xy 271.716437 -100.095584)
			(xy 271.78581 -100.11378) (xy 271.853498 -100.137487) (xy 271.886426 -100.151692) (xy 271.896368 -100.155498)
			(xy 271.917632 -100.155498) (xy 271.927574 -100.151692) (xy 271.970236 -100.133447) (xy 272.058529 -100.104903)
			(xy 272.149314 -100.08571) (xy 272.241604 -100.076077) (xy 272.288 -100.075492) (xy 272.329102 -100.075967)
			(xy 272.410957 -100.083552) (xy 272.491762 -100.098657) (xy 272.570829 -100.121153) (xy 272.647483 -100.150849)
			(xy 272.72107 -100.187491) (xy 272.790962 -100.230766) (xy 272.856563 -100.280306) (xy 272.917313 -100.335687)
			(xy 272.972694 -100.396437) (xy 273.022234 -100.462038) (xy 273.065509 -100.53193) (xy 273.102151 -100.605517)
			(xy 273.131847 -100.682171) (xy 273.154343 -100.761238) (xy 273.169448 -100.842043) (xy 273.177033 -100.923898)
			(xy 273.177508 -100.965) (xy 273.176925 -101.011396) (xy 273.16728 -101.103684) (xy 273.148084 -101.194468)
			(xy 273.119546 -101.282761) (xy 273.101308 -101.325426) (xy 273.097502 -101.335368) (xy 273.097502 -101.356632)
			(xy 273.101308 -101.366574) (xy 273.119553 -101.409236) (xy 273.148097 -101.497529) (xy 273.16729 -101.588314)
			(xy 273.176923 -101.680604) (xy 273.177508 -101.727) (xy 273.177087 -101.76701) (xy 273.169907 -101.846708)
			(xy 273.155596 -101.925439) (xy 273.134269 -102.002565) (xy 273.106099 -102.077463) (xy 273.071314 -102.149528)
			(xy 273.030196 -102.218176) (xy 272.983076 -102.282852) (xy 272.957036 -102.313232) (xy 272.947892 -102.3239)
			(xy 272.942812 -102.350824) (xy 272.982436 -102.460806) (xy 273.003518 -102.478332) (xy 273.017488 -102.480618)
			(xy 273.058748 -102.487682) (xy 273.139783 -102.5087) (xy 273.202283 -102.531361) (xy 275.081742 -102.531361)
			(xy 275.081742 -102.446639) (xy 275.089795 -102.362302) (xy 275.105829 -102.279112) (xy 275.129697 -102.197822)
			(xy 275.161185 -102.11917) (xy 275.200007 -102.043867) (xy 275.24581 -101.972595) (xy 275.298181 -101.905999)
			(xy 275.356646 -101.844684) (xy 275.420674 -101.789203) (xy 275.489686 -101.74006) (xy 275.563056 -101.6977)
			(xy 275.640121 -101.662505) (xy 275.720183 -101.634796) (xy 275.802516 -101.614822) (xy 275.886375 -101.602765)
			(xy 275.971 -101.598734) (xy 276.055625 -101.602765) (xy 276.139484 -101.614822) (xy 276.221817 -101.634796)
			(xy 276.301879 -101.662505) (xy 276.378944 -101.6977) (xy 276.452314 -101.74006) (xy 276.521326 -101.789203)
			(xy 276.585354 -101.844684) (xy 276.643819 -101.905999) (xy 276.69619 -101.972595) (xy 276.741993 -102.043867)
			(xy 276.780815 -102.11917) (xy 276.812303 -102.197822) (xy 276.836171 -102.279112) (xy 276.852205 -102.362302)
			(xy 276.860258 -102.446639) (xy 276.860762 -102.489) (xy 276.860258 -102.531361) (xy 276.852205 -102.615698)
			(xy 276.836171 -102.698888) (xy 276.812303 -102.780178) (xy 276.780815 -102.85883) (xy 276.741993 -102.934133)
			(xy 276.69619 -103.005405) (xy 276.643819 -103.072001) (xy 276.585354 -103.133316) (xy 276.521326 -103.188797)
			(xy 276.452314 -103.23794) (xy 276.378944 -103.2803) (xy 276.301879 -103.315495) (xy 276.221817 -103.343204)
			(xy 276.139484 -103.363178) (xy 276.055625 -103.375235) (xy 275.971 -103.379267) (xy 275.886375 -103.375235)
			(xy 275.802516 -103.363178) (xy 275.720183 -103.343204) (xy 275.640121 -103.315495) (xy 275.563056 -103.2803)
			(xy 275.489686 -103.23794) (xy 275.420674 -103.188797) (xy 275.356646 -103.133316) (xy 275.298181 -103.072001)
			(xy 275.24581 -103.005405) (xy 275.200007 -102.934133) (xy 275.161185 -102.85883) (xy 275.129697 -102.780178)
			(xy 275.105829 -102.698888) (xy 275.089795 -102.615698) (xy 275.081742 -102.531361) (xy 273.202283 -102.531361)
			(xy 273.218486 -102.537236) (xy 273.29416 -102.573039) (xy 273.366137 -102.615792) (xy 273.43378 -102.665117)
			(xy 273.49649 -102.720577) (xy 273.553714 -102.781682) (xy 273.604945 -102.847892) (xy 273.649731 -102.918622)
			(xy 273.687675 -102.993246) (xy 273.718442 -103.071104) (xy 273.741759 -103.151508) (xy 273.757421 -103.233746)
			(xy 273.76529 -103.317092) (xy 273.765772 -103.35895) (xy 273.765268 -103.401298) (xy 273.757217 -103.485612)
			(xy 273.741188 -103.568778) (xy 273.717327 -103.650045) (xy 273.685848 -103.728675) (xy 273.647037 -103.803956)
			(xy 273.601247 -103.875208) (xy 273.548891 -103.941784) (xy 273.490443 -104.003082) (xy 273.426433 -104.058547)
			(xy 273.357441 -104.107676) (xy 273.284091 -104.150025) (xy 273.207048 -104.185209) (xy 273.127009 -104.212911)
			(xy 273.0447 -104.232879) (xy 272.960865 -104.244932) (xy 272.876264 -104.248963) (xy 272.791663 -104.244932)
			(xy 272.707828 -104.232879) (xy 272.625519 -104.212911) (xy 272.54548 -104.185209) (xy 272.468437 -104.150025)
			(xy 272.395087 -104.107676) (xy 272.326095 -104.058547) (xy 272.262085 -104.003082) (xy 272.203637 -103.941784)
			(xy 272.151281 -103.875208) (xy 272.105491 -103.803956) (xy 272.06668 -103.728675) (xy 272.035201 -103.650045)
			(xy 272.01134 -103.568778) (xy 271.995311 -103.485612) (xy 271.98726 -103.401298) (xy 271.986756 -103.35895)
			(xy 271.987216 -103.318941) (xy 271.994392 -103.239244) (xy 272.008698 -103.160515) (xy 272.03002 -103.083389)
			(xy 272.058184 -103.008491) (xy 272.092963 -102.936426) (xy 272.134076 -102.867777) (xy 272.181191 -102.803099)
			(xy 272.207228 -102.772718) (xy 272.216372 -102.76205) (xy 272.221452 -102.735126) (xy 272.181828 -102.625144)
			(xy 272.160746 -102.607618) (xy 272.146776 -102.605332) (xy 272.109108 -102.598853) (xy 272.034963 -102.580278)
			(xy 271.962681 -102.555417) (xy 271.927574 -102.540308) (xy 271.917632 -102.536502) (xy 271.896368 -102.536502)
			(xy 271.886426 -102.540308) (xy 271.843764 -102.558553) (xy 271.755471 -102.587097) (xy 271.664686 -102.60629)
			(xy 271.572396 -102.615923) (xy 271.526 -102.616508) (xy 271.479604 -102.615925) (xy 271.387316 -102.60628)
			(xy 271.296532 -102.587084) (xy 271.208239 -102.558546) (xy 271.165574 -102.540308) (xy 271.155632 -102.536502)
			(xy 271.134368 -102.536502) (xy 271.124426 -102.540308) (xy 271.081764 -102.558553) (xy 270.993471 -102.587097)
			(xy 270.902686 -102.60629) (xy 270.810396 -102.615923) (xy 270.764 -102.616508) (xy 270.717604 -102.615925)
			(xy 270.625316 -102.60628) (xy 270.534532 -102.587084) (xy 270.446239 -102.558546) (xy 270.403574 -102.540308)
			(xy 270.393632 -102.536502) (xy 270.372368 -102.536502) (xy 270.362426 -102.540308) (xy 270.319764 -102.558553)
			(xy 270.231471 -102.587097) (xy 270.140686 -102.60629) (xy 270.048396 -102.615923) (xy 270.002 -102.616508)
			(xy 269.955604 -102.615925) (xy 269.863316 -102.60628) (xy 269.772532 -102.587084) (xy 269.684239 -102.558546)
			(xy 269.641574 -102.540308) (xy 269.631632 -102.536502) (xy 269.610368 -102.536502) (xy 269.600426 -102.540308)
			(xy 269.557764 -102.558553) (xy 269.469471 -102.587097) (xy 269.378686 -102.60629) (xy 269.286396 -102.615923)
			(xy 269.24 -102.616508) (xy 269.198898 -102.616033) (xy 269.117043 -102.608448) (xy 269.036238 -102.593343)
			(xy 268.957171 -102.570847) (xy 268.880517 -102.541151) (xy 268.80693 -102.504509) (xy 268.737038 -102.461234)
			(xy 268.671437 -102.411694) (xy 268.610687 -102.356313) (xy 268.555306 -102.295563) (xy 268.505766 -102.229962)
			(xy 268.462491 -102.16007) (xy 268.425849 -102.086483) (xy 268.396153 -102.009829) (xy 268.373657 -101.930762)
			(xy 268.358552 -101.849957) (xy 268.350967 -101.768102) (xy 268.350492 -101.727) (xy 216.450056 -101.727)
			(xy 216.416993 -101.791133) (xy 216.37119 -101.862405) (xy 216.318819 -101.929001) (xy 216.260354 -101.990316)
			(xy 216.196326 -102.045797) (xy 216.127314 -102.09494) (xy 216.053944 -102.1373) (xy 215.976879 -102.172495)
			(xy 215.896817 -102.200204) (xy 215.814484 -102.220178) (xy 215.730625 -102.232235) (xy 215.646 -102.236267)
			(xy 215.561375 -102.232235) (xy 215.477516 -102.220178) (xy 215.395183 -102.200204) (xy 215.315121 -102.172495)
			(xy 215.238056 -102.1373) (xy 215.164686 -102.09494) (xy 215.095674 -102.045797) (xy 215.031646 -101.990316)
			(xy 214.973181 -101.929001) (xy 214.92081 -101.862405) (xy 214.875007 -101.791133) (xy 214.836185 -101.71583)
			(xy 214.804697 -101.637178) (xy 214.780829 -101.555888) (xy 214.764795 -101.472698) (xy 214.756742 -101.388361)
			(xy 0.509016 -101.388361) (xy 0.509016 -108.3818) (xy 28.498292 -108.3818) (xy 28.498875 -108.335404)
			(xy 28.50852 -108.243116) (xy 28.527716 -108.152332) (xy 28.556254 -108.064039) (xy 28.574492 -108.021374)
			(xy 28.578397 -108.011452) (xy 28.578397 -107.990148) (xy 28.574492 -107.980226) (xy 28.556247 -107.937564)
			(xy 28.527703 -107.849271) (xy 28.50851 -107.758486) (xy 28.498877 -107.666196) (xy 28.498292 -107.6198)
			(xy 28.498723 -107.581372) (xy 28.505365 -107.504803) (xy 28.518591 -107.429093) (xy 28.538303 -107.354808)
			(xy 28.564353 -107.282501) (xy 28.58008 -107.247436) (xy 28.584223 -107.237163) (xy 28.584223 -107.215037)
			(xy 28.58008 -107.204764) (xy 28.564356 -107.169698) (xy 28.53831 -107.097389) (xy 28.518597 -107.023104)
			(xy 28.505365 -106.947396) (xy 28.498711 -106.870828) (xy 28.498292 -106.8324) (xy 28.498875 -106.786004)
			(xy 28.50852 -106.693716) (xy 28.527716 -106.602932) (xy 28.556254 -106.514639) (xy 28.574492 -106.471974)
			(xy 28.578397 -106.462052) (xy 28.578397 -106.440748) (xy 28.574492 -106.430826) (xy 28.556247 -106.388164)
			(xy 28.527703 -106.299871) (xy 28.50851 -106.209086) (xy 28.498877 -106.116796) (xy 28.498292 -106.0704)
			(xy 28.498875 -106.024004) (xy 28.50852 -105.931716) (xy 28.527716 -105.840932) (xy 28.556254 -105.752639)
			(xy 28.574492 -105.709974) (xy 28.578397 -105.700052) (xy 28.578397 -105.678748) (xy 28.574492 -105.668826)
			(xy 28.556247 -105.626164) (xy 28.527703 -105.537871) (xy 28.50851 -105.447086) (xy 28.498877 -105.354796)
			(xy 28.498292 -105.3084) (xy 28.498875 -105.262004) (xy 28.50852 -105.169716) (xy 28.527716 -105.078932)
			(xy 28.556254 -104.990639) (xy 28.574492 -104.947974) (xy 28.578397 -104.938052) (xy 28.578397 -104.916748)
			(xy 28.574492 -104.906826) (xy 28.556247 -104.864164) (xy 28.527703 -104.775871) (xy 28.50851 -104.685086)
			(xy 28.498877 -104.592796) (xy 28.498292 -104.5464) (xy 28.498875 -104.500004) (xy 28.50852 -104.407716)
			(xy 28.527716 -104.316932) (xy 28.556254 -104.228639) (xy 28.574492 -104.185974) (xy 28.578397 -104.176052)
			(xy 28.578397 -104.154748) (xy 28.574492 -104.144826) (xy 28.556247 -104.102164) (xy 28.527703 -104.013871)
			(xy 28.50851 -103.923086) (xy 28.498877 -103.830796) (xy 28.498292 -103.7844) (xy 28.498767 -103.743298)
			(xy 28.506352 -103.661443) (xy 28.521457 -103.580638) (xy 28.543953 -103.501571) (xy 28.573649 -103.424917)
			(xy 28.610291 -103.35133) (xy 28.653566 -103.281438) (xy 28.703106 -103.215837) (xy 28.758487 -103.155087)
			(xy 28.819237 -103.099706) (xy 28.884838 -103.050166) (xy 28.95473 -103.006891) (xy 29.028317 -102.970249)
			(xy 29.104971 -102.940553) (xy 29.184038 -102.918057) (xy 29.264843 -102.902952) (xy 29.346698 -102.895367)
			(xy 29.3878 -102.894892) (xy 29.433417 -102.895466) (xy 29.524172 -102.904799) (xy 29.613497 -102.923367)
			(xy 29.700453 -102.950974) (xy 29.78413 -102.987332) (xy 29.824172 -103.009192) (xy 29.832335 -103.013339)
			(xy 29.8504 -103.0162) (xy 29.86831 -103.012491) (xy 29.876242 -103.007922) (xy 29.911906 -102.985856)
			(xy 29.986639 -102.947783) (xy 30.064625 -102.916916) (xy 30.145171 -102.89353) (xy 30.227561 -102.877832)
			(xy 30.311064 -102.869963) (xy 30.353 -102.869492) (xy 30.39679 -102.86998) (xy 30.483949 -102.878545)
			(xy 30.569843 -102.89564) (xy 30.65364 -102.921101) (xy 30.734526 -102.95468) (xy 30.77337 -102.974902)
			(xy 30.784836 -102.98032) (xy 30.810164 -102.98032) (xy 30.82163 -102.974902) (xy 30.860471 -102.954677)
			(xy 30.941366 -102.921126) (xy 31.025164 -102.89568) (xy 31.111056 -102.878584) (xy 31.198212 -102.870005)
			(xy 31.242 -102.869492) (xy 31.283102 -102.869967) (xy 31.364957 -102.877552) (xy 31.445762 -102.892657)
			(xy 31.524829 -102.915153) (xy 31.601483 -102.944849) (xy 31.67507 -102.981491) (xy 31.744962 -103.024766)
			(xy 31.810563 -103.074306) (xy 31.871313 -103.129687) (xy 31.926694 -103.190437) (xy 31.976234 -103.256038)
			(xy 32.019509 -103.32593) (xy 32.056151 -103.399517) (xy 32.085847 -103.476171) (xy 32.108343 -103.555238)
			(xy 32.123448 -103.636043) (xy 32.131033 -103.717898) (xy 32.131508 -103.759) (xy 32.130925 -103.805396)
			(xy 32.12128 -103.897684) (xy 32.102084 -103.988468) (xy 32.073546 -104.076761) (xy 32.055308 -104.119426)
			(xy 32.051502 -104.129368) (xy 32.051502 -104.150632) (xy 32.055308 -104.160574) (xy 32.073553 -104.203236)
			(xy 32.102097 -104.291529) (xy 32.12129 -104.382314) (xy 32.130923 -104.474604) (xy 32.131508 -104.521)
			(xy 32.130925 -104.567396) (xy 32.12128 -104.659684) (xy 32.102084 -104.750468) (xy 32.073546 -104.838761)
			(xy 32.055308 -104.881426) (xy 32.051502 -104.891368) (xy 32.051502 -104.912632) (xy 32.055308 -104.922574)
			(xy 32.073553 -104.965236) (xy 32.102097 -105.053529) (xy 32.12129 -105.144314) (xy 32.130923 -105.236604)
			(xy 32.131508 -105.283) (xy 32.130925 -105.329396) (xy 32.12128 -105.421684) (xy 32.102084 -105.512468)
			(xy 32.073546 -105.600761) (xy 32.055308 -105.643426) (xy 32.051502 -105.653368) (xy 32.051502 -105.674632)
			(xy 32.055308 -105.684574) (xy 32.073553 -105.727236) (xy 32.102097 -105.815529) (xy 32.12129 -105.906314)
			(xy 32.130923 -105.998604) (xy 32.131508 -106.045) (xy 32.130925 -106.091396) (xy 32.12128 -106.183684)
			(xy 32.102084 -106.274468) (xy 32.073546 -106.362761) (xy 32.055308 -106.405426) (xy 32.051502 -106.415368)
			(xy 32.051502 -106.436632) (xy 32.055308 -106.446574) (xy 32.073553 -106.489236) (xy 32.102097 -106.577529)
			(xy 32.12129 -106.668314) (xy 32.130923 -106.760604) (xy 32.131508 -106.807) (xy 32.131149 -106.845449)
			(xy 32.124566 -106.922065) (xy 32.111388 -106.997826) (xy 32.091715 -107.072165) (xy 32.065692 -107.144526)
			(xy 32.049974 -107.179618) (xy 32.045874 -107.189831) (xy 32.045885 -107.211818) (xy 32.049974 -107.222036)
			(xy 32.065681 -107.257103) (xy 32.091668 -107.329421) (xy 32.111325 -107.40371) (xy 32.124505 -107.479417)
			(xy 32.131112 -107.555977) (xy 32.131508 -107.5944) (xy 32.130925 -107.640796) (xy 32.12128 -107.733084)
			(xy 32.102084 -107.823868) (xy 32.073546 -107.912161) (xy 32.055308 -107.954826) (xy 32.051403 -107.964748)
			(xy 32.051403 -107.986052) (xy 32.055308 -107.995974) (xy 32.073553 -108.038636) (xy 32.102097 -108.126929)
			(xy 32.12129 -108.217714) (xy 32.130923 -108.310004) (xy 32.131508 -108.3564) (xy 38.937692 -108.3564)
			(xy 38.938275 -108.310004) (xy 38.94792 -108.217716) (xy 38.967116 -108.126932) (xy 38.995654 -108.038639)
			(xy 39.013892 -107.995974) (xy 39.017797 -107.986052) (xy 39.017797 -107.964748) (xy 39.013892 -107.954826)
			(xy 38.995647 -107.912164) (xy 38.967103 -107.823871) (xy 38.94791 -107.733086) (xy 38.938277 -107.640796)
			(xy 38.937692 -107.5944) (xy 38.938251 -107.550173) (xy 38.947033 -107.462156) (xy 38.964509 -107.375446)
			(xy 38.990508 -107.2909) (xy 39.024773 -107.209352) (xy 39.045388 -107.17022) (xy 39.050228 -107.160228)
			(xy 39.051661 -107.138093) (xy 39.048182 -107.127548) (xy 39.033858 -107.089132) (xy 39.011486 -107.010251)
			(xy 38.996473 -106.929644) (xy 38.988949 -106.847997) (xy 38.988492 -106.807) (xy 38.989075 -106.760604)
			(xy 38.99872 -106.668316) (xy 39.017916 -106.577532) (xy 39.046454 -106.489239) (xy 39.064692 -106.446574)
			(xy 39.068498 -106.436632) (xy 39.068498 -106.415368) (xy 39.064692 -106.405426) (xy 39.046447 -106.362764)
			(xy 39.017903 -106.274471) (xy 38.99871 -106.183686) (xy 38.989077 -106.091396) (xy 38.988492 -106.045)
			(xy 38.989075 -105.998604) (xy 38.99872 -105.906316) (xy 39.017916 -105.815532) (xy 39.046454 -105.727239)
			(xy 39.064692 -105.684574) (xy 39.068498 -105.674632) (xy 39.068498 -105.653368) (xy 39.064692 -105.643426)
			(xy 39.046447 -105.600764) (xy 39.017903 -105.512471) (xy 38.99871 -105.421686) (xy 38.989077 -105.329396)
			(xy 38.988492 -105.283) (xy 38.989075 -105.236604) (xy 38.99872 -105.144316) (xy 39.017916 -105.053532)
			(xy 39.046454 -104.965239) (xy 39.064692 -104.922574) (xy 39.068498 -104.912632) (xy 39.068498 -104.891368)
			(xy 39.064692 -104.881426) (xy 39.046447 -104.838764) (xy 39.017903 -104.750471) (xy 38.99871 -104.659686)
			(xy 38.989077 -104.567396) (xy 38.988492 -104.521) (xy 38.989075 -104.474604) (xy 38.99872 -104.382316)
			(xy 39.017916 -104.291532) (xy 39.046454 -104.203239) (xy 39.064692 -104.160574) (xy 39.068498 -104.150632)
			(xy 39.068498 -104.129368) (xy 39.064692 -104.119426) (xy 39.046447 -104.076764) (xy 39.017903 -103.988471)
			(xy 38.99871 -103.897686) (xy 38.989077 -103.805396) (xy 38.988492 -103.759) (xy 38.988967 -103.717898)
			(xy 38.996552 -103.636043) (xy 39.011657 -103.555238) (xy 39.034153 -103.476171) (xy 39.063849 -103.399517)
			(xy 39.100491 -103.32593) (xy 39.143766 -103.256038) (xy 39.193306 -103.190437) (xy 39.248687 -103.129687)
			(xy 39.309437 -103.074306) (xy 39.375038 -103.024766) (xy 39.44493 -102.981491) (xy 39.518517 -102.944849)
			(xy 39.595171 -102.915153) (xy 39.674238 -102.892657) (xy 39.755043 -102.877552) (xy 39.836898 -102.869967)
			(xy 39.878 -102.869492) (xy 39.92179 -102.86998) (xy 40.008949 -102.878545) (xy 40.094843 -102.89564)
			(xy 40.17864 -102.921101) (xy 40.259526 -102.95468) (xy 40.29837 -102.974902) (xy 40.309836 -102.98032)
			(xy 40.335164 -102.98032) (xy 40.34663 -102.974902) (xy 40.385471 -102.954677) (xy 40.466366 -102.921126)
			(xy 40.550164 -102.89568) (xy 40.636056 -102.878584) (xy 40.723212 -102.870005) (xy 40.767 -102.869492)
			(xy 40.813379 -102.870097) (xy 40.905633 -102.879747) (xy 40.996382 -102.898942) (xy 41.084642 -102.927473)
			(xy 41.169455 -102.965032) (xy 41.209976 -102.987602) (xy 41.221253 -102.993254) (xy 41.246432 -102.993937)
			(xy 41.257982 -102.988872) (xy 41.295102 -102.970822) (xy 41.372033 -102.940898) (xy 41.451405 -102.918227)
			(xy 41.532535 -102.903004) (xy 41.614727 -102.89536) (xy 41.656 -102.894892) (xy 41.697102 -102.895367)
			(xy 41.778957 -102.902952) (xy 41.859762 -102.918057) (xy 41.938829 -102.940553) (xy 42.015483 -102.970249)
			(xy 42.08907 -103.006891) (xy 42.158962 -103.050166) (xy 42.224563 -103.099706) (xy 42.285313 -103.155087)
			(xy 42.340694 -103.215837) (xy 42.390234 -103.281438) (xy 42.433509 -103.35133) (xy 42.470151 -103.424917)
			(xy 42.499847 -103.501571) (xy 42.522343 -103.580638) (xy 42.537448 -103.661443) (xy 42.545033 -103.743298)
			(xy 42.545508 -103.7844) (xy 42.544925 -103.830796) (xy 42.53528 -103.923084) (xy 42.516084 -104.013868)
			(xy 42.487546 -104.102161) (xy 42.469308 -104.144826) (xy 42.465403 -104.154748) (xy 42.465403 -104.176052)
			(xy 42.469308 -104.185974) (xy 42.487553 -104.228636) (xy 42.516097 -104.316929) (xy 42.53529 -104.407714)
			(xy 42.544923 -104.500004) (xy 42.545508 -104.5464) (xy 42.544925 -104.592796) (xy 42.53528 -104.685084)
			(xy 42.516084 -104.775868) (xy 42.487546 -104.864161) (xy 42.469308 -104.906826) (xy 42.465403 -104.916748)
			(xy 42.465403 -104.938052) (xy 42.469308 -104.947974) (xy 42.487553 -104.990636) (xy 42.516097 -105.078929)
			(xy 42.53529 -105.169714) (xy 42.544923 -105.262004) (xy 42.545508 -105.3084) (xy 42.544925 -105.354796)
			(xy 42.53528 -105.447084) (xy 42.516084 -105.537868) (xy 42.487546 -105.626161) (xy 42.469308 -105.668826)
			(xy 42.465403 -105.678748) (xy 42.465403 -105.700052) (xy 42.469308 -105.709974) (xy 42.487553 -105.752636)
			(xy 42.516097 -105.840929) (xy 42.525034 -105.883202) (xy 201.446892 -105.883202) (xy 201.447476 -105.836806)
			(xy 201.45712 -105.744518) (xy 201.476316 -105.653734) (xy 201.504854 -105.565441) (xy 201.523092 -105.522776)
			(xy 201.526896 -105.512833) (xy 201.526897 -105.49157) (xy 201.523092 -105.481628) (xy 201.504848 -105.438966)
			(xy 201.476304 -105.350673) (xy 201.45711 -105.259888) (xy 201.447477 -105.167598) (xy 201.446892 -105.121202)
			(xy 201.447364 -105.078635) (xy 201.455472 -104.993887) (xy 201.471642 -104.910303) (xy 201.495727 -104.828647)
			(xy 201.511154 -104.78897) (xy 201.514396 -104.779715) (xy 201.514403 -104.760122) (xy 201.511154 -104.75087)
			(xy 201.495726 -104.711195) (xy 201.47165 -104.629536) (xy 201.455485 -104.545952) (xy 201.447378 -104.461205)
			(xy 201.446892 -104.418638) (xy 201.447488 -104.372243) (xy 201.457129 -104.279955) (xy 201.476321 -104.189171)
			(xy 201.504856 -104.100877) (xy 201.523092 -104.058212) (xy 201.526875 -104.048263) (xy 201.526889 -104.027006)
			(xy 201.523092 -104.017064) (xy 201.50486 -103.974397) (xy 201.476312 -103.886106) (xy 201.457116 -103.795323)
			(xy 201.447479 -103.703034) (xy 201.446892 -103.656638) (xy 201.447488 -103.610243) (xy 201.457129 -103.517955)
			(xy 201.476321 -103.427171) (xy 201.504856 -103.338877) (xy 201.523092 -103.296212) (xy 201.526875 -103.286263)
			(xy 201.526889 -103.265006) (xy 201.523092 -103.255064) (xy 201.50486 -103.212397) (xy 201.476312 -103.124106)
			(xy 201.457116 -103.033323) (xy 201.447479 -102.941034) (xy 201.446892 -102.894638) (xy 201.447449 -102.853533)
			(xy 201.455029 -102.771674) (xy 201.470129 -102.690863) (xy 201.492619 -102.61179) (xy 201.522308 -102.535128)
			(xy 201.558942 -102.461532) (xy 201.60221 -102.39163) (xy 201.651741 -102.326017) (xy 201.707115 -102.265254)
			(xy 201.767857 -102.209858) (xy 201.833451 -102.160301) (xy 201.903337 -102.117007) (xy 201.976919 -102.080345)
			(xy 202.053569 -102.050627) (xy 202.132634 -102.028106) (xy 202.213439 -102.012976) (xy 202.295295 -102.005364)
			(xy 202.3364 -102.004876) (xy 202.38045 -102.00545) (xy 202.468114 -102.014227) (xy 202.554483 -102.031616)
			(xy 202.638713 -102.057447) (xy 202.679554 -102.073964) (xy 202.688564 -102.077299) (xy 202.707756 -102.077697)
			(xy 202.716892 -102.074726) (xy 202.754276 -102.061238) (xy 202.83092 -102.040197) (xy 202.909137 -102.026086)
			(xy 202.988302 -102.019017) (xy 203.028042 -102.018592) (xy 203.074437 -102.019195) (xy 203.166725 -102.028834)
			(xy 203.257509 -102.048024) (xy 203.345803 -102.076557) (xy 203.388468 -102.094792) (xy 203.39841 -102.098598)
			(xy 203.419674 -102.098598) (xy 203.429616 -102.094792) (xy 203.472273 -102.076533) (xy 203.560567 -102.047993)
			(xy 203.651354 -102.028804) (xy 203.743645 -102.019175) (xy 203.790042 -102.018592) (xy 203.836437 -102.019195)
			(xy 203.928725 -102.028834) (xy 204.019509 -102.048024) (xy 204.107803 -102.076557) (xy 204.150468 -102.094792)
			(xy 204.16041 -102.098598) (xy 204.181674 -102.098598) (xy 204.191616 -102.094792) (xy 204.234273 -102.076533)
			(xy 204.322567 -102.047993) (xy 204.413354 -102.028804) (xy 204.505645 -102.019175) (xy 204.552042 -102.018592)
			(xy 204.598437 -102.019195) (xy 204.690725 -102.028834) (xy 204.781509 -102.048024) (xy 204.869803 -102.076557)
			(xy 204.912468 -102.094792) (xy 204.92241 -102.098598) (xy 204.943674 -102.098598) (xy 204.953616 -102.094792)
			(xy 204.996273 -102.076533) (xy 205.084567 -102.047993) (xy 205.175354 -102.028804) (xy 205.267645 -102.019175)
			(xy 205.314042 -102.018592) (xy 205.360437 -102.019195) (xy 205.452725 -102.028834) (xy 205.543509 -102.048024)
			(xy 205.631803 -102.076557) (xy 205.674468 -102.094792) (xy 205.68441 -102.098598) (xy 205.705674 -102.098598)
			(xy 205.715616 -102.094792) (xy 205.758273 -102.076533) (xy 205.846567 -102.047993) (xy 205.937354 -102.028804)
			(xy 206.029645 -102.019175) (xy 206.076042 -102.018592) (xy 206.122437 -102.019195) (xy 206.214725 -102.028834)
			(xy 206.305509 -102.048024) (xy 206.393803 -102.076557) (xy 206.436468 -102.094792) (xy 206.44641 -102.098598)
			(xy 206.467674 -102.098598) (xy 206.477616 -102.094792) (xy 206.520273 -102.076533) (xy 206.608567 -102.047993)
			(xy 206.699354 -102.028804) (xy 206.791645 -102.019175) (xy 206.838042 -102.018592) (xy 206.879551 -102.019069)
			(xy 206.962209 -102.026787) (xy 207.043788 -102.042181) (xy 207.123575 -102.065115) (xy 207.1624 -102.079806)
			(xy 207.171897 -102.08298) (xy 207.191897 -102.082587) (xy 207.201262 -102.079044) (xy 207.243424 -102.061305)
			(xy 207.330583 -102.033534) (xy 207.420131 -102.014855) (xy 207.511124 -102.005463) (xy 207.556862 -102.004876)
			(xy 207.597969 -102.005349) (xy 207.679833 -102.01293) (xy 207.760649 -102.028032) (xy 207.839727 -102.050525)
			(xy 207.916392 -102.080217) (xy 207.989991 -102.116856) (xy 208.059896 -102.160128) (xy 208.125511 -102.209665)
			(xy 208.186276 -102.265044) (xy 208.241672 -102.325793) (xy 208.291228 -102.391394) (xy 208.334521 -102.461287)
			(xy 208.37118 -102.534875) (xy 208.400895 -102.611532) (xy 208.42341 -102.690604) (xy 208.438535 -102.771415)
			(xy 208.446139 -102.853277) (xy 208.446624 -102.894384) (xy 208.446027 -102.940787) (xy 208.436328 -103.033085)
			(xy 208.417066 -103.12387) (xy 208.38845 -103.212155) (xy 208.37017 -103.25481) (xy 208.366371 -103.264755)
			(xy 208.366365 -103.286016) (xy 208.37017 -103.295958) (xy 208.388427 -103.338621) (xy 208.417021 -103.426908)
			(xy 208.43628 -103.51769) (xy 208.445994 -103.609983) (xy 208.446624 -103.656384) (xy 208.446027 -103.702787)
			(xy 208.436328 -103.795085) (xy 208.417066 -103.88587) (xy 208.38845 -103.974155) (xy 208.37017 -104.01681)
			(xy 208.366371 -104.026755) (xy 208.366365 -104.048016) (xy 208.37017 -104.057958) (xy 208.388427 -104.100621)
			(xy 208.417021 -104.188908) (xy 208.43628 -104.27969) (xy 208.445994 -104.371983) (xy 208.446624 -104.418384)
			(xy 208.446109 -104.460957) (xy 208.437948 -104.545711) (xy 208.421718 -104.629296) (xy 208.397568 -104.710946)
			(xy 208.382108 -104.750616) (xy 208.378875 -104.759874) (xy 208.378863 -104.779464) (xy 208.382108 -104.788716)
			(xy 208.39754 -104.828395) (xy 208.421676 -104.910046) (xy 208.43791 -104.993628) (xy 208.446096 -105.078377)
			(xy 208.446624 -105.120948) (xy 208.446014 -105.167351) (xy 208.436319 -105.259648) (xy 208.417061 -105.350434)
			(xy 208.388448 -105.438718) (xy 208.37017 -105.481374) (xy 208.366333 -105.491307) (xy 208.366351 -105.51258)
			(xy 208.37017 -105.522522) (xy 208.388448 -105.565176) (xy 208.417037 -105.653467) (xy 208.43629 -105.744252)
			(xy 208.445997 -105.836546) (xy 208.446624 -105.882948) (xy 208.446621 -105.883202) (xy 215.929464 -105.883202)
			(xy 215.930093 -105.8368) (xy 215.939782 -105.744503) (xy 215.959035 -105.653717) (xy 215.987643 -105.565432)
			(xy 216.005918 -105.522776) (xy 216.009721 -105.512833) (xy 216.009721 -105.49157) (xy 216.005918 -105.481628)
			(xy 215.987656 -105.438967) (xy 215.959063 -105.350679) (xy 215.939806 -105.259896) (xy 215.930093 -105.167603)
			(xy 215.929464 -105.121202) (xy 215.929976 -105.078629) (xy 215.938138 -104.993875) (xy 215.954369 -104.910289)
			(xy 215.978519 -104.82864) (xy 215.99398 -104.78897) (xy 215.997221 -104.779714) (xy 215.997228 -104.760122)
			(xy 215.99398 -104.75087) (xy 215.978542 -104.711193) (xy 215.954408 -104.629541) (xy 215.938175 -104.545959)
			(xy 215.929991 -104.461209) (xy 215.929464 -104.418638) (xy 215.93007 -104.372235) (xy 215.939766 -104.279937)
			(xy 215.959026 -104.189152) (xy 215.98764 -104.100867) (xy 216.005918 -104.058212) (xy 216.0097 -104.048263)
			(xy 216.009714 -104.027006) (xy 216.005918 -104.017064) (xy 215.987667 -103.974398) (xy 215.959071 -103.886112)
			(xy 215.939811 -103.795331) (xy 215.930095 -103.703039) (xy 215.929464 -103.656638) (xy 215.93007 -103.610235)
			(xy 215.939766 -103.517937) (xy 215.959026 -103.427152) (xy 215.98764 -103.338867) (xy 216.005918 -103.296212)
			(xy 216.0097 -103.286263) (xy 216.009714 -103.265006) (xy 216.005918 -103.255064) (xy 215.987667 -103.212398)
			(xy 215.959071 -103.124112) (xy 215.939811 -103.033331) (xy 215.930095 -102.941039) (xy 215.929464 -102.894638)
			(xy 215.929935 -102.853523) (xy 215.937519 -102.771643) (xy 215.952626 -102.690813) (xy 215.975127 -102.611721)
			(xy 216.00483 -102.535043) (xy 216.041481 -102.461433) (xy 216.084768 -102.391519) (xy 216.134322 -102.325897)
			(xy 216.18972 -102.265128) (xy 216.250488 -102.20973) (xy 216.316109 -102.160175) (xy 216.386023 -102.116887)
			(xy 216.459632 -102.080234) (xy 216.53631 -102.050531) (xy 216.615401 -102.028029) (xy 216.696232 -102.01292)
			(xy 216.778111 -102.005335) (xy 216.819226 -102.004876) (xy 216.863277 -102.005441) (xy 216.950941 -102.014221)
			(xy 217.03731 -102.031612) (xy 217.12154 -102.057446) (xy 217.16238 -102.073964) (xy 217.171386 -102.077313)
			(xy 217.190582 -102.077702) (xy 217.199718 -102.074726) (xy 217.237099 -102.061231) (xy 217.313744 -102.040192)
			(xy 217.391962 -102.026083) (xy 217.471128 -102.019016) (xy 217.510868 -102.018592) (xy 217.557263 -102.019186)
			(xy 217.649551 -102.028828) (xy 217.740335 -102.048021) (xy 217.828629 -102.076556) (xy 217.871294 -102.094792)
			(xy 217.881236 -102.098598) (xy 217.9025 -102.098598) (xy 217.912442 -102.094792) (xy 217.955109 -102.076558)
			(xy 218.043399 -102.048011) (xy 218.134183 -102.028815) (xy 218.226472 -102.019179) (xy 218.272868 -102.018592)
			(xy 218.319263 -102.019186) (xy 218.411551 -102.028828) (xy 218.502335 -102.048021) (xy 218.590629 -102.076556)
			(xy 218.633294 -102.094792) (xy 218.643236 -102.098598) (xy 218.6645 -102.098598) (xy 218.674442 -102.094792)
			(xy 218.717109 -102.076558) (xy 218.805399 -102.048011) (xy 218.896183 -102.028815) (xy 218.988472 -102.019179)
			(xy 219.034868 -102.018592) (xy 219.081263 -102.019186) (xy 219.173551 -102.028828) (xy 219.264335 -102.048021)
			(xy 219.352629 -102.076556) (xy 219.395294 -102.094792) (xy 219.405236 -102.098598) (xy 219.4265 -102.098598)
			(xy 219.436442 -102.094792) (xy 219.479109 -102.076558) (xy 219.567399 -102.048011) (xy 219.658183 -102.028815)
			(xy 219.750472 -102.019179) (xy 219.796868 -102.018592) (xy 219.843263 -102.019186) (xy 219.935551 -102.028828)
			(xy 220.026335 -102.048021) (xy 220.114629 -102.076556) (xy 220.157294 -102.094792) (xy 220.167236 -102.098598)
			(xy 220.1885 -102.098598) (xy 220.198442 -102.094792) (xy 220.241109 -102.076558) (xy 220.329399 -102.048011)
			(xy 220.420183 -102.028815) (xy 220.512472 -102.019179) (xy 220.558868 -102.018592) (xy 220.605263 -102.019186)
			(xy 220.697551 -102.028828) (xy 220.788335 -102.048021) (xy 220.876629 -102.076556) (xy 220.919294 -102.094792)
			(xy 220.929236 -102.098598) (xy 220.9505 -102.098598) (xy 220.960442 -102.094792) (xy 221.003109 -102.076558)
			(xy 221.091399 -102.048011) (xy 221.182183 -102.028815) (xy 221.274472 -102.019179) (xy 221.320868 -102.018592)
			(xy 221.362377 -102.01906) (xy 221.445036 -102.026781) (xy 221.526614 -102.042177) (xy 221.606401 -102.065114)
			(xy 221.645226 -102.079806) (xy 221.654719 -102.082995) (xy 221.674723 -102.082593) (xy 221.684088 -102.079044)
			(xy 221.726247 -102.061296) (xy 221.813407 -102.033528) (xy 221.902956 -102.014851) (xy 221.99395 -102.005462)
			(xy 222.039688 -102.004876) (xy 222.08079 -102.005378) (xy 222.162643 -102.012962) (xy 222.243447 -102.028065)
			(xy 222.322513 -102.05056) (xy 222.399166 -102.080255) (xy 222.472752 -102.116895) (xy 222.542644 -102.160169)
			(xy 222.608245 -102.209706) (xy 222.668995 -102.265086) (xy 222.724376 -102.325834) (xy 222.773916 -102.391433)
			(xy 222.817191 -102.461323) (xy 222.853834 -102.534908) (xy 222.883531 -102.61156) (xy 222.906028 -102.690626)
			(xy 222.921134 -102.771429) (xy 222.928721 -102.853282) (xy 222.929196 -102.894384) (xy 222.928609 -102.940779)
			(xy 222.918965 -103.033068) (xy 222.89977 -103.123852) (xy 222.871233 -103.212145) (xy 222.852996 -103.25481)
			(xy 222.849201 -103.264755) (xy 222.849195 -103.286016) (xy 222.852996 -103.295958) (xy 222.871235 -103.338623)
			(xy 222.899781 -103.426914) (xy 222.918975 -103.517698) (xy 222.92861 -103.609988) (xy 222.929196 -103.656384)
			(xy 222.928609 -103.702779) (xy 222.918965 -103.795068) (xy 222.89977 -103.885852) (xy 222.871233 -103.974145)
			(xy 222.852996 -104.01681) (xy 222.849201 -104.026755) (xy 222.849195 -104.048016) (xy 222.852996 -104.057958)
			(xy 222.871235 -104.100623) (xy 222.899781 -104.188914) (xy 222.918975 -104.279698) (xy 222.92861 -104.371988)
			(xy 222.929196 -104.418384) (xy 222.928713 -104.460951) (xy 222.920608 -104.545698) (xy 222.90444 -104.629282)
			(xy 222.880359 -104.710939) (xy 222.864934 -104.750616) (xy 222.8617 -104.759874) (xy 222.861688 -104.779464)
			(xy 222.864934 -104.788716) (xy 222.880357 -104.828393) (xy 222.904434 -104.910051) (xy 222.908221 -104.929629)
			(xy 270.263616 -104.929629) (xy 270.263616 -104.844907) (xy 270.271669 -104.76057) (xy 270.287703 -104.67738)
			(xy 270.311571 -104.59609) (xy 270.343059 -104.517438) (xy 270.381881 -104.442135) (xy 270.427684 -104.370863)
			(xy 270.480055 -104.304267) (xy 270.53852 -104.242952) (xy 270.602548 -104.187471) (xy 270.67156 -104.138328)
			(xy 270.74493 -104.095968) (xy 270.821995 -104.060773) (xy 270.902057 -104.033064) (xy 270.98439 -104.01309)
			(xy 271.068249 -104.001033) (xy 271.152874 -103.997002) (xy 271.237499 -104.001033) (xy 271.321358 -104.01309)
			(xy 271.403691 -104.033064) (xy 271.483753 -104.060773) (xy 271.560818 -104.095968) (xy 271.634188 -104.138328)
			(xy 271.7032 -104.187471) (xy 271.767228 -104.242952) (xy 271.825693 -104.304267) (xy 271.878064 -104.370863)
			(xy 271.923867 -104.442135) (xy 271.962689 -104.517438) (xy 271.994177 -104.59609) (xy 272.018045 -104.67738)
			(xy 272.034079 -104.76057) (xy 272.042132 -104.844907) (xy 272.042636 -104.887268) (xy 272.042132 -104.929629)
			(xy 272.034079 -105.013966) (xy 272.018045 -105.097156) (xy 271.994177 -105.178446) (xy 271.962689 -105.257098)
			(xy 271.923867 -105.332401) (xy 271.878064 -105.403673) (xy 271.825693 -105.470269) (xy 271.767228 -105.531584)
			(xy 271.7032 -105.587065) (xy 271.634188 -105.636208) (xy 271.560818 -105.678568) (xy 271.483753 -105.713763)
			(xy 271.403691 -105.741472) (xy 271.321358 -105.761446) (xy 271.237499 -105.773503) (xy 271.152874 -105.777535)
			(xy 271.068249 -105.773503) (xy 270.98439 -105.761446) (xy 270.902057 -105.741472) (xy 270.821995 -105.713763)
			(xy 270.74493 -105.678568) (xy 270.67156 -105.636208) (xy 270.602548 -105.587065) (xy 270.53852 -105.531584)
			(xy 270.480055 -105.470269) (xy 270.427684 -105.403673) (xy 270.381881 -105.332401) (xy 270.343059 -105.257098)
			(xy 270.311571 -105.178446) (xy 270.287703 -105.097156) (xy 270.271669 -105.013966) (xy 270.263616 -104.929629)
			(xy 222.908221 -104.929629) (xy 222.920601 -104.993635) (xy 222.92871 -105.078381) (xy 222.929196 -105.120948)
			(xy 222.928596 -105.167343) (xy 222.918956 -105.259631) (xy 222.899765 -105.350415) (xy 222.871232 -105.438709)
			(xy 222.852996 -105.481374) (xy 222.849163 -105.491308) (xy 222.849181 -105.512579) (xy 222.852996 -105.522522)
			(xy 222.871223 -105.565192) (xy 222.899772 -105.653481) (xy 222.91897 -105.744264) (xy 222.928608 -105.836553)
			(xy 222.929196 -105.882948) (xy 222.928779 -105.924052) (xy 222.92119 -106.005908) (xy 222.90608 -106.086715)
			(xy 222.883579 -106.165783) (xy 222.853879 -106.242437) (xy 222.817233 -106.316025) (xy 222.773954 -106.385917)
			(xy 222.761182 -106.402829) (xy 268.600678 -106.402829) (xy 268.600678 -106.318107) (xy 268.608731 -106.23377)
			(xy 268.624765 -106.15058) (xy 268.648633 -106.06929) (xy 268.680121 -105.990638) (xy 268.718943 -105.915335)
			(xy 268.764746 -105.844063) (xy 268.817117 -105.777467) (xy 268.875582 -105.716152) (xy 268.93961 -105.660671)
			(xy 269.008622 -105.611528) (xy 269.081992 -105.569168) (xy 269.159057 -105.533973) (xy 269.239119 -105.506264)
			(xy 269.321452 -105.48629) (xy 269.405311 -105.474233) (xy 269.489936 -105.470202) (xy 269.574561 -105.474233)
			(xy 269.65842 -105.48629) (xy 269.740753 -105.506264) (xy 269.820815 -105.533973) (xy 269.89788 -105.569168)
			(xy 269.97125 -105.611528) (xy 270.040262 -105.660671) (xy 270.10429 -105.716152) (xy 270.162755 -105.777467)
			(xy 270.215126 -105.844063) (xy 270.260929 -105.915335) (xy 270.299751 -105.990638) (xy 270.331239 -106.06929)
			(xy 270.355107 -106.15058) (xy 270.371141 -106.23377) (xy 270.379194 -106.318107) (xy 270.379698 -106.360468)
			(xy 270.379194 -106.402829) (xy 270.371141 -106.487166) (xy 270.355107 -106.570356) (xy 270.331239 -106.651646)
			(xy 270.299751 -106.730298) (xy 270.260929 -106.805601) (xy 270.215126 -106.876873) (xy 270.162755 -106.943469)
			(xy 270.10429 -107.004784) (xy 270.040262 -107.060265) (xy 269.97125 -107.109408) (xy 269.89788 -107.151768)
			(xy 269.820815 -107.186963) (xy 269.740753 -107.214672) (xy 269.65842 -107.234646) (xy 269.574561 -107.246703)
			(xy 269.489936 -107.250735) (xy 269.405311 -107.246703) (xy 269.321452 -107.234646) (xy 269.239119 -107.214672)
			(xy 269.159057 -107.186963) (xy 269.081992 -107.151768) (xy 269.008622 -107.109408) (xy 268.93961 -107.060265)
			(xy 268.875582 -107.004784) (xy 268.817117 -106.943469) (xy 268.764746 -106.876873) (xy 268.718943 -106.805601)
			(xy 268.680121 -106.730298) (xy 268.648633 -106.651646) (xy 268.624765 -106.570356) (xy 268.608731 -106.487166)
			(xy 268.600678 -106.402829) (xy 222.761182 -106.402829) (xy 222.724411 -106.451518) (xy 222.669026 -106.512268)
			(xy 222.608272 -106.567649) (xy 222.542668 -106.617188) (xy 222.472772 -106.660463) (xy 222.399183 -106.697104)
			(xy 222.322526 -106.726799) (xy 222.243456 -106.749294) (xy 222.162648 -106.764398) (xy 222.080792 -106.771982)
			(xy 222.039688 -106.772456) (xy 221.998179 -106.771973) (xy 221.915521 -106.764257) (xy 221.833943 -106.748865)
			(xy 221.754155 -106.725932) (xy 221.71533 -106.711242) (xy 221.705829 -106.708082) (xy 221.685833 -106.708464)
			(xy 221.676468 -106.712004) (xy 221.634314 -106.729763) (xy 221.547152 -106.757529) (xy 221.457601 -106.776203)
			(xy 221.366607 -106.785588) (xy 221.320868 -106.786172) (xy 221.274473 -106.785568) (xy 221.182185 -106.77593)
			(xy 221.091401 -106.75674) (xy 221.003107 -106.728207) (xy 220.960442 -106.709972) (xy 220.9505 -106.706166)
			(xy 220.929236 -106.706166) (xy 220.919294 -106.709972) (xy 220.876635 -106.728225) (xy 220.788342 -106.756768)
			(xy 220.697556 -106.775958) (xy 220.605264 -106.785589) (xy 220.558868 -106.786172) (xy 220.512473 -106.785568)
			(xy 220.420185 -106.77593) (xy 220.329401 -106.75674) (xy 220.241107 -106.728207) (xy 220.198442 -106.709972)
			(xy 220.1885 -106.706166) (xy 220.167236 -106.706166) (xy 220.157294 -106.709972) (xy 220.114635 -106.728225)
			(xy 220.026342 -106.756768) (xy 219.935556 -106.775958) (xy 219.843264 -106.785589) (xy 219.796868 -106.786172)
			(xy 219.750473 -106.785568) (xy 219.658185 -106.77593) (xy 219.567401 -106.75674) (xy 219.479107 -106.728207)
			(xy 219.436442 -106.709972) (xy 219.4265 -106.706166) (xy 219.405236 -106.706166) (xy 219.395294 -106.709972)
			(xy 219.352635 -106.728225) (xy 219.264342 -106.756768) (xy 219.173556 -106.775958) (xy 219.081264 -106.785589)
			(xy 219.034868 -106.786172) (xy 218.988473 -106.785568) (xy 218.896185 -106.77593) (xy 218.805401 -106.75674)
			(xy 218.717107 -106.728207) (xy 218.674442 -106.709972) (xy 218.6645 -106.706166) (xy 218.643236 -106.706166)
			(xy 218.633294 -106.709972) (xy 218.590635 -106.728225) (xy 218.502342 -106.756768) (xy 218.411556 -106.775958)
			(xy 218.319264 -106.785589) (xy 218.272868 -106.786172) (xy 218.226473 -106.785568) (xy 218.134185 -106.77593)
			(xy 218.043401 -106.75674) (xy 217.955107 -106.728207) (xy 217.912442 -106.709972) (xy 217.9025 -106.706166)
			(xy 217.881236 -106.706166) (xy 217.871294 -106.709972) (xy 217.828635 -106.728225) (xy 217.740342 -106.756768)
			(xy 217.649556 -106.775958) (xy 217.557264 -106.785589) (xy 217.510868 -106.786172) (xy 217.466823 -106.785646)
			(xy 217.379163 -106.776938) (xy 217.292793 -106.759609) (xy 217.208558 -106.733831) (xy 217.167714 -106.717338)
			(xy 217.158709 -106.713986) (xy 217.139512 -106.713599) (xy 217.130376 -106.716576) (xy 217.093 -106.7301)
			(xy 217.016359 -106.751198) (xy 216.938142 -106.765371) (xy 216.858971 -106.772505) (xy 216.819226 -106.772964)
			(xy 216.778112 -106.772477) (xy 216.696233 -106.764892) (xy 216.615404 -106.749785) (xy 216.536314 -106.727283)
			(xy 216.459637 -106.697581) (xy 216.386028 -106.66093) (xy 216.316115 -106.617643) (xy 216.250494 -106.568091)
			(xy 216.189725 -106.512694) (xy 216.134327 -106.451927) (xy 216.084773 -106.386308) (xy 216.041484 -106.316396)
			(xy 216.004831 -106.242788) (xy 215.975125 -106.166113) (xy 215.952622 -106.087023) (xy 215.937512 -106.006194)
			(xy 215.929925 -105.924316) (xy 215.929464 -105.883202) (xy 208.446621 -105.883202) (xy 208.446193 -105.924059)
			(xy 208.438601 -106.00593) (xy 208.423487 -106.08675) (xy 208.400978 -106.165831) (xy 208.371268 -106.242498)
			(xy 208.33461 -106.316096) (xy 208.291317 -106.385997) (xy 208.241758 -106.451604) (xy 208.186356 -106.512358)
			(xy 208.125584 -106.567741) (xy 208.059961 -106.617279) (xy 207.990046 -106.66055) (xy 207.916436 -106.697184)
			(xy 207.83976 -106.726869) (xy 207.760672 -106.749352) (xy 207.679846 -106.764441) (xy 207.597973 -106.772007)
			(xy 207.556862 -106.772456) (xy 207.515353 -106.771982) (xy 207.432694 -106.764263) (xy 207.351116 -106.748869)
			(xy 207.271329 -106.725933) (xy 207.232504 -106.711242) (xy 207.223007 -106.708067) (xy 207.203007 -106.708459)
			(xy 207.193642 -106.712004) (xy 207.151478 -106.729739) (xy 207.06432 -106.757511) (xy 206.974772 -106.776192)
			(xy 206.88378 -106.785585) (xy 206.838042 -106.786172) (xy 206.791647 -106.785577) (xy 206.699359 -106.775936)
			(xy 206.608575 -106.756744) (xy 206.520281 -106.728209) (xy 206.477616 -106.709972) (xy 206.467674 -106.706166)
			(xy 206.44641 -106.706166) (xy 206.436468 -106.709972) (xy 206.393799 -106.728201) (xy 206.305509 -106.756749)
			(xy 206.214726 -106.775947) (xy 206.122438 -106.785585) (xy 206.076042 -106.786172) (xy 206.029647 -106.785577)
			(xy 205.937359 -106.775936) (xy 205.846575 -106.756744) (xy 205.758281 -106.728209) (xy 205.715616 -106.709972)
			(xy 205.705674 -106.706166) (xy 205.68441 -106.706166) (xy 205.674468 -106.709972) (xy 205.631799 -106.728201)
			(xy 205.543509 -106.756749) (xy 205.452726 -106.775947) (xy 205.360438 -106.785585) (xy 205.314042 -106.786172)
			(xy 205.267647 -106.785577) (xy 205.175359 -106.775936) (xy 205.084575 -106.756744) (xy 204.996281 -106.728209)
			(xy 204.953616 -106.709972) (xy 204.943674 -106.706166) (xy 204.92241 -106.706166) (xy 204.912468 -106.709972)
			(xy 204.869799 -106.728201) (xy 204.781509 -106.756749) (xy 204.690726 -106.775947) (xy 204.598438 -106.785585)
			(xy 204.552042 -106.786172) (xy 204.505647 -106.785577) (xy 204.413359 -106.775936) (xy 204.322575 -106.756744)
			(xy 204.234281 -106.728209) (xy 204.191616 -106.709972) (xy 204.181674 -106.706166) (xy 204.16041 -106.706166)
			(xy 204.150468 -106.709972) (xy 204.107799 -106.728201) (xy 204.019509 -106.756749) (xy 203.928726 -106.775947)
			(xy 203.836438 -106.785585) (xy 203.790042 -106.786172) (xy 203.743647 -106.785577) (xy 203.651359 -106.775936)
			(xy 203.560575 -106.756744) (xy 203.472281 -106.728209) (xy 203.429616 -106.709972) (xy 203.419674 -106.706166)
			(xy 203.39841 -106.706166) (xy 203.388468 -106.709972) (xy 203.345799 -106.728201) (xy 203.257509 -106.756749)
			(xy 203.166726 -106.775947) (xy 203.074438 -106.785585) (xy 203.028042 -106.786172) (xy 202.983997 -106.785621)
			(xy 202.896338 -106.77692) (xy 202.809969 -106.759599) (xy 202.725733 -106.733828) (xy 202.684888 -106.717338)
			(xy 202.675887 -106.713972) (xy 202.656687 -106.713594) (xy 202.64755 -106.716576) (xy 202.610166 -106.730079)
			(xy 202.533529 -106.751183) (xy 202.455313 -106.765361) (xy 202.376145 -106.772501) (xy 202.3364 -106.772964)
			(xy 202.295288 -106.772547) (xy 202.213415 -106.764959) (xy 202.132592 -106.749847) (xy 202.053508 -106.727341)
			(xy 201.976839 -106.697632) (xy 201.903239 -106.660975) (xy 201.833336 -106.617681) (xy 201.767727 -106.568121)
			(xy 201.706971 -106.512718) (xy 201.651588 -106.451944) (xy 201.60205 -106.386318) (xy 201.55878 -106.316401)
			(xy 201.522147 -106.242788) (xy 201.492464 -106.166109) (xy 201.469984 -106.087018) (xy 201.4549 -106.00619)
			(xy 201.447339 -105.924314) (xy 201.446892 -105.883202) (xy 42.525034 -105.883202) (xy 42.53529 -105.931714)
			(xy 42.544923 -106.024004) (xy 42.545508 -106.0704) (xy 42.544925 -106.116796) (xy 42.53528 -106.209084)
			(xy 42.516084 -106.299868) (xy 42.487546 -106.388161) (xy 42.469308 -106.430826) (xy 42.465403 -106.440748)
			(xy 42.465403 -106.462052) (xy 42.469308 -106.471974) (xy 42.487553 -106.514636) (xy 42.516097 -106.602929)
			(xy 42.53529 -106.693714) (xy 42.544923 -106.786004) (xy 42.545508 -106.8324) (xy 42.544974 -106.876652)
			(xy 42.53619 -106.964719) (xy 42.51871 -107.05148) (xy 42.492705 -107.136077) (xy 42.458433 -107.217676)
			(xy 42.437812 -107.256834) (xy 42.432976 -107.266759) (xy 42.431544 -107.28877) (xy 42.435018 -107.299252)
			(xy 42.449342 -107.337668) (xy 42.471714 -107.416549) (xy 42.486727 -107.497156) (xy 42.494251 -107.578803)
			(xy 42.494708 -107.6198) (xy 42.494125 -107.666196) (xy 42.48448 -107.758484) (xy 42.465284 -107.849268)
			(xy 42.436746 -107.937561) (xy 42.418508 -107.980226) (xy 42.414603 -107.990148) (xy 42.414603 -108.011452)
			(xy 42.418508 -108.021374) (xy 42.436753 -108.064036) (xy 42.465297 -108.152329) (xy 42.48449 -108.243114)
			(xy 42.494123 -108.335404) (xy 42.494708 -108.3818) (xy 42.494233 -108.422902) (xy 42.486648 -108.504757)
			(xy 42.471543 -108.585562) (xy 42.449047 -108.664629) (xy 42.419351 -108.741283) (xy 42.382709 -108.81487)
			(xy 42.339434 -108.884762) (xy 42.289894 -108.950363) (xy 42.234513 -109.011113) (xy 42.173763 -109.066494)
			(xy 42.108162 -109.116034) (xy 42.03827 -109.159309) (xy 41.964683 -109.195951) (xy 41.888029 -109.225647)
			(xy 41.808962 -109.248143) (xy 41.728157 -109.263248) (xy 41.646302 -109.270833) (xy 41.6052 -109.271308)
			(xy 41.558821 -109.270703) (xy 41.466567 -109.261053) (xy 41.375818 -109.241858) (xy 41.287558 -109.213327)
			(xy 41.202745 -109.175768) (xy 41.162224 -109.153198) (xy 41.150947 -109.147546) (xy 41.125768 -109.146863)
			(xy 41.114218 -109.151928) (xy 41.077098 -109.169978) (xy 41.000167 -109.199902) (xy 40.920795 -109.222573)
			(xy 40.839665 -109.237796) (xy 40.757473 -109.24544) (xy 40.7162 -109.245908) (xy 40.672407 -109.245348)
			(xy 40.585246 -109.236718) (xy 40.499354 -109.219572) (xy 40.41556 -109.194075) (xy 40.334675 -109.160474)
			(xy 40.29583 -109.140244) (xy 40.284364 -109.134826) (xy 40.259036 -109.134826) (xy 40.24757 -109.140244)
			(xy 40.208728 -109.160483) (xy 40.127852 -109.194119) (xy 40.044059 -109.219632) (xy 39.958163 -109.236777)
			(xy 39.870996 -109.245387) (xy 39.8272 -109.245908) (xy 39.786098 -109.245433) (xy 39.704243 -109.237848)
			(xy 39.623438 -109.222743) (xy 39.544371 -109.200247) (xy 39.467717 -109.170551) (xy 39.39413 -109.133909)
			(xy 39.324238 -109.090634) (xy 39.258637 -109.041094) (xy 39.197887 -108.985713) (xy 39.142506 -108.924963)
			(xy 39.092966 -108.859362) (xy 39.049691 -108.78947) (xy 39.013049 -108.715883) (xy 38.983353 -108.639229)
			(xy 38.960857 -108.560162) (xy 38.945752 -108.479357) (xy 38.938167 -108.397502) (xy 38.937692 -108.3564)
			(xy 32.131508 -108.3564) (xy 32.131033 -108.397502) (xy 32.123448 -108.479357) (xy 32.108343 -108.560162)
			(xy 32.085847 -108.639229) (xy 32.056151 -108.715883) (xy 32.019509 -108.78947) (xy 31.976234 -108.859362)
			(xy 31.926694 -108.924963) (xy 31.871313 -108.985713) (xy 31.810563 -109.041094) (xy 31.744962 -109.090634)
			(xy 31.67507 -109.133909) (xy 31.601483 -109.170551) (xy 31.524829 -109.200247) (xy 31.445762 -109.222743)
			(xy 31.364957 -109.237848) (xy 31.283102 -109.245433) (xy 31.242 -109.245908) (xy 31.198207 -109.245348)
			(xy 31.111046 -109.236718) (xy 31.025154 -109.219572) (xy 30.94136 -109.194075) (xy 30.860475 -109.160474)
			(xy 30.82163 -109.140244) (xy 30.810164 -109.134826) (xy 30.784836 -109.134826) (xy 30.77337 -109.140244)
			(xy 30.734528 -109.160483) (xy 30.653652 -109.194119) (xy 30.569859 -109.219632) (xy 30.483963 -109.236777)
			(xy 30.396796 -109.245387) (xy 30.353 -109.245908) (xy 30.307377 -109.245294) (xy 30.216612 -109.235924)
			(xy 30.127284 -109.217312) (xy 30.040329 -109.189655) (xy 29.956662 -109.153242) (xy 29.916628 -109.131354)
			(xy 29.908405 -109.127232) (xy 29.890238 -109.12446) (xy 29.872258 -109.128261) (xy 29.864304 -109.132878)
			(xy 29.82866 -109.154937) (xy 29.753965 -109.19299) (xy 29.67602 -109.223846) (xy 29.595518 -109.247231)
			(xy 29.513173 -109.262937) (xy 29.429715 -109.270825) (xy 29.3878 -109.271308) (xy 29.346698 -109.270833)
			(xy 29.264843 -109.263248) (xy 29.184038 -109.248143) (xy 29.104971 -109.225647) (xy 29.028317 -109.195951)
			(xy 28.95473 -109.159309) (xy 28.884838 -109.116034) (xy 28.819237 -109.066494) (xy 28.758487 -109.011113)
			(xy 28.703106 -108.950363) (xy 28.653566 -108.884762) (xy 28.610291 -108.81487) (xy 28.573649 -108.741283)
			(xy 28.543953 -108.664629) (xy 28.521457 -108.585562) (xy 28.506352 -108.504757) (xy 28.498767 -108.422902)
			(xy 28.498292 -108.3818) (xy 0.509016 -108.3818) (xy 0.509016 -112.268) (xy 141.857988 -112.268)
			(xy 141.862018 -112.183399) (xy 141.874071 -112.099564) (xy 141.894039 -112.017255) (xy 141.921741 -111.937216)
			(xy 141.956925 -111.860173) (xy 141.999274 -111.786823) (xy 142.048403 -111.717831) (xy 142.103868 -111.653821)
			(xy 142.165166 -111.595373) (xy 142.231742 -111.543017) (xy 142.302994 -111.497227) (xy 142.378275 -111.458416)
			(xy 142.456905 -111.426937) (xy 142.538172 -111.403076) (xy 142.621338 -111.387047) (xy 142.705652 -111.378996)
			(xy 142.748 -111.378492) (xy 142.786284 -111.37888) (xy 142.862573 -111.385419) (xy 142.938015 -111.3985)
			(xy 143.012052 -111.418027) (xy 143.048228 -111.430562) (xy 143.056665 -111.433213) (xy 143.074335 -111.433213)
			(xy 143.082772 -111.430562) (xy 143.11895 -111.418037) (xy 143.19299 -111.398529) (xy 143.268431 -111.385449)
			(xy 143.344717 -111.378894) (xy 143.383 -111.378492) (xy 143.425348 -111.378996) (xy 143.509662 -111.387047)
			(xy 143.592828 -111.403076) (xy 143.674095 -111.426937) (xy 143.752725 -111.458416) (xy 143.828006 -111.497227)
			(xy 143.899258 -111.543017) (xy 143.965834 -111.595373) (xy 144.027132 -111.653821) (xy 144.082597 -111.717831)
			(xy 144.131726 -111.786823) (xy 144.174075 -111.860173) (xy 144.209259 -111.937216) (xy 144.236961 -112.017255)
			(xy 144.256929 -112.099564) (xy 144.268982 -112.183399) (xy 144.273013 -112.268) (xy 144.268982 -112.352601)
			(xy 144.256929 -112.436436) (xy 144.236961 -112.518745) (xy 144.209259 -112.598784) (xy 144.174075 -112.675827)
			(xy 144.131726 -112.749177) (xy 144.082597 -112.818169) (xy 144.027132 -112.882179) (xy 143.965834 -112.940627)
			(xy 143.899258 -112.992983) (xy 143.828006 -113.038773) (xy 143.752725 -113.077584) (xy 143.674095 -113.109063)
			(xy 143.592828 -113.132924) (xy 143.509662 -113.148953) (xy 143.425348 -113.157004) (xy 143.383 -113.157508)
			(xy 143.344716 -113.15712) (xy 143.268427 -113.150581) (xy 143.192985 -113.1375) (xy 143.118948 -113.117973)
			(xy 143.082772 -113.105438) (xy 143.074335 -113.102787) (xy 143.056665 -113.102787) (xy 143.048228 -113.105438)
			(xy 143.01205 -113.117963) (xy 142.93801 -113.137471) (xy 142.862569 -113.150551) (xy 142.786283 -113.157106)
			(xy 142.748 -113.157508) (xy 142.705652 -113.157004) (xy 142.621338 -113.148953) (xy 142.538172 -113.132924)
			(xy 142.456905 -113.109063) (xy 142.378275 -113.077584) (xy 142.302994 -113.038773) (xy 142.231742 -112.992983)
			(xy 142.165166 -112.940627) (xy 142.103868 -112.882179) (xy 142.048403 -112.818169) (xy 141.999274 -112.749177)
			(xy 141.956925 -112.675827) (xy 141.921741 -112.598784) (xy 141.894039 -112.518745) (xy 141.874071 -112.436436)
			(xy 141.862018 -112.352601) (xy 141.857988 -112.268) (xy 0.509016 -112.268) (xy 0.509016 -113.229898)
			(xy 0.509506 -113.299774) (xy 0.517342 -113.439307) (xy 0.53299 -113.578181) (xy 0.556399 -113.715959)
			(xy 0.573755 -113.792) (xy 268.350492 -113.792) (xy 268.351075 -113.745604) (xy 268.36072 -113.653316)
			(xy 268.379916 -113.562532) (xy 268.408454 -113.474239) (xy 268.426692 -113.431574) (xy 268.430498 -113.421632)
			(xy 268.430498 -113.400368) (xy 268.426692 -113.390426) (xy 268.408447 -113.347764) (xy 268.379903 -113.259471)
			(xy 268.36071 -113.168686) (xy 268.351077 -113.076396) (xy 268.350492 -113.03) (xy 268.351075 -112.983604)
			(xy 268.36072 -112.891316) (xy 268.379916 -112.800532) (xy 268.408454 -112.712239) (xy 268.426692 -112.669574)
			(xy 268.430498 -112.659632) (xy 268.430498 -112.638368) (xy 268.426692 -112.628426) (xy 268.408447 -112.585764)
			(xy 268.379903 -112.497471) (xy 268.36071 -112.406686) (xy 268.351077 -112.314396) (xy 268.350492 -112.268)
			(xy 268.351075 -112.221604) (xy 268.36072 -112.129316) (xy 268.379916 -112.038532) (xy 268.408454 -111.950239)
			(xy 268.426692 -111.907574) (xy 268.430498 -111.897632) (xy 268.430498 -111.876368) (xy 268.426692 -111.866426)
			(xy 268.408447 -111.823764) (xy 268.379903 -111.735471) (xy 268.36071 -111.644686) (xy 268.351077 -111.552396)
			(xy 268.350492 -111.506) (xy 268.351075 -111.459604) (xy 268.36072 -111.367316) (xy 268.379916 -111.276532)
			(xy 268.408454 -111.188239) (xy 268.426692 -111.145574) (xy 268.430498 -111.135632) (xy 268.430498 -111.114368)
			(xy 268.426692 -111.104426) (xy 268.408447 -111.061764) (xy 268.379903 -110.973471) (xy 268.36071 -110.882686)
			(xy 268.351077 -110.790396) (xy 268.350492 -110.744) (xy 268.351075 -110.697604) (xy 268.36072 -110.605316)
			(xy 268.379916 -110.514532) (xy 268.408454 -110.426239) (xy 268.426692 -110.383574) (xy 268.430498 -110.373632)
			(xy 268.430498 -110.352368) (xy 268.426692 -110.342426) (xy 268.408447 -110.299764) (xy 268.379903 -110.211471)
			(xy 268.36071 -110.120686) (xy 268.351077 -110.028396) (xy 268.350492 -109.982) (xy 268.350967 -109.940898)
			(xy 268.358552 -109.859043) (xy 268.373657 -109.778238) (xy 268.396153 -109.699171) (xy 268.425849 -109.622517)
			(xy 268.462491 -109.54893) (xy 268.505766 -109.479038) (xy 268.555306 -109.413437) (xy 268.610687 -109.352687)
			(xy 268.671437 -109.297306) (xy 268.737038 -109.247766) (xy 268.80693 -109.204491) (xy 268.880517 -109.167849)
			(xy 268.957171 -109.138153) (xy 269.036238 -109.115657) (xy 269.117043 -109.100552) (xy 269.198898 -109.092967)
			(xy 269.24 -109.092492) (xy 269.286396 -109.093075) (xy 269.378684 -109.10272) (xy 269.469468 -109.121916)
			(xy 269.557761 -109.150454) (xy 269.600426 -109.168692) (xy 269.610368 -109.172498) (xy 269.631632 -109.172498)
			(xy 269.641574 -109.168692) (xy 269.684236 -109.150447) (xy 269.772529 -109.121903) (xy 269.863314 -109.10271)
			(xy 269.955604 -109.093077) (xy 270.002 -109.092492) (xy 270.048396 -109.093075) (xy 270.140684 -109.10272)
			(xy 270.231468 -109.121916) (xy 270.319761 -109.150454) (xy 270.362426 -109.168692) (xy 270.372368 -109.172498)
			(xy 270.393632 -109.172498) (xy 270.403574 -109.168692) (xy 270.446236 -109.150447) (xy 270.534529 -109.121903)
			(xy 270.625314 -109.10271) (xy 270.717604 -109.093077) (xy 270.764 -109.092492) (xy 270.810396 -109.093075)
			(xy 270.902684 -109.10272) (xy 270.993468 -109.121916) (xy 271.081761 -109.150454) (xy 271.124426 -109.168692)
			(xy 271.134368 -109.172498) (xy 271.155632 -109.172498) (xy 271.165574 -109.168692) (xy 271.208236 -109.150447)
			(xy 271.296529 -109.121903) (xy 271.387314 -109.10271) (xy 271.479604 -109.093077) (xy 271.526 -109.092492)
			(xy 271.572396 -109.093075) (xy 271.664684 -109.10272) (xy 271.755468 -109.121916) (xy 271.843761 -109.150454)
			(xy 271.886426 -109.168692) (xy 271.896368 -109.172498) (xy 271.917632 -109.172498) (xy 271.927574 -109.168692)
			(xy 271.970236 -109.150447) (xy 272.058529 -109.121903) (xy 272.149314 -109.10271) (xy 272.241604 -109.093077)
			(xy 272.288 -109.092492) (xy 272.329102 -109.092967) (xy 272.410957 -109.100552) (xy 272.491762 -109.115657)
			(xy 272.570829 -109.138153) (xy 272.647483 -109.167849) (xy 272.72107 -109.204491) (xy 272.790962 -109.247766)
			(xy 272.856563 -109.297306) (xy 272.917313 -109.352687) (xy 272.972694 -109.413437) (xy 273.022234 -109.479038)
			(xy 273.065509 -109.54893) (xy 273.102151 -109.622517) (xy 273.131847 -109.699171) (xy 273.154343 -109.778238)
			(xy 273.169448 -109.859043) (xy 273.177033 -109.940898) (xy 273.177508 -109.982) (xy 273.176925 -110.028396)
			(xy 273.16728 -110.120684) (xy 273.148084 -110.211468) (xy 273.119546 -110.299761) (xy 273.101308 -110.342426)
			(xy 273.097502 -110.352368) (xy 273.097502 -110.373632) (xy 273.101308 -110.383574) (xy 273.119553 -110.426236)
			(xy 273.148097 -110.514529) (xy 273.16729 -110.605314) (xy 273.176923 -110.697604) (xy 273.177508 -110.744)
			(xy 273.177033 -110.785102) (xy 273.169448 -110.866957) (xy 273.154343 -110.947762) (xy 273.131847 -111.026829)
			(xy 273.102151 -111.103483) (xy 273.065509 -111.17707) (xy 273.022234 -111.246962) (xy 272.972694 -111.312563)
			(xy 272.917313 -111.373313) (xy 272.856563 -111.428694) (xy 272.790962 -111.478234) (xy 272.72107 -111.521509)
			(xy 272.647483 -111.558151) (xy 272.570829 -111.587847) (xy 272.491762 -111.610343) (xy 272.410957 -111.625448)
			(xy 272.329102 -111.633033) (xy 272.288 -111.633508) (xy 272.241604 -111.632925) (xy 272.149316 -111.62328)
			(xy 272.058532 -111.604084) (xy 271.970239 -111.575546) (xy 271.927574 -111.557308) (xy 271.917632 -111.553502)
			(xy 271.896368 -111.553502) (xy 271.886426 -111.557308) (xy 271.853507 -111.571537) (xy 271.785822 -111.595257)
			(xy 271.716442 -111.613437) (xy 271.681194 -111.620046) (xy 271.67107 -111.622344) (xy 271.653749 -111.633749)
			(xy 271.642344 -111.65107) (xy 271.640046 -111.661194) (xy 271.633416 -111.696437) (xy 271.61522 -111.76581)
			(xy 271.591513 -111.833498) (xy 271.577308 -111.866426) (xy 271.573502 -111.876368) (xy 271.573502 -111.897632)
			(xy 271.577308 -111.907574) (xy 271.591537 -111.940493) (xy 271.615257 -112.008178) (xy 271.633437 -112.077558)
			(xy 271.640046 -112.112806) (xy 271.642344 -112.12293) (xy 271.653749 -112.140251) (xy 271.67107 -112.151656)
			(xy 271.681194 -112.153954) (xy 271.716437 -112.160584) (xy 271.78581 -112.17878) (xy 271.853498 -112.202487)
			(xy 271.886426 -112.216692) (xy 271.896368 -112.220498) (xy 271.917632 -112.220498) (xy 271.927574 -112.216692)
			(xy 271.970236 -112.198447) (xy 272.058529 -112.169903) (xy 272.149314 -112.15071) (xy 272.241604 -112.141077)
			(xy 272.288 -112.140492) (xy 272.329102 -112.140967) (xy 272.410957 -112.148552) (xy 272.491762 -112.163657)
			(xy 272.570829 -112.186153) (xy 272.647483 -112.215849) (xy 272.72107 -112.252491) (xy 272.790962 -112.295766)
			(xy 272.856563 -112.345306) (xy 272.917313 -112.400687) (xy 272.972694 -112.461437) (xy 273.022234 -112.527038)
			(xy 273.065509 -112.59693) (xy 273.102151 -112.670517) (xy 273.131847 -112.747171) (xy 273.154343 -112.826238)
			(xy 273.169448 -112.907043) (xy 273.177033 -112.988898) (xy 273.177508 -113.03) (xy 273.176925 -113.076396)
			(xy 273.16728 -113.168684) (xy 273.148084 -113.259468) (xy 273.119546 -113.347761) (xy 273.101308 -113.390426)
			(xy 273.097502 -113.400368) (xy 273.097502 -113.421632) (xy 273.101308 -113.431574) (xy 273.119553 -113.474236)
			(xy 273.148097 -113.562529) (xy 273.16729 -113.653314) (xy 273.176923 -113.745604) (xy 273.177508 -113.792)
			(xy 273.177033 -113.833102) (xy 273.169448 -113.914957) (xy 273.154343 -113.995762) (xy 273.131847 -114.074829)
			(xy 273.102151 -114.151483) (xy 273.065509 -114.22507) (xy 273.022234 -114.294962) (xy 272.972694 -114.360563)
			(xy 272.917313 -114.421313) (xy 272.856563 -114.476694) (xy 272.790962 -114.526234) (xy 272.72107 -114.569509)
			(xy 272.647483 -114.606151) (xy 272.570829 -114.635847) (xy 272.491762 -114.658343) (xy 272.410957 -114.673448)
			(xy 272.329102 -114.681033) (xy 272.288 -114.681508) (xy 272.241604 -114.680925) (xy 272.149316 -114.67128)
			(xy 272.058532 -114.652084) (xy 271.970239 -114.623546) (xy 271.927574 -114.605308) (xy 271.917632 -114.601502)
			(xy 271.896368 -114.601502) (xy 271.886426 -114.605308) (xy 271.843764 -114.623553) (xy 271.755471 -114.652097)
			(xy 271.664686 -114.67129) (xy 271.572396 -114.680923) (xy 271.526 -114.681508) (xy 271.479604 -114.680925)
			(xy 271.387316 -114.67128) (xy 271.296532 -114.652084) (xy 271.208239 -114.623546) (xy 271.165574 -114.605308)
			(xy 271.155632 -114.601502) (xy 271.134368 -114.601502) (xy 271.124426 -114.605308) (xy 271.081764 -114.623553)
			(xy 270.993471 -114.652097) (xy 270.902686 -114.67129) (xy 270.810396 -114.680923) (xy 270.764 -114.681508)
			(xy 270.717604 -114.680925) (xy 270.625316 -114.67128) (xy 270.534532 -114.652084) (xy 270.446239 -114.623546)
			(xy 270.403574 -114.605308) (xy 270.393632 -114.601502) (xy 270.372368 -114.601502) (xy 270.362426 -114.605308)
			(xy 270.319764 -114.623553) (xy 270.231471 -114.652097) (xy 270.140686 -114.67129) (xy 270.048396 -114.680923)
			(xy 270.002 -114.681508) (xy 269.955604 -114.680925) (xy 269.863316 -114.67128) (xy 269.772532 -114.652084)
			(xy 269.684239 -114.623546) (xy 269.641574 -114.605308) (xy 269.631632 -114.601502) (xy 269.610368 -114.601502)
			(xy 269.600426 -114.605308) (xy 269.557764 -114.623553) (xy 269.469471 -114.652097) (xy 269.378686 -114.67129)
			(xy 269.286396 -114.680923) (xy 269.24 -114.681508) (xy 269.198898 -114.681033) (xy 269.117043 -114.673448)
			(xy 269.036238 -114.658343) (xy 268.957171 -114.635847) (xy 268.880517 -114.606151) (xy 268.80693 -114.569509)
			(xy 268.737038 -114.526234) (xy 268.671437 -114.476694) (xy 268.610687 -114.421313) (xy 268.555306 -114.360563)
			(xy 268.505766 -114.294962) (xy 268.462491 -114.22507) (xy 268.425849 -114.151483) (xy 268.396153 -114.074829)
			(xy 268.373657 -113.995762) (xy 268.358552 -113.914957) (xy 268.350967 -113.833102) (xy 268.350492 -113.792)
			(xy 0.573755 -113.792) (xy 0.587497 -113.852208) (xy 0.626186 -113.986499) (xy 0.672343 -114.118409)
			(xy 0.725824 -114.247524) (xy 0.78646 -114.373436) (xy 0.854061 -114.495751) (xy 0.928414 -114.614083)
			(xy 1.009285 -114.72806) (xy 1.09642 -114.837323) (xy 1.189543 -114.941529) (xy 1.288363 -115.040349)
			(xy 1.392569 -115.133472) (xy 1.501832 -115.220607) (xy 1.615809 -115.301478) (xy 1.734141 -115.375831)
			(xy 1.856456 -115.443432) (xy 1.982368 -115.504068) (xy 2.111483 -115.557549) (xy 2.243393 -115.603706)
			(xy 2.377684 -115.642395) (xy 2.513933 -115.673493) (xy 2.651711 -115.696902) (xy 2.790585 -115.71255)
			(xy 2.930118 -115.720386) (xy 2.999994 -115.720876) (xy 9.59993 -115.720876) (xy 9.643968 -115.721358)
			(xy 9.731709 -115.729037) (xy 9.818446 -115.744333) (xy 9.90352 -115.767131) (xy 9.986284 -115.797257)
			(xy 10.066107 -115.834482) (xy 10.142382 -115.878522) (xy 10.214528 -115.929042) (xy 10.281997 -115.985658)
			(xy 10.344275 -116.047939) (xy 10.400887 -116.11541) (xy 10.451404 -116.187559) (xy 10.49544 -116.263836)
			(xy 10.532661 -116.34366) (xy 10.562783 -116.426425) (xy 10.585577 -116.511501) (xy 10.60087 -116.598239)
			(xy 10.608544 -116.68598) (xy 10.609072 -116.730018) (xy 10.609072 -116.971769) (xy 270.314162 -116.971769)
			(xy 270.314162 -116.887047) (xy 270.322215 -116.80271) (xy 270.338249 -116.71952) (xy 270.362117 -116.63823)
			(xy 270.393605 -116.559578) (xy 270.432427 -116.484275) (xy 270.47823 -116.413003) (xy 270.530601 -116.346407)
			(xy 270.589066 -116.285092) (xy 270.653094 -116.229611) (xy 270.722106 -116.180468) (xy 270.795476 -116.138108)
			(xy 270.872541 -116.102913) (xy 270.952603 -116.075204) (xy 271.034936 -116.05523) (xy 271.118795 -116.043173)
			(xy 271.20342 -116.039142) (xy 271.288045 -116.043173) (xy 271.371904 -116.05523) (xy 271.454237 -116.075204)
			(xy 271.534299 -116.102913) (xy 271.611364 -116.138108) (xy 271.684734 -116.180468) (xy 271.753746 -116.229611)
			(xy 271.817774 -116.285092) (xy 271.876239 -116.346407) (xy 271.92861 -116.413003) (xy 271.974413 -116.484275)
			(xy 272.013235 -116.559578) (xy 272.044723 -116.63823) (xy 272.068591 -116.71952) (xy 272.084625 -116.80271)
			(xy 272.092678 -116.887047) (xy 272.093182 -116.929408) (xy 272.092678 -116.971769) (xy 272.084625 -117.056106)
			(xy 272.068591 -117.139296) (xy 272.044723 -117.220586) (xy 272.013235 -117.299238) (xy 271.974413 -117.374541)
			(xy 271.92861 -117.445813) (xy 271.876239 -117.512409) (xy 271.817774 -117.573724) (xy 271.753746 -117.629205)
			(xy 271.684734 -117.678348) (xy 271.611364 -117.720708) (xy 271.534299 -117.755903) (xy 271.454237 -117.783612)
			(xy 271.371904 -117.803586) (xy 271.288045 -117.815643) (xy 271.20342 -117.819675) (xy 271.118795 -117.815643)
			(xy 271.034936 -117.803586) (xy 270.952603 -117.783612) (xy 270.872541 -117.755903) (xy 270.795476 -117.720708)
			(xy 270.722106 -117.678348) (xy 270.653094 -117.629205) (xy 270.589066 -117.573724) (xy 270.530601 -117.512409)
			(xy 270.47823 -117.445813) (xy 270.432427 -117.374541) (xy 270.393605 -117.299238) (xy 270.362117 -117.220586)
			(xy 270.338249 -117.139296) (xy 270.322215 -117.056106) (xy 270.314162 -116.971769) (xy 10.609072 -116.971769)
			(xy 10.609072 -122.48007) (xy 12.909653 -122.48007) (xy 12.913615 -122.339639) (xy 12.92549 -122.199655)
			(xy 12.94524 -122.060564) (xy 12.972802 -121.922808) (xy 13.008088 -121.786825) (xy 13.050986 -121.653048)
			(xy 13.101359 -121.521903) (xy 13.159047 -121.393807) (xy 13.223867 -121.269168) (xy 13.295611 -121.148382)
			(xy 13.374053 -121.031834) (xy 13.458942 -120.919895) (xy 13.550008 -120.812921) (xy 13.646962 -120.711253)
			(xy 13.749494 -120.615213) (xy 13.857279 -120.525108) (xy 13.969973 -120.441224) (xy 14.087218 -120.363828)
			(xy 14.208641 -120.293167) (xy 14.333855 -120.229466) (xy 14.462462 -120.172926) (xy 14.594052 -120.123729)
			(xy 14.728208 -120.08203) (xy 14.864501 -120.047962) (xy 15.002499 -120.021634) (xy 15.141762 -120.00313)
			(xy 15.281846 -119.992508) (xy 15.422307 -119.989803) (xy 15.562696 -119.995022) (xy 15.702568 -120.008149)
			(xy 15.841477 -120.029143) (xy 15.978981 -120.057936) (xy 16.114643 -120.094438) (xy 16.248031 -120.138531)
			(xy 16.37872 -120.190076) (xy 16.506295 -120.248908) (xy 16.630349 -120.31484) (xy 16.750487 -120.387663)
			(xy 16.866328 -120.467145) (xy 16.977503 -120.553032) (xy 17.083658 -120.645052) (xy 17.184455 -120.742911)
			(xy 17.232376 -120.794272) (xy 17.241266 -120.803924) (xy 17.264888 -120.812052) (xy 17.3736 -120.795542)
			(xy 17.393666 -120.780556) (xy 17.399 -120.768872) (xy 17.438151 -120.687) (xy 17.522868 -120.526483)
			(xy 17.614754 -120.36996) (xy 17.713621 -120.21775) (xy 17.819267 -120.070165) (xy 17.931475 -119.927505)
			(xy 18.050018 -119.790064) (xy 18.174651 -119.65812) (xy 18.305121 -119.531945) (xy 18.441161 -119.411797)
			(xy 18.582492 -119.29792) (xy 18.728826 -119.190548) (xy 18.879864 -119.089899) (xy 19.035297 -118.996181)
			(xy 19.194807 -118.909584) (xy 19.358068 -118.830285) (xy 19.524747 -118.758447) (xy 19.694502 -118.694216)
			(xy 19.866987 -118.637724) (xy 20.04185 -118.589086) (xy 20.218732 -118.548401) (xy 20.397272 -118.515753)
			(xy 20.577105 -118.491209) (xy 20.757864 -118.474818) (xy 20.93918 -118.466614) (xy 21.02993 -118.466108)
			(xy 21.120007 -118.466613) (xy 21.147082 -118.467829) (xy 268.757142 -118.467829) (xy 268.757142 -118.383107)
			(xy 268.765195 -118.29877) (xy 268.781229 -118.21558) (xy 268.805097 -118.13429) (xy 268.836585 -118.055638)
			(xy 268.875407 -117.980335) (xy 268.92121 -117.909063) (xy 268.973581 -117.842467) (xy 269.032046 -117.781152)
			(xy 269.096074 -117.725671) (xy 269.165086 -117.676528) (xy 269.238456 -117.634168) (xy 269.315521 -117.598973)
			(xy 269.395583 -117.571264) (xy 269.477916 -117.55129) (xy 269.561775 -117.539233) (xy 269.6464 -117.535202)
			(xy 269.731025 -117.539233) (xy 269.814884 -117.55129) (xy 269.897217 -117.571264) (xy 269.977279 -117.598973)
			(xy 270.054344 -117.634168) (xy 270.127714 -117.676528) (xy 270.196726 -117.725671) (xy 270.260754 -117.781152)
			(xy 270.319219 -117.842467) (xy 270.37159 -117.909063) (xy 270.417393 -117.980335) (xy 270.456215 -118.055638)
			(xy 270.487703 -118.13429) (xy 270.511571 -118.21558) (xy 270.527605 -118.29877) (xy 270.535658 -118.383107)
			(xy 270.536162 -118.425468) (xy 270.535658 -118.467829) (xy 270.527605 -118.552166) (xy 270.511571 -118.635356)
			(xy 270.487703 -118.716646) (xy 270.456215 -118.795298) (xy 270.417393 -118.870601) (xy 270.37159 -118.941873)
			(xy 270.319219 -119.008469) (xy 270.260754 -119.069784) (xy 270.196726 -119.125265) (xy 270.127714 -119.174408)
			(xy 270.054344 -119.216768) (xy 269.977279 -119.251963) (xy 269.897217 -119.279672) (xy 269.814884 -119.299646)
			(xy 269.731025 -119.311703) (xy 269.6464 -119.315735) (xy 269.561775 -119.311703) (xy 269.477916 -119.299646)
			(xy 269.395583 -119.279672) (xy 269.315521 -119.251963) (xy 269.238456 -119.216768) (xy 269.165086 -119.174408)
			(xy 269.096074 -119.125265) (xy 269.032046 -119.069784) (xy 268.973581 -119.008469) (xy 268.92121 -118.941873)
			(xy 268.875407 -118.870601) (xy 268.836585 -118.795298) (xy 268.805097 -118.716646) (xy 268.781229 -118.635356)
			(xy 268.765195 -118.552166) (xy 268.757142 -118.467829) (xy 21.147082 -118.467829) (xy 21.299979 -118.474696)
			(xy 21.479408 -118.490845) (xy 21.657931 -118.515027) (xy 21.83519 -118.547195) (xy 22.010827 -118.587283)
			(xy 22.184488 -118.63521) (xy 22.355825 -118.690881) (xy 22.524491 -118.754183) (xy 22.690147 -118.824987)
			(xy 22.85246 -118.903153) (xy 23.011103 -118.988522) (xy 23.165755 -119.080923) (xy 23.316107 -119.180169)
			(xy 23.461854 -119.286061) (xy 23.602704 -119.398385) (xy 23.738373 -119.516915) (xy 23.868587 -119.641413)
			(xy 23.993085 -119.771627) (xy 24.111615 -119.907296) (xy 24.223939 -120.048146) (xy 24.329831 -120.193893)
			(xy 24.429077 -120.344245) (xy 24.521478 -120.498897) (xy 24.606847 -120.65754) (xy 24.685013 -120.819853)
			(xy 24.755817 -120.985509) (xy 24.819119 -121.154175) (xy 24.87479 -121.325512) (xy 24.922717 -121.499173)
			(xy 24.962805 -121.67481) (xy 24.994973 -121.852069) (xy 25.019155 -122.030592) (xy 25.035304 -122.210021)
			(xy 25.043387 -122.389993) (xy 25.043387 -122.48007) (xy 25.159471 -122.48007) (xy 25.16346 -122.339172)
			(xy 25.175414 -122.198725) (xy 25.195294 -122.05918) (xy 25.223037 -121.920983) (xy 25.258555 -121.784577)
			(xy 25.301732 -121.650398) (xy 25.352432 -121.518878) (xy 25.410492 -121.390436) (xy 25.475724 -121.265485)
			(xy 25.547922 -121.144424) (xy 25.626853 -121.027642) (xy 25.712264 -120.915513) (xy 25.803883 -120.808395)
			(xy 25.901415 -120.706632) (xy 26.004547 -120.61055) (xy 26.112951 -120.520457) (xy 26.226278 -120.43664)
			(xy 26.344165 -120.35937) (xy 26.466235 -120.288893) (xy 26.592097 -120.225434) (xy 26.721347 -120.169199)
			(xy 26.853572 -120.120365) (xy 26.988348 -120.07909) (xy 27.125243 -120.045507) (xy 27.263819 -120.019722)
			(xy 27.403632 -120.001818) (xy 27.544234 -119.991853) (xy 27.685174 -119.989858) (xy 27.826002 -119.995841)
			(xy 27.966265 -120.009781) (xy 28.105515 -120.031634) (xy 28.243306 -120.06133) (xy 28.379196 -120.098774)
			(xy 28.51275 -120.143846) (xy 28.64354 -120.196402) (xy 28.771147 -120.256273) (xy 28.895163 -120.323268)
			(xy 29.015189 -120.397171) (xy 29.130843 -120.477747) (xy 29.241752 -120.564736) (xy 29.347563 -120.657861)
			(xy 29.447935 -120.756823) (xy 29.542548 -120.861305) (xy 29.631099 -120.970973) (xy 29.713303 -121.085475)
			(xy 29.788897 -121.204444) (xy 29.791898 -121.209816) (xy 62.652667 -121.209816) (xy 62.65664 -121.089706)
			(xy 62.668543 -120.970121) (xy 62.688324 -120.851584) (xy 62.715895 -120.734613) (xy 62.751137 -120.61972)
			(xy 62.793894 -120.507408) (xy 62.843982 -120.398167) (xy 62.901179 -120.292476) (xy 62.965237 -120.190795)
			(xy 63.035874 -120.093571) (xy 63.112783 -120.001228) (xy 63.195627 -119.914169) (xy 63.284043 -119.832776)
			(xy 63.377646 -119.757405) (xy 63.476025 -119.688384) (xy 63.57875 -119.626016) (xy 63.685373 -119.570574)
			(xy 63.795427 -119.5223) (xy 63.908431 -119.481405) (xy 64.023891 -119.448068) (xy 64.141301 -119.422434)
			(xy 64.260149 -119.404616) (xy 64.379915 -119.394692) (xy 64.500074 -119.392705) (xy 64.620102 -119.398664)
			(xy 64.739474 -119.412543) (xy 64.857668 -119.43428) (xy 64.974167 -119.463782) (xy 65.088461 -119.500918)
			(xy 65.200051 -119.545527) (xy 65.308449 -119.597414) (xy 65.41318 -119.656351) (xy 65.513787 -119.722081)
			(xy 65.609831 -119.794316) (xy 65.70089 -119.872742) (xy 65.786567 -119.957013) (xy 65.866487 -120.046763)
			(xy 65.9403 -120.141599) (xy 66.007685 -120.241106) (xy 66.068346 -120.344849) (xy 66.122017 -120.452374)
			(xy 66.168465 -120.563211) (xy 66.207486 -120.676875) (xy 66.23891 -120.79287) (xy 66.262599 -120.910689)
			(xy 66.278449 -121.029815) (xy 66.286391 -121.149728) (xy 66.286888 -121.209816) (xy 102.652587 -121.209816)
			(xy 102.65656 -121.089706) (xy 102.668463 -120.970121) (xy 102.688244 -120.851584) (xy 102.715815 -120.734613)
			(xy 102.751057 -120.61972) (xy 102.793814 -120.507408) (xy 102.843902 -120.398167) (xy 102.901099 -120.292476)
			(xy 102.965157 -120.190795) (xy 103.035794 -120.093571) (xy 103.112703 -120.001228) (xy 103.195547 -119.914169)
			(xy 103.283963 -119.832776) (xy 103.377566 -119.757405) (xy 103.475945 -119.688384) (xy 103.57867 -119.626016)
			(xy 103.685293 -119.570574) (xy 103.795347 -119.5223) (xy 103.908351 -119.481405) (xy 104.023811 -119.448068)
			(xy 104.141221 -119.422434) (xy 104.260069 -119.404616) (xy 104.379835 -119.394692) (xy 104.499994 -119.392705)
			(xy 104.620022 -119.398664) (xy 104.739394 -119.412543) (xy 104.857588 -119.43428) (xy 104.974087 -119.463782)
			(xy 105.088381 -119.500918) (xy 105.199971 -119.545527) (xy 105.308369 -119.597414) (xy 105.4131 -119.656351)
			(xy 105.513707 -119.722081) (xy 105.609751 -119.794316) (xy 105.70081 -119.872742) (xy 105.786487 -119.957013)
			(xy 105.866407 -120.046763) (xy 105.94022 -120.141599) (xy 106.007605 -120.241106) (xy 106.068266 -120.344849)
			(xy 106.121937 -120.452374) (xy 106.168385 -120.563211) (xy 106.207406 -120.676875) (xy 106.23883 -120.79287)
			(xy 106.262519 -120.910689) (xy 106.278369 -121.029815) (xy 106.286311 -121.149728) (xy 106.286808 -121.209816)
			(xy 142.652761 -121.209816) (xy 142.656734 -121.089706) (xy 142.668637 -120.970121) (xy 142.688418 -120.851584)
			(xy 142.715989 -120.734613) (xy 142.751231 -120.61972) (xy 142.793988 -120.507408) (xy 142.844076 -120.398167)
			(xy 142.901273 -120.292476) (xy 142.965331 -120.190795) (xy 143.035968 -120.093571) (xy 143.112877 -120.001228)
			(xy 143.195721 -119.914169) (xy 143.284137 -119.832776) (xy 143.37774 -119.757405) (xy 143.476119 -119.688384)
			(xy 143.578844 -119.626016) (xy 143.685467 -119.570574) (xy 143.795521 -119.5223) (xy 143.908525 -119.481405)
			(xy 144.023985 -119.448068) (xy 144.141395 -119.422434) (xy 144.260243 -119.404616) (xy 144.380009 -119.394692)
			(xy 144.500168 -119.392705) (xy 144.620196 -119.398664) (xy 144.739568 -119.412543) (xy 144.857762 -119.43428)
			(xy 144.974261 -119.463782) (xy 145.088555 -119.500918) (xy 145.200145 -119.545527) (xy 145.308543 -119.597414)
			(xy 145.413274 -119.656351) (xy 145.513881 -119.722081) (xy 145.609925 -119.794316) (xy 145.700984 -119.872742)
			(xy 145.786661 -119.957013) (xy 145.866581 -120.046763) (xy 145.940394 -120.141599) (xy 146.007779 -120.241106)
			(xy 146.06844 -120.344849) (xy 146.122111 -120.452374) (xy 146.168559 -120.563211) (xy 146.20758 -120.676875)
			(xy 146.239004 -120.79287) (xy 146.262693 -120.910689) (xy 146.278543 -121.029815) (xy 146.286485 -121.149728)
			(xy 146.286982 -121.209816) (xy 182.652935 -121.209816) (xy 182.656908 -121.089706) (xy 182.668811 -120.970121)
			(xy 182.688592 -120.851584) (xy 182.716163 -120.734613) (xy 182.751405 -120.61972) (xy 182.794162 -120.507408)
			(xy 182.84425 -120.398167) (xy 182.901447 -120.292476) (xy 182.965505 -120.190795) (xy 183.036142 -120.093571)
			(xy 183.113051 -120.001228) (xy 183.195895 -119.914169) (xy 183.284311 -119.832776) (xy 183.377914 -119.757405)
			(xy 183.476293 -119.688384) (xy 183.579018 -119.626016) (xy 183.685641 -119.570574) (xy 183.795695 -119.5223)
			(xy 183.908699 -119.481405) (xy 184.024159 -119.448068) (xy 184.141569 -119.422434) (xy 184.260417 -119.404616)
			(xy 184.380183 -119.394692) (xy 184.500342 -119.392705) (xy 184.62037 -119.398664) (xy 184.739742 -119.412543)
			(xy 184.857936 -119.43428) (xy 184.974435 -119.463782) (xy 185.088729 -119.500918) (xy 185.200319 -119.545527)
			(xy 185.308717 -119.597414) (xy 185.413448 -119.656351) (xy 185.514055 -119.722081) (xy 185.610099 -119.794316)
			(xy 185.701158 -119.872742) (xy 185.786835 -119.957013) (xy 185.866755 -120.046763) (xy 185.940568 -120.141599)
			(xy 186.007953 -120.241106) (xy 186.068614 -120.344849) (xy 186.122285 -120.452374) (xy 186.168733 -120.563211)
			(xy 186.207754 -120.676875) (xy 186.239178 -120.79287) (xy 186.262867 -120.910689) (xy 186.278717 -121.029815)
			(xy 186.286659 -121.149728) (xy 186.287156 -121.209816) (xy 186.286659 -121.269904) (xy 186.278717 -121.389817)
			(xy 186.262867 -121.508943) (xy 186.239178 -121.626762) (xy 186.207754 -121.742757) (xy 186.168733 -121.856421)
			(xy 186.122285 -121.967258) (xy 186.068614 -122.074783) (xy 186.007953 -122.178526) (xy 185.940568 -122.278033)
			(xy 185.866755 -122.372869) (xy 185.786835 -122.462619) (xy 185.701158 -122.54689) (xy 185.610099 -122.625316)
			(xy 185.514055 -122.697551) (xy 185.413448 -122.763281) (xy 185.330851 -122.809762) (xy 201.460608 -122.809762)
			(xy 201.461219 -122.763359) (xy 201.470913 -122.671062) (xy 201.490171 -122.580276) (xy 201.518784 -122.491991)
			(xy 201.537062 -122.449336) (xy 201.540892 -122.439401) (xy 201.540877 -122.41813) (xy 201.537062 -122.408188)
			(xy 201.518789 -122.365532) (xy 201.490198 -122.277242) (xy 201.470944 -122.186458) (xy 201.461235 -122.094163)
			(xy 201.460608 -122.047762) (xy 201.461152 -122.004334) (xy 201.469646 -121.917893) (xy 201.486519 -121.83269)
			(xy 201.511611 -121.749536) (xy 201.527664 -121.70918) (xy 201.531108 -121.699762) (xy 201.531126 -121.679728)
			(xy 201.527664 -121.670318) (xy 201.511607 -121.629963) (xy 201.486507 -121.54681) (xy 201.469633 -121.461607)
			(xy 201.461143 -121.375165) (xy 201.460608 -121.331736) (xy 201.46121 -121.285333) (xy 201.470907 -121.193035)
			(xy 201.490167 -121.10225) (xy 201.518783 -121.013965) (xy 201.537062 -120.97131) (xy 201.540848 -120.961362)
			(xy 201.540862 -120.940104) (xy 201.537062 -120.930162) (xy 201.518813 -120.887496) (xy 201.490216 -120.79921)
			(xy 201.470955 -120.708428) (xy 201.461239 -120.616137) (xy 201.460608 -120.569736) (xy 201.461087 -120.528625)
			(xy 201.468672 -120.446755) (xy 201.48378 -120.365934) (xy 201.506282 -120.286852) (xy 201.535987 -120.210185)
			(xy 201.57264 -120.136586) (xy 201.61593 -120.066683) (xy 201.665486 -120.001075) (xy 201.720885 -119.940319)
			(xy 201.781655 -119.884936) (xy 201.847277 -119.835397) (xy 201.91719 -119.792126) (xy 201.990799 -119.755492)
			(xy 202.067474 -119.725808) (xy 202.146562 -119.703326) (xy 202.227387 -119.688239) (xy 202.309259 -119.680676)
			(xy 202.35037 -119.680228) (xy 202.396765 -119.680818) (xy 202.489054 -119.690461) (xy 202.579837 -119.709654)
			(xy 202.668131 -119.738191) (xy 202.710796 -119.756428) (xy 202.720738 -119.760234) (xy 202.742002 -119.760234)
			(xy 202.751944 -119.756428) (xy 202.794611 -119.738195) (xy 202.882902 -119.709648) (xy 202.973685 -119.690451)
			(xy 203.065974 -119.680814) (xy 203.11237 -119.680228) (xy 203.158765 -119.680818) (xy 203.251054 -119.690461)
			(xy 203.341837 -119.709654) (xy 203.430131 -119.738191) (xy 203.472796 -119.756428) (xy 203.482738 -119.760234)
			(xy 203.504002 -119.760234) (xy 203.513944 -119.756428) (xy 203.556611 -119.738195) (xy 203.644902 -119.709648)
			(xy 203.735685 -119.690451) (xy 203.827974 -119.680814) (xy 203.87437 -119.680228) (xy 203.920765 -119.680818)
			(xy 204.013054 -119.690461) (xy 204.103837 -119.709654) (xy 204.192131 -119.738191) (xy 204.234796 -119.756428)
			(xy 204.244738 -119.760234) (xy 204.266002 -119.760234) (xy 204.275944 -119.756428) (xy 204.318611 -119.738195)
			(xy 204.406902 -119.709648) (xy 204.497685 -119.690451) (xy 204.589974 -119.680814) (xy 204.63637 -119.680228)
			(xy 204.682765 -119.680818) (xy 204.775054 -119.690461) (xy 204.865837 -119.709654) (xy 204.954131 -119.738191)
			(xy 204.996796 -119.756428) (xy 205.006738 -119.760234) (xy 205.028002 -119.760234) (xy 205.037944 -119.756428)
			(xy 205.080611 -119.738195) (xy 205.168902 -119.709648) (xy 205.259685 -119.690451) (xy 205.351974 -119.680814)
			(xy 205.39837 -119.680228) (xy 205.444765 -119.680818) (xy 205.537054 -119.690461) (xy 205.627837 -119.709654)
			(xy 205.716131 -119.738191) (xy 205.758796 -119.756428) (xy 205.768738 -119.760234) (xy 205.790002 -119.760234)
			(xy 205.799944 -119.756428) (xy 205.842611 -119.738195) (xy 205.930902 -119.709648) (xy 206.021685 -119.690451)
			(xy 206.113974 -119.680814) (xy 206.16037 -119.680228) (xy 206.206765 -119.680818) (xy 206.299054 -119.690461)
			(xy 206.389837 -119.709654) (xy 206.478131 -119.738191) (xy 206.520796 -119.756428) (xy 206.530738 -119.760234)
			(xy 206.552002 -119.760234) (xy 206.561944 -119.756428) (xy 206.604611 -119.738195) (xy 206.692902 -119.709648)
			(xy 206.783685 -119.690451) (xy 206.875974 -119.680814) (xy 206.92237 -119.680228) (xy 206.968765 -119.680818)
			(xy 207.061054 -119.690461) (xy 207.151837 -119.709654) (xy 207.240131 -119.738191) (xy 207.282796 -119.756428)
			(xy 207.292738 -119.760234) (xy 207.314002 -119.760234) (xy 207.323944 -119.756428) (xy 207.366611 -119.738195)
			(xy 207.454902 -119.709648) (xy 207.545685 -119.690451) (xy 207.637974 -119.680814) (xy 207.68437 -119.680228)
			(xy 207.725476 -119.680741) (xy 207.807338 -119.688323) (xy 207.888151 -119.703424) (xy 207.967226 -119.725916)
			(xy 208.043889 -119.755607) (xy 208.117486 -119.792244) (xy 208.18739 -119.835514) (xy 208.253003 -119.885048)
			(xy 208.313767 -119.940425) (xy 208.369164 -120.00117) (xy 208.41872 -120.066768) (xy 208.462013 -120.136657)
			(xy 208.498674 -120.210242) (xy 208.528391 -120.286895) (xy 208.550909 -120.365963) (xy 208.566037 -120.446771)
			(xy 208.573645 -120.52863) (xy 208.574132 -120.569736) (xy 208.573517 -120.616138) (xy 208.563823 -120.708436)
			(xy 208.544566 -120.799221) (xy 208.515955 -120.887506) (xy 208.497678 -120.930162) (xy 208.493853 -120.940098)
			(xy 208.493867 -120.961367) (xy 208.497678 -120.97131) (xy 208.515953 -121.013966) (xy 208.544542 -121.102256)
			(xy 208.563796 -121.19304) (xy 208.573505 -121.285335) (xy 208.574132 -121.331736) (xy 208.573584 -121.375164)
			(xy 208.565091 -121.461605) (xy 208.548219 -121.546808) (xy 208.523128 -121.629962) (xy 208.507076 -121.670318)
			(xy 208.503705 -121.679744) (xy 208.503722 -121.699746) (xy 208.507076 -121.70918) (xy 208.523129 -121.749537)
			(xy 208.54823 -121.832688) (xy 208.565107 -121.917891) (xy 208.573597 -122.004333) (xy 208.574132 -122.047762)
			(xy 208.573526 -122.094165) (xy 208.56383 -122.186463) (xy 208.54457 -122.277248) (xy 208.515957 -122.365533)
			(xy 208.497678 -122.408188) (xy 208.493897 -122.418137) (xy 208.493882 -122.439394) (xy 208.497678 -122.449336)
			(xy 208.515928 -122.492002) (xy 208.544524 -122.580288) (xy 208.563785 -122.671069) (xy 208.573501 -122.763361)
			(xy 208.574132 -122.809762) (xy 215.837516 -122.809762) (xy 215.838126 -122.763359) (xy 215.847821 -122.671062)
			(xy 215.867079 -122.580276) (xy 215.895692 -122.491991) (xy 215.91397 -122.449336) (xy 215.917799 -122.439401)
			(xy 215.917785 -122.41813) (xy 215.91397 -122.408188) (xy 215.895691 -122.365534) (xy 215.867103 -122.277243)
			(xy 215.847851 -122.186458) (xy 215.838143 -122.094164) (xy 215.837516 -122.047762) (xy 215.83806 -122.004334)
			(xy 215.846553 -121.917893) (xy 215.863427 -121.83269) (xy 215.888519 -121.749536) (xy 215.904572 -121.70918)
			(xy 215.908015 -121.699762) (xy 215.908033 -121.679728) (xy 215.904572 -121.670318) (xy 215.888515 -121.629963)
			(xy 215.863416 -121.54681) (xy 215.846541 -121.461607) (xy 215.838051 -121.375165) (xy 215.837516 -121.331736)
			(xy 215.838117 -121.285333) (xy 215.847814 -121.193035) (xy 215.867075 -121.10225) (xy 215.89569 -121.013965)
			(xy 215.91397 -120.97131) (xy 215.917755 -120.961361) (xy 215.917769 -120.940104) (xy 215.91397 -120.930162)
			(xy 215.895716 -120.887498) (xy 215.867121 -120.799211) (xy 215.847862 -120.708429) (xy 215.838147 -120.616137)
			(xy 215.837516 -120.569736) (xy 215.837987 -120.528625) (xy 215.845572 -120.446754) (xy 215.86068 -120.365933)
			(xy 215.883183 -120.286851) (xy 215.912888 -120.210183) (xy 215.949542 -120.136583) (xy 215.992832 -120.066681)
			(xy 216.042388 -120.001072) (xy 216.097788 -119.940317) (xy 216.158558 -119.884933) (xy 216.224181 -119.835395)
			(xy 216.294095 -119.792124) (xy 216.367704 -119.75549) (xy 216.44438 -119.725806) (xy 216.523469 -119.703324)
			(xy 216.604294 -119.688238) (xy 216.686167 -119.680676) (xy 216.727278 -119.680228) (xy 216.773673 -119.680816)
			(xy 216.865962 -119.690459) (xy 216.956746 -119.709653) (xy 217.045039 -119.738191) (xy 217.087704 -119.756428)
			(xy 217.097646 -119.760234) (xy 217.11891 -119.760234) (xy 217.128852 -119.756428) (xy 217.171518 -119.738193)
			(xy 217.259809 -119.709646) (xy 217.350593 -119.69045) (xy 217.442882 -119.680814) (xy 217.489278 -119.680228)
			(xy 217.535673 -119.680816) (xy 217.627962 -119.690459) (xy 217.718746 -119.709653) (xy 217.807039 -119.738191)
			(xy 217.849704 -119.756428) (xy 217.859646 -119.760234) (xy 217.88091 -119.760234) (xy 217.890852 -119.756428)
			(xy 217.933518 -119.738193) (xy 218.021809 -119.709646) (xy 218.112593 -119.69045) (xy 218.204882 -119.680814)
			(xy 218.251278 -119.680228) (xy 218.297673 -119.680816) (xy 218.389962 -119.690459) (xy 218.480746 -119.709653)
			(xy 218.569039 -119.738191) (xy 218.611704 -119.756428) (xy 218.621646 -119.760234) (xy 218.64291 -119.760234)
			(xy 218.652852 -119.756428) (xy 218.695518 -119.738193) (xy 218.783809 -119.709646) (xy 218.874593 -119.69045)
			(xy 218.966882 -119.680814) (xy 219.013278 -119.680228) (xy 219.059673 -119.680816) (xy 219.151962 -119.690459)
			(xy 219.242746 -119.709653) (xy 219.331039 -119.738191) (xy 219.373704 -119.756428) (xy 219.383646 -119.760234)
			(xy 219.40491 -119.760234) (xy 219.414852 -119.756428) (xy 219.457518 -119.738193) (xy 219.545809 -119.709646)
			(xy 219.636593 -119.69045) (xy 219.728882 -119.680814) (xy 219.775278 -119.680228) (xy 219.821673 -119.680816)
			(xy 219.913962 -119.690459) (xy 220.004746 -119.709653) (xy 220.093039 -119.738191) (xy 220.135704 -119.756428)
			(xy 220.145646 -119.760234) (xy 220.16691 -119.760234) (xy 220.176852 -119.756428) (xy 220.219518 -119.738193)
			(xy 220.307809 -119.709646) (xy 220.398593 -119.69045) (xy 220.490882 -119.680814) (xy 220.537278 -119.680228)
			(xy 220.583673 -119.680816) (xy 220.675962 -119.690459) (xy 220.766746 -119.709653) (xy 220.855039 -119.738191)
			(xy 220.897704 -119.756428) (xy 220.907646 -119.760234) (xy 220.92891 -119.760234) (xy 220.938852 -119.756428)
			(xy 220.981518 -119.738193) (xy 221.069809 -119.709646) (xy 221.160593 -119.69045) (xy 221.252882 -119.680814)
			(xy 221.299278 -119.680228) (xy 221.345673 -119.680816) (xy 221.437962 -119.690459) (xy 221.528746 -119.709653)
			(xy 221.617039 -119.738191) (xy 221.659704 -119.756428) (xy 221.669646 -119.760234) (xy 221.69091 -119.760234)
			(xy 221.700852 -119.756428) (xy 221.743518 -119.738193) (xy 221.831809 -119.709646) (xy 221.922593 -119.69045)
			(xy 222.014882 -119.680814) (xy 222.061278 -119.680228) (xy 222.102384 -119.680733) (xy 222.184246 -119.688316)
			(xy 222.265059 -119.703418) (xy 222.344135 -119.72591) (xy 222.420798 -119.755602) (xy 222.494395 -119.792239)
			(xy 222.564298 -119.83551) (xy 222.629912 -119.885045) (xy 222.690676 -119.940422) (xy 222.746072 -120.001168)
			(xy 222.795628 -120.066766) (xy 222.838921 -120.136655) (xy 222.875582 -120.21024) (xy 222.905299 -120.286894)
			(xy 222.927817 -120.365962) (xy 222.942945 -120.446771) (xy 222.950553 -120.52863) (xy 222.95104 -120.569736)
			(xy 222.950424 -120.616138) (xy 222.940731 -120.708436) (xy 222.921474 -120.799221) (xy 222.892863 -120.887506)
			(xy 222.874586 -120.930162) (xy 222.87076 -120.940098) (xy 222.870774 -120.961367) (xy 222.874586 -120.97131)
			(xy 222.892861 -121.013965) (xy 222.921451 -121.102256) (xy 222.940704 -121.19304) (xy 222.950413 -121.285335)
			(xy 222.95104 -121.331736) (xy 222.950499 -121.375165) (xy 222.942005 -121.461606) (xy 222.925131 -121.546808)
			(xy 222.900038 -121.629962) (xy 222.883984 -121.670318) (xy 222.880612 -121.679744) (xy 222.88063 -121.699746)
			(xy 222.883984 -121.70918) (xy 222.900038 -121.749536) (xy 222.925139 -121.832688) (xy 222.942015 -121.917891)
			(xy 222.950505 -122.004333) (xy 222.95104 -122.047762) (xy 222.950434 -122.094165) (xy 222.940737 -122.186463)
			(xy 222.921478 -122.277248) (xy 222.892864 -122.365533) (xy 222.874586 -122.408188) (xy 222.870804 -122.418137)
			(xy 222.87079 -122.439394) (xy 222.874586 -122.449336) (xy 222.892837 -122.492001) (xy 222.921433 -122.580288)
			(xy 222.940693 -122.671069) (xy 222.950409 -122.763361) (xy 222.95104 -122.809762) (xy 222.950563 -122.851239)
			(xy 222.942823 -122.933832) (xy 222.927426 -123.015345) (xy 222.904504 -123.09507) (xy 222.889826 -123.133866)
			(xy 222.886651 -123.143365) (xy 222.887035 -123.163366) (xy 222.890588 -123.172728) (xy 222.908345 -123.214883)
			(xy 222.936112 -123.302044) (xy 222.954787 -123.391595) (xy 222.964172 -123.482589) (xy 222.964756 -123.528328)
			(xy 222.964274 -123.569438) (xy 222.956685 -123.651306) (xy 222.941572 -123.732125) (xy 222.919067 -123.811204)
			(xy 222.88936 -123.887869) (xy 222.852705 -123.961465) (xy 222.809414 -124.031365) (xy 222.759859 -124.096972)
			(xy 222.70446 -124.157726) (xy 222.643692 -124.213108) (xy 222.578072 -124.262647) (xy 222.508161 -124.305918)
			(xy 222.434555 -124.342554) (xy 222.357882 -124.372241) (xy 222.278797 -124.394726) (xy 222.197974 -124.409817)
			(xy 222.116104 -124.417385) (xy 222.074994 -124.417836) (xy 222.028598 -124.417253) (xy 221.93631 -124.407607)
			(xy 221.845526 -124.388412) (xy 221.757233 -124.359874) (xy 221.714568 -124.341636) (xy 221.704626 -124.33783)
			(xy 221.683362 -124.33783) (xy 221.67342 -124.341636) (xy 221.630759 -124.359884) (xy 221.542466 -124.388427)
			(xy 221.451681 -124.407619) (xy 221.35939 -124.417251) (xy 221.312994 -124.417836) (xy 221.266598 -124.417253)
			(xy 221.17431 -124.407607) (xy 221.083526 -124.388412) (xy 220.995233 -124.359874) (xy 220.952568 -124.341636)
			(xy 220.942626 -124.33783) (xy 220.921362 -124.33783) (xy 220.91142 -124.341636) (xy 220.868759 -124.359884)
			(xy 220.780466 -124.388427) (xy 220.689681 -124.407619) (xy 220.59739 -124.417251) (xy 220.550994 -124.417836)
			(xy 220.504598 -124.417253) (xy 220.41231 -124.407607) (xy 220.321526 -124.388412) (xy 220.233233 -124.359874)
			(xy 220.190568 -124.341636) (xy 220.180626 -124.33783) (xy 220.159362 -124.33783) (xy 220.14942 -124.341636)
			(xy 220.106759 -124.359884) (xy 220.018466 -124.388427) (xy 219.927681 -124.407619) (xy 219.83539 -124.417251)
			(xy 219.788994 -124.417836) (xy 219.742598 -124.417253) (xy 219.65031 -124.407607) (xy 219.559526 -124.388412)
			(xy 219.471233 -124.359874) (xy 219.428568 -124.341636) (xy 219.418626 -124.33783) (xy 219.397362 -124.33783)
			(xy 219.38742 -124.341636) (xy 219.344759 -124.359884) (xy 219.256466 -124.388427) (xy 219.165681 -124.407619)
			(xy 219.07339 -124.417251) (xy 219.026994 -124.417836) (xy 218.980598 -124.417253) (xy 218.88831 -124.407607)
			(xy 218.797526 -124.388412) (xy 218.709233 -124.359874) (xy 218.666568 -124.341636) (xy 218.656626 -124.33783)
			(xy 218.635362 -124.33783) (xy 218.62542 -124.341636) (xy 218.582759 -124.359884) (xy 218.494466 -124.388427)
			(xy 218.403681 -124.407619) (xy 218.31139 -124.417251) (xy 218.264994 -124.417836) (xy 218.218598 -124.417253)
			(xy 218.12631 -124.407607) (xy 218.035526 -124.388412) (xy 217.947233 -124.359874) (xy 217.904568 -124.341636)
			(xy 217.894626 -124.33783) (xy 217.873362 -124.33783) (xy 217.86342 -124.341636) (xy 217.820759 -124.359884)
			(xy 217.732466 -124.388427) (xy 217.641681 -124.407619) (xy 217.54939 -124.417251) (xy 217.502994 -124.417836)
			(xy 217.456598 -124.417253) (xy 217.36431 -124.407607) (xy 217.273526 -124.388412) (xy 217.185233 -124.359874)
			(xy 217.142568 -124.341636) (xy 217.132626 -124.33783) (xy 217.111362 -124.33783) (xy 217.10142 -124.341636)
			(xy 217.058759 -124.359884) (xy 216.970466 -124.388427) (xy 216.879681 -124.407619) (xy 216.78739 -124.417251)
			(xy 216.740994 -124.417836) (xy 216.699886 -124.417393) (xy 216.618022 -124.409808) (xy 216.537206 -124.394703)
			(xy 216.458128 -124.372207) (xy 216.381463 -124.342511) (xy 216.307865 -124.30587) (xy 216.23796 -124.262595)
			(xy 216.172346 -124.213056) (xy 216.111582 -124.157675) (xy 216.056186 -124.096925) (xy 216.00663 -124.031323)
			(xy 215.963338 -123.961429) (xy 215.926678 -123.88784) (xy 215.896964 -123.811182) (xy 215.874448 -123.73211)
			(xy 215.859323 -123.651298) (xy 215.851717 -123.569436) (xy 215.851232 -123.528328) (xy 215.851707 -123.486851)
			(xy 215.859448 -123.404258) (xy 215.874846 -123.322745) (xy 215.897768 -123.24302) (xy 215.912446 -123.204224)
			(xy 215.915622 -123.194726) (xy 215.915236 -123.174725) (xy 215.911684 -123.165362) (xy 215.893922 -123.123209)
			(xy 215.866157 -123.036047) (xy 215.847484 -122.946496) (xy 215.838099 -122.855501) (xy 215.837516 -122.809762)
			(xy 208.574132 -122.809762) (xy 208.573649 -122.851239) (xy 208.56591 -122.933831) (xy 208.550514 -123.015344)
			(xy 208.527595 -123.09507) (xy 208.512918 -123.133866) (xy 208.509744 -123.143365) (xy 208.510127 -123.163365)
			(xy 208.51368 -123.172728) (xy 208.531436 -123.214883) (xy 208.559204 -123.302044) (xy 208.577878 -123.391595)
			(xy 208.587264 -123.482589) (xy 208.587848 -123.528328) (xy 208.587374 -123.569438) (xy 208.579784 -123.651307)
			(xy 208.564672 -123.732126) (xy 208.542166 -123.811205) (xy 208.512459 -123.887871) (xy 208.475803 -123.961467)
			(xy 208.432513 -124.031368) (xy 208.382957 -124.096975) (xy 208.327557 -124.157729) (xy 208.266788 -124.213111)
			(xy 208.201168 -124.26265) (xy 208.131256 -124.305921) (xy 208.057649 -124.342556) (xy 207.980976 -124.372243)
			(xy 207.90189 -124.394727) (xy 207.821067 -124.409818) (xy 207.739196 -124.417385) (xy 207.698086 -124.417836)
			(xy 207.65169 -124.417256) (xy 207.559402 -124.407609) (xy 207.468618 -124.388413) (xy 207.380325 -124.359874)
			(xy 207.33766 -124.341636) (xy 207.327718 -124.33783) (xy 207.306454 -124.33783) (xy 207.296512 -124.341636)
			(xy 207.253852 -124.359887) (xy 207.165559 -124.388429) (xy 207.074773 -124.40762) (xy 206.982482 -124.417252)
			(xy 206.936086 -124.417836) (xy 206.88969 -124.417256) (xy 206.797402 -124.407609) (xy 206.706618 -124.388413)
			(xy 206.618325 -124.359874) (xy 206.57566 -124.341636) (xy 206.565718 -124.33783) (xy 206.544454 -124.33783)
			(xy 206.534512 -124.341636) (xy 206.491852 -124.359887) (xy 206.403559 -124.388429) (xy 206.312773 -124.40762)
			(xy 206.220482 -124.417252) (xy 206.174086 -124.417836) (xy 206.12769 -124.417256) (xy 206.035402 -124.407609)
			(xy 205.944618 -124.388413) (xy 205.856325 -124.359874) (xy 205.81366 -124.341636) (xy 205.803718 -124.33783)
			(xy 205.782454 -124.33783) (xy 205.772512 -124.341636) (xy 205.729852 -124.359887) (xy 205.641559 -124.388429)
			(xy 205.550773 -124.40762) (xy 205.458482 -124.417252) (xy 205.412086 -124.417836) (xy 205.36569 -124.417256)
			(xy 205.273402 -124.407609) (xy 205.182618 -124.388413) (xy 205.094325 -124.359874) (xy 205.05166 -124.341636)
			(xy 205.041718 -124.33783) (xy 205.020454 -124.33783) (xy 205.010512 -124.341636) (xy 204.967852 -124.359887)
			(xy 204.879559 -124.388429) (xy 204.788773 -124.40762) (xy 204.696482 -124.417252) (xy 204.650086 -124.417836)
			(xy 204.60369 -124.417256) (xy 204.511402 -124.407609) (xy 204.420618 -124.388413) (xy 204.332325 -124.359874)
			(xy 204.28966 -124.341636) (xy 204.279718 -124.33783) (xy 204.258454 -124.33783) (xy 204.248512 -124.341636)
			(xy 204.205852 -124.359887) (xy 204.117559 -124.388429) (xy 204.026773 -124.40762) (xy 203.934482 -124.417252)
			(xy 203.888086 -124.417836) (xy 203.84169 -124.417256) (xy 203.749402 -124.407609) (xy 203.658618 -124.388413)
			(xy 203.570325 -124.359874) (xy 203.52766 -124.341636) (xy 203.517718 -124.33783) (xy 203.496454 -124.33783)
			(xy 203.486512 -124.341636) (xy 203.443852 -124.359887) (xy 203.355559 -124.388429) (xy 203.264773 -124.40762)
			(xy 203.172482 -124.417252) (xy 203.126086 -124.417836) (xy 203.07969 -124.417256) (xy 202.987402 -124.407609)
			(xy 202.896618 -124.388413) (xy 202.808325 -124.359874) (xy 202.76566 -124.341636) (xy 202.755718 -124.33783)
			(xy 202.734454 -124.33783) (xy 202.724512 -124.341636) (xy 202.681852 -124.359887) (xy 202.593559 -124.388429)
			(xy 202.502773 -124.40762) (xy 202.410482 -124.417252) (xy 202.364086 -124.417836) (xy 202.322978 -124.417401)
			(xy 202.241113 -124.409815) (xy 202.160298 -124.394709) (xy 202.08122 -124.372212) (xy 202.004555 -124.342516)
			(xy 201.930956 -124.305875) (xy 201.861052 -124.262599) (xy 201.795437 -124.21306) (xy 201.734673 -124.157678)
			(xy 201.679277 -124.096927) (xy 201.629722 -124.031325) (xy 201.58643 -123.961431) (xy 201.54977 -123.887841)
			(xy 201.520056 -123.811183) (xy 201.49754 -123.732111) (xy 201.482415 -123.651299) (xy 201.474809 -123.569436)
			(xy 201.474324 -123.528328) (xy 201.4748 -123.486851) (xy 201.48254 -123.404258) (xy 201.497938 -123.322745)
			(xy 201.52086 -123.24302) (xy 201.535538 -123.204224) (xy 201.538714 -123.194726) (xy 201.538328 -123.174725)
			(xy 201.534776 -123.165362) (xy 201.517014 -123.123209) (xy 201.489249 -123.036047) (xy 201.470576 -122.946496)
			(xy 201.461191 -122.855501) (xy 201.460608 -122.809762) (xy 185.330851 -122.809762) (xy 185.308717 -122.822218)
			(xy 185.200319 -122.874105) (xy 185.088729 -122.918714) (xy 184.974435 -122.95585) (xy 184.857936 -122.985352)
			(xy 184.739742 -123.007089) (xy 184.62037 -123.020968) (xy 184.500342 -123.026927) (xy 184.380183 -123.02494)
			(xy 184.260417 -123.015016) (xy 184.141569 -122.997198) (xy 184.024159 -122.971564) (xy 183.908699 -122.938227)
			(xy 183.795695 -122.897332) (xy 183.685641 -122.849058) (xy 183.579018 -122.793616) (xy 183.476293 -122.731248)
			(xy 183.377914 -122.662227) (xy 183.284311 -122.586856) (xy 183.195895 -122.505463) (xy 183.113051 -122.418404)
			(xy 183.036142 -122.326061) (xy 182.965505 -122.228837) (xy 182.901447 -122.127156) (xy 182.84425 -122.021465)
			(xy 182.794162 -121.912224) (xy 182.751405 -121.799912) (xy 182.716163 -121.685019) (xy 182.688592 -121.568048)
			(xy 182.668811 -121.449511) (xy 182.656908 -121.329926) (xy 182.652935 -121.209816) (xy 146.286982 -121.209816)
			(xy 146.286485 -121.269904) (xy 146.278543 -121.389817) (xy 146.262693 -121.508943) (xy 146.239004 -121.626762)
			(xy 146.20758 -121.742757) (xy 146.168559 -121.856421) (xy 146.122111 -121.967258) (xy 146.06844 -122.074783)
			(xy 146.007779 -122.178526) (xy 145.940394 -122.278033) (xy 145.866581 -122.372869) (xy 145.786661 -122.462619)
			(xy 145.700984 -122.54689) (xy 145.609925 -122.625316) (xy 145.513881 -122.697551) (xy 145.413274 -122.763281)
			(xy 145.308543 -122.822218) (xy 145.200145 -122.874105) (xy 145.088555 -122.918714) (xy 144.974261 -122.95585)
			(xy 144.857762 -122.985352) (xy 144.739568 -123.007089) (xy 144.620196 -123.020968) (xy 144.500168 -123.026927)
			(xy 144.380009 -123.02494) (xy 144.260243 -123.015016) (xy 144.141395 -122.997198) (xy 144.023985 -122.971564)
			(xy 143.908525 -122.938227) (xy 143.795521 -122.897332) (xy 143.685467 -122.849058) (xy 143.578844 -122.793616)
			(xy 143.476119 -122.731248) (xy 143.37774 -122.662227) (xy 143.284137 -122.586856) (xy 143.195721 -122.505463)
			(xy 143.112877 -122.418404) (xy 143.035968 -122.326061) (xy 142.965331 -122.228837) (xy 142.901273 -122.127156)
			(xy 142.844076 -122.021465) (xy 142.793988 -121.912224) (xy 142.751231 -121.799912) (xy 142.715989 -121.685019)
			(xy 142.688418 -121.568048) (xy 142.668637 -121.449511) (xy 142.656734 -121.329926) (xy 142.652761 -121.209816)
			(xy 106.286808 -121.209816) (xy 106.286311 -121.269904) (xy 106.278369 -121.389817) (xy 106.262519 -121.508943)
			(xy 106.23883 -121.626762) (xy 106.207406 -121.742757) (xy 106.168385 -121.856421) (xy 106.121937 -121.967258)
			(xy 106.068266 -122.074783) (xy 106.007605 -122.178526) (xy 105.94022 -122.278033) (xy 105.866407 -122.372869)
			(xy 105.786487 -122.462619) (xy 105.70081 -122.54689) (xy 105.609751 -122.625316) (xy 105.513707 -122.697551)
			(xy 105.4131 -122.763281) (xy 105.308369 -122.822218) (xy 105.199971 -122.874105) (xy 105.088381 -122.918714)
			(xy 104.974087 -122.95585) (xy 104.857588 -122.985352) (xy 104.739394 -123.007089) (xy 104.620022 -123.020968)
			(xy 104.499994 -123.026927) (xy 104.379835 -123.02494) (xy 104.260069 -123.015016) (xy 104.141221 -122.997198)
			(xy 104.023811 -122.971564) (xy 103.908351 -122.938227) (xy 103.795347 -122.897332) (xy 103.685293 -122.849058)
			(xy 103.57867 -122.793616) (xy 103.475945 -122.731248) (xy 103.377566 -122.662227) (xy 103.283963 -122.586856)
			(xy 103.195547 -122.505463) (xy 103.112703 -122.418404) (xy 103.035794 -122.326061) (xy 102.965157 -122.228837)
			(xy 102.901099 -122.127156) (xy 102.843902 -122.021465) (xy 102.793814 -121.912224) (xy 102.751057 -121.799912)
			(xy 102.715815 -121.685019) (xy 102.688244 -121.568048) (xy 102.668463 -121.449511) (xy 102.65656 -121.329926)
			(xy 102.652587 -121.209816) (xy 66.286888 -121.209816) (xy 66.286391 -121.269904) (xy 66.278449 -121.389817)
			(xy 66.262599 -121.508943) (xy 66.23891 -121.626762) (xy 66.207486 -121.742757) (xy 66.168465 -121.856421)
			(xy 66.122017 -121.967258) (xy 66.068346 -122.074783) (xy 66.007685 -122.178526) (xy 65.9403 -122.278033)
			(xy 65.866487 -122.372869) (xy 65.786567 -122.462619) (xy 65.70089 -122.54689) (xy 65.609831 -122.625316)
			(xy 65.513787 -122.697551) (xy 65.41318 -122.763281) (xy 65.308449 -122.822218) (xy 65.200051 -122.874105)
			(xy 65.088461 -122.918714) (xy 64.974167 -122.95585) (xy 64.857668 -122.985352) (xy 64.739474 -123.007089)
			(xy 64.620102 -123.020968) (xy 64.500074 -123.026927) (xy 64.379915 -123.02494) (xy 64.260149 -123.015016)
			(xy 64.141301 -122.997198) (xy 64.023891 -122.971564) (xy 63.908431 -122.938227) (xy 63.795427 -122.897332)
			(xy 63.685373 -122.849058) (xy 63.57875 -122.793616) (xy 63.476025 -122.731248) (xy 63.377646 -122.662227)
			(xy 63.284043 -122.586856) (xy 63.195627 -122.505463) (xy 63.112783 -122.418404) (xy 63.035874 -122.326061)
			(xy 62.965237 -122.228837) (xy 62.901179 -122.127156) (xy 62.843982 -122.021465) (xy 62.793894 -121.912224)
			(xy 62.751137 -121.799912) (xy 62.715895 -121.685019) (xy 62.688324 -121.568048) (xy 62.668543 -121.449511)
			(xy 62.65664 -121.329926) (xy 62.652667 -121.209816) (xy 29.791898 -121.209816) (xy 29.85764 -121.327499)
			(xy 29.919311 -121.454246) (xy 29.973712 -121.584279) (xy 30.02067 -121.717182) (xy 30.060033 -121.852528)
			(xy 30.091676 -121.989885) (xy 30.115498 -122.128812) (xy 30.131421 -122.268864) (xy 30.139396 -122.409593)
			(xy 30.139894 -122.48007) (xy 30.139396 -122.550547) (xy 30.131421 -122.691276) (xy 30.115498 -122.831328)
			(xy 30.091676 -122.970255) (xy 30.060033 -123.107612) (xy 30.02067 -123.242958) (xy 29.973712 -123.375861)
			(xy 29.919311 -123.505894) (xy 29.85764 -123.632641) (xy 29.788897 -123.755696) (xy 29.713303 -123.874665)
			(xy 29.631099 -123.989167) (xy 29.542548 -124.098835) (xy 29.447935 -124.203317) (xy 29.347563 -124.302279)
			(xy 29.241752 -124.395404) (xy 29.130843 -124.482393) (xy 29.015189 -124.562969) (xy 28.895163 -124.636872)
			(xy 28.771147 -124.703867) (xy 28.64354 -124.763738) (xy 28.51275 -124.816294) (xy 28.379196 -124.861366)
			(xy 28.243306 -124.89881) (xy 28.105515 -124.928506) (xy 27.966265 -124.950359) (xy 27.826002 -124.964299)
			(xy 27.685174 -124.970282) (xy 27.544234 -124.968287) (xy 27.403632 -124.958322) (xy 27.263819 -124.940418)
			(xy 27.125243 -124.914633) (xy 26.988348 -124.88105) (xy 26.853572 -124.839775) (xy 26.721347 -124.790941)
			(xy 26.592097 -124.734706) (xy 26.466235 -124.671247) (xy 26.344165 -124.60077) (xy 26.226278 -124.5235)
			(xy 26.112951 -124.439683) (xy 26.004547 -124.34959) (xy 25.901415 -124.253508) (xy 25.803883 -124.151745)
			(xy 25.712264 -124.044627) (xy 25.626853 -123.932498) (xy 25.547922 -123.815716) (xy 25.475724 -123.694655)
			(xy 25.410492 -123.569704) (xy 25.352432 -123.441262) (xy 25.301732 -123.309742) (xy 25.258555 -123.175563)
			(xy 25.223037 -123.039157) (xy 25.195294 -122.90096) (xy 25.175414 -122.761415) (xy 25.16346 -122.620968)
			(xy 25.159471 -122.48007) (xy 25.043387 -122.48007) (xy 25.043387 -122.570147) (xy 25.035304 -122.750119)
			(xy 25.019155 -122.929548) (xy 24.994973 -123.108071) (xy 24.962805 -123.28533) (xy 24.922717 -123.460967)
			(xy 24.87479 -123.634628) (xy 24.819119 -123.805965) (xy 24.755817 -123.974631) (xy 24.685013 -124.140287)
			(xy 24.606847 -124.3026) (xy 24.521478 -124.461243) (xy 24.429077 -124.615895) (xy 24.329831 -124.766247)
			(xy 24.223939 -124.911994) (xy 24.111615 -125.052844) (xy 23.993085 -125.188513) (xy 23.868587 -125.318727)
			(xy 23.738373 -125.443225) (xy 23.602704 -125.561755) (xy 23.461854 -125.674079) (xy 23.316107 -125.779971)
			(xy 23.165755 -125.879217) (xy 23.011103 -125.971618) (xy 22.85246 -126.056987) (xy 22.690147 -126.135153)
			(xy 22.524491 -126.205957) (xy 22.355825 -126.269259) (xy 22.184488 -126.32493) (xy 22.010827 -126.372857)
			(xy 21.83519 -126.412945) (xy 21.657931 -126.445113) (xy 21.479408 -126.469295) (xy 21.299979 -126.485444)
			(xy 21.154006 -126.492) (xy 42.020472 -126.492) (xy 42.024502 -126.407397) (xy 42.036556 -126.32356)
			(xy 42.056525 -126.241249) (xy 42.084227 -126.161209) (xy 42.119412 -126.084164) (xy 42.161762 -126.010813)
			(xy 42.210892 -125.941819) (xy 42.266358 -125.877808) (xy 42.327658 -125.81936) (xy 42.394236 -125.767002)
			(xy 42.465489 -125.721211) (xy 42.540773 -125.6824) (xy 42.619405 -125.650921) (xy 42.700673 -125.627059)
			(xy 42.783841 -125.61103) (xy 42.868157 -125.60298) (xy 42.910506 -125.602492) (xy 42.956902 -125.603073)
			(xy 43.04919 -125.612718) (xy 43.139974 -125.631915) (xy 43.228267 -125.660454) (xy 43.270932 -125.678692)
			(xy 43.280874 -125.682498) (xy 43.302138 -125.682498) (xy 43.31208 -125.678692) (xy 43.354741 -125.660445)
			(xy 43.443034 -125.631902) (xy 43.533819 -125.612709) (xy 43.62611 -125.603077) (xy 43.672506 -125.602492)
			(xy 43.714854 -125.602996) (xy 43.799167 -125.611047) (xy 43.882333 -125.627077) (xy 43.963599 -125.650939)
			(xy 44.042229 -125.682418) (xy 44.11751 -125.721229) (xy 44.188761 -125.767019) (xy 44.255337 -125.819376)
			(xy 44.316634 -125.877823) (xy 44.372099 -125.941833) (xy 44.421227 -126.010825) (xy 44.463575 -126.084174)
			(xy 44.49876 -126.161217) (xy 44.526461 -126.241256) (xy 44.546429 -126.323565) (xy 44.558482 -126.407399)
			(xy 44.562513 -126.492) (xy 54.212472 -126.492) (xy 54.216502 -126.407397) (xy 54.228556 -126.32356)
			(xy 54.248525 -126.241249) (xy 54.276227 -126.161209) (xy 54.311412 -126.084164) (xy 54.353762 -126.010813)
			(xy 54.402892 -125.941819) (xy 54.458358 -125.877808) (xy 54.519658 -125.81936) (xy 54.586236 -125.767002)
			(xy 54.657489 -125.721211) (xy 54.732773 -125.6824) (xy 54.811405 -125.650921) (xy 54.892673 -125.627059)
			(xy 54.975841 -125.61103) (xy 55.060157 -125.60298) (xy 55.102506 -125.602492) (xy 55.148902 -125.603073)
			(xy 55.24119 -125.612718) (xy 55.331974 -125.631915) (xy 55.420267 -125.660454) (xy 55.462932 -125.678692)
			(xy 55.472874 -125.682498) (xy 55.494138 -125.682498) (xy 55.50408 -125.678692) (xy 55.546741 -125.660445)
			(xy 55.635034 -125.631902) (xy 55.725819 -125.612709) (xy 55.81811 -125.603077) (xy 55.864506 -125.602492)
			(xy 55.906854 -125.602996) (xy 55.991167 -125.611047) (xy 56.074333 -125.627077) (xy 56.155599 -125.650939)
			(xy 56.234229 -125.682418) (xy 56.30951 -125.721229) (xy 56.380761 -125.767019) (xy 56.447337 -125.819376)
			(xy 56.508634 -125.877823) (xy 56.564099 -125.941833) (xy 56.613227 -126.010825) (xy 56.655575 -126.084174)
			(xy 56.69076 -126.161217) (xy 56.718461 -126.241256) (xy 56.738429 -126.323565) (xy 56.750482 -126.407399)
			(xy 56.754513 -126.492) (xy 66.404472 -126.492) (xy 66.408502 -126.407397) (xy 66.420556 -126.32356)
			(xy 66.440525 -126.241249) (xy 66.468227 -126.161209) (xy 66.503412 -126.084164) (xy 66.545762 -126.010813)
			(xy 66.594892 -125.941819) (xy 66.650358 -125.877808) (xy 66.711658 -125.81936) (xy 66.778236 -125.767002)
			(xy 66.849489 -125.721211) (xy 66.924773 -125.6824) (xy 67.003405 -125.650921) (xy 67.084673 -125.627059)
			(xy 67.167841 -125.61103) (xy 67.252157 -125.60298) (xy 67.294506 -125.602492) (xy 67.340902 -125.603073)
			(xy 67.43319 -125.612718) (xy 67.523974 -125.631915) (xy 67.612267 -125.660454) (xy 67.654932 -125.678692)
			(xy 67.664874 -125.682498) (xy 67.686138 -125.682498) (xy 67.69608 -125.678692) (xy 67.738741 -125.660445)
			(xy 67.827034 -125.631902) (xy 67.917819 -125.612709) (xy 68.01011 -125.603077) (xy 68.056506 -125.602492)
			(xy 68.098854 -125.602996) (xy 68.183167 -125.611047) (xy 68.266333 -125.627077) (xy 68.347599 -125.650939)
			(xy 68.426229 -125.682418) (xy 68.50151 -125.721229) (xy 68.572761 -125.767019) (xy 68.639337 -125.819376)
			(xy 68.700634 -125.877823) (xy 68.756099 -125.941833) (xy 68.805227 -126.010825) (xy 68.847575 -126.084174)
			(xy 68.88276 -126.161217) (xy 68.910461 -126.241256) (xy 68.930429 -126.323565) (xy 68.942482 -126.407399)
			(xy 68.946513 -126.492) (xy 82.020372 -126.492) (xy 82.024402 -126.407396) (xy 82.036457 -126.323558)
			(xy 82.056426 -126.241246) (xy 82.084129 -126.161204) (xy 82.119315 -126.084159) (xy 82.161666 -126.010807)
			(xy 82.210798 -125.941813) (xy 82.266265 -125.877801) (xy 82.327566 -125.819352) (xy 82.394146 -125.766995)
			(xy 82.465401 -125.721204) (xy 82.540686 -125.682394) (xy 82.61932 -125.650916) (xy 82.700589 -125.627055)
			(xy 82.783759 -125.611028) (xy 82.868076 -125.602979) (xy 82.910426 -125.602492) (xy 82.956821 -125.603101)
			(xy 83.049109 -125.612738) (xy 83.139892 -125.631927) (xy 83.228187 -125.660458) (xy 83.270852 -125.678692)
			(xy 83.280794 -125.682498) (xy 83.302058 -125.682498) (xy 83.312 -125.678692) (xy 83.354659 -125.660439)
			(xy 83.442952 -125.631897) (xy 83.533738 -125.612706) (xy 83.62603 -125.603076) (xy 83.672426 -125.602492)
			(xy 83.714774 -125.602997) (xy 83.799085 -125.61105) (xy 83.88225 -125.627081) (xy 83.963514 -125.650944)
			(xy 84.042142 -125.682424) (xy 84.117421 -125.721235) (xy 84.188671 -125.767026) (xy 84.255245 -125.819383)
			(xy 84.316541 -125.87783) (xy 84.372004 -125.941839) (xy 84.421131 -126.010831) (xy 84.463478 -126.08418)
			(xy 84.498661 -126.161222) (xy 84.526362 -126.241259) (xy 84.546329 -126.323567) (xy 84.558383 -126.407401)
			(xy 84.562413 -126.492) (xy 94.212372 -126.492) (xy 94.216402 -126.407396) (xy 94.228457 -126.323558)
			(xy 94.248426 -126.241246) (xy 94.276129 -126.161204) (xy 94.311315 -126.084159) (xy 94.353666 -126.010807)
			(xy 94.402798 -125.941813) (xy 94.458265 -125.877801) (xy 94.519566 -125.819352) (xy 94.586146 -125.766995)
			(xy 94.657401 -125.721204) (xy 94.732686 -125.682394) (xy 94.81132 -125.650916) (xy 94.892589 -125.627055)
			(xy 94.975759 -125.611028) (xy 95.060076 -125.602979) (xy 95.102426 -125.602492) (xy 95.148821 -125.603101)
			(xy 95.241109 -125.612738) (xy 95.331892 -125.631927) (xy 95.420187 -125.660458) (xy 95.462852 -125.678692)
			(xy 95.472794 -125.682498) (xy 95.494058 -125.682498) (xy 95.504 -125.678692) (xy 95.546659 -125.660439)
			(xy 95.634952 -125.631897) (xy 95.725738 -125.612706) (xy 95.81803 -125.603076) (xy 95.864426 -125.602492)
			(xy 95.906774 -125.602997) (xy 95.991085 -125.61105) (xy 96.07425 -125.627081) (xy 96.155514 -125.650944)
			(xy 96.234142 -125.682424) (xy 96.309421 -125.721235) (xy 96.380671 -125.767026) (xy 96.447245 -125.819383)
			(xy 96.508541 -125.87783) (xy 96.564004 -125.941839) (xy 96.613131 -126.010831) (xy 96.655478 -126.08418)
			(xy 96.690661 -126.161222) (xy 96.718362 -126.241259) (xy 96.738329 -126.323567) (xy 96.750383 -126.407401)
			(xy 96.754413 -126.492) (xy 106.404372 -126.492) (xy 106.408402 -126.407396) (xy 106.420457 -126.323558)
			(xy 106.440426 -126.241246) (xy 106.468129 -126.161204) (xy 106.503315 -126.084159) (xy 106.545666 -126.010807)
			(xy 106.594798 -125.941813) (xy 106.650265 -125.877801) (xy 106.711566 -125.819352) (xy 106.778146 -125.766995)
			(xy 106.849401 -125.721204) (xy 106.924686 -125.682394) (xy 107.00332 -125.650916) (xy 107.084589 -125.627055)
			(xy 107.167759 -125.611028) (xy 107.252076 -125.602979) (xy 107.294426 -125.602492) (xy 107.340821 -125.603101)
			(xy 107.433109 -125.612738) (xy 107.523892 -125.631927) (xy 107.612187 -125.660458) (xy 107.654852 -125.678692)
			(xy 107.664794 -125.682498) (xy 107.686058 -125.682498) (xy 107.696 -125.678692) (xy 107.738659 -125.660439)
			(xy 107.826952 -125.631897) (xy 107.917738 -125.612706) (xy 108.01003 -125.603076) (xy 108.056426 -125.602492)
			(xy 108.098774 -125.602997) (xy 108.183085 -125.61105) (xy 108.26625 -125.627081) (xy 108.347514 -125.650944)
			(xy 108.426142 -125.682424) (xy 108.501421 -125.721235) (xy 108.572671 -125.767026) (xy 108.639245 -125.819383)
			(xy 108.700541 -125.87783) (xy 108.756004 -125.941839) (xy 108.805131 -126.010831) (xy 108.847478 -126.08418)
			(xy 108.882661 -126.161222) (xy 108.910362 -126.241259) (xy 108.930329 -126.323567) (xy 108.942383 -126.407401)
			(xy 108.946413 -126.492) (xy 122.020588 -126.492) (xy 122.024618 -126.407399) (xy 122.036671 -126.323564)
			(xy 122.056639 -126.241255) (xy 122.084341 -126.161216) (xy 122.119525 -126.084173) (xy 122.161874 -126.010823)
			(xy 122.211003 -125.941831) (xy 122.266468 -125.877821) (xy 122.327766 -125.819373) (xy 122.394342 -125.767017)
			(xy 122.465594 -125.721227) (xy 122.540875 -125.682416) (xy 122.619505 -125.650937) (xy 122.700772 -125.627076)
			(xy 122.783938 -125.611047) (xy 122.868252 -125.602996) (xy 122.9106 -125.602492) (xy 122.956996 -125.603075)
			(xy 123.049284 -125.61272) (xy 123.140068 -125.631916) (xy 123.228361 -125.660454) (xy 123.271026 -125.678692)
			(xy 123.280968 -125.682498) (xy 123.302232 -125.682498) (xy 123.312174 -125.678692) (xy 123.354836 -125.660447)
			(xy 123.443129 -125.631903) (xy 123.533914 -125.61271) (xy 123.626204 -125.603077) (xy 123.6726 -125.602492)
			(xy 123.714948 -125.602996) (xy 123.799262 -125.611047) (xy 123.882428 -125.627076) (xy 123.963695 -125.650937)
			(xy 124.042325 -125.682416) (xy 124.117606 -125.721227) (xy 124.188858 -125.767017) (xy 124.255434 -125.819373)
			(xy 124.316732 -125.877821) (xy 124.372197 -125.941831) (xy 124.421326 -126.010823) (xy 124.463675 -126.084173)
			(xy 124.498859 -126.161216) (xy 124.526561 -126.241255) (xy 124.546529 -126.323564) (xy 124.558582 -126.407399)
			(xy 124.562613 -126.492) (xy 134.212588 -126.492) (xy 134.216618 -126.407399) (xy 134.228671 -126.323564)
			(xy 134.248639 -126.241255) (xy 134.276341 -126.161216) (xy 134.311525 -126.084173) (xy 134.353874 -126.010823)
			(xy 134.403003 -125.941831) (xy 134.458468 -125.877821) (xy 134.519766 -125.819373) (xy 134.586342 -125.767017)
			(xy 134.657594 -125.721227) (xy 134.732875 -125.682416) (xy 134.811505 -125.650937) (xy 134.892772 -125.627076)
			(xy 134.975938 -125.611047) (xy 135.060252 -125.602996) (xy 135.1026 -125.602492) (xy 135.148996 -125.603075)
			(xy 135.241284 -125.61272) (xy 135.332068 -125.631916) (xy 135.420361 -125.660454) (xy 135.463026 -125.678692)
			(xy 135.472968 -125.682498) (xy 135.494232 -125.682498) (xy 135.504174 -125.678692) (xy 135.546836 -125.660447)
			(xy 135.635129 -125.631903) (xy 135.725914 -125.61271) (xy 135.818204 -125.603077) (xy 135.8646 -125.602492)
			(xy 135.906948 -125.602996) (xy 135.991262 -125.611047) (xy 136.074428 -125.627076) (xy 136.155695 -125.650937)
			(xy 136.234325 -125.682416) (xy 136.309606 -125.721227) (xy 136.380858 -125.767017) (xy 136.447434 -125.819373)
			(xy 136.508732 -125.877821) (xy 136.564197 -125.941831) (xy 136.613326 -126.010823) (xy 136.655675 -126.084173)
			(xy 136.690859 -126.161216) (xy 136.718561 -126.241255) (xy 136.738529 -126.323564) (xy 136.750582 -126.407399)
			(xy 136.754613 -126.492) (xy 146.404588 -126.492) (xy 146.408618 -126.407399) (xy 146.420671 -126.323564)
			(xy 146.440639 -126.241255) (xy 146.468341 -126.161216) (xy 146.503525 -126.084173) (xy 146.545874 -126.010823)
			(xy 146.595003 -125.941831) (xy 146.650468 -125.877821) (xy 146.711766 -125.819373) (xy 146.778342 -125.767017)
			(xy 146.849594 -125.721227) (xy 146.924875 -125.682416) (xy 147.003505 -125.650937) (xy 147.084772 -125.627076)
			(xy 147.167938 -125.611047) (xy 147.252252 -125.602996) (xy 147.2946 -125.602492) (xy 147.340996 -125.603075)
			(xy 147.433284 -125.61272) (xy 147.524068 -125.631916) (xy 147.612361 -125.660454) (xy 147.655026 -125.678692)
			(xy 147.664968 -125.682498) (xy 147.686232 -125.682498) (xy 147.696174 -125.678692) (xy 147.738836 -125.660447)
			(xy 147.827129 -125.631903) (xy 147.917914 -125.61271) (xy 148.010204 -125.603077) (xy 148.0566 -125.602492)
			(xy 148.098948 -125.602996) (xy 148.183262 -125.611047) (xy 148.266428 -125.627076) (xy 148.347695 -125.650937)
			(xy 148.426325 -125.682416) (xy 148.501606 -125.721227) (xy 148.572858 -125.767017) (xy 148.639434 -125.819373)
			(xy 148.700732 -125.877821) (xy 148.756197 -125.941831) (xy 148.805326 -126.010823) (xy 148.847675 -126.084173)
			(xy 148.882859 -126.161216) (xy 148.910561 -126.241255) (xy 148.930529 -126.323564) (xy 148.942582 -126.407399)
			(xy 148.946613 -126.492) (xy 162.020787 -126.492) (xy 162.024817 -126.407401) (xy 162.036871 -126.323567)
			(xy 162.056838 -126.241259) (xy 162.084539 -126.161222) (xy 162.119722 -126.08418) (xy 162.162069 -126.010831)
			(xy 162.211196 -125.941839) (xy 162.266659 -125.87783) (xy 162.327955 -125.819383) (xy 162.394529 -125.767026)
			(xy 162.465779 -125.721235) (xy 162.541058 -125.682424) (xy 162.619686 -125.650944) (xy 162.70095 -125.627081)
			(xy 162.784115 -125.61105) (xy 162.868426 -125.602997) (xy 162.910774 -125.602492) (xy 162.957169 -125.603084)
			(xy 163.049457 -125.612726) (xy 163.140241 -125.63192) (xy 163.228535 -125.660455) (xy 163.2712 -125.678692)
			(xy 163.281142 -125.682498) (xy 163.302406 -125.682498) (xy 163.312348 -125.678692) (xy 163.355014 -125.660456)
			(xy 163.443305 -125.63191) (xy 163.534089 -125.612714) (xy 163.626378 -125.603078) (xy 163.672774 -125.602492)
			(xy 163.715124 -125.602979) (xy 163.799441 -125.611028) (xy 163.882611 -125.627055) (xy 163.96388 -125.650916)
			(xy 164.042514 -125.682394) (xy 164.117799 -125.721204) (xy 164.189054 -125.766995) (xy 164.255634 -125.819352)
			(xy 164.316935 -125.877801) (xy 164.372402 -125.941813) (xy 164.421534 -126.010807) (xy 164.463885 -126.084159)
			(xy 164.499071 -126.161204) (xy 164.526774 -126.241246) (xy 164.546743 -126.323558) (xy 164.558798 -126.407396)
			(xy 164.562828 -126.492) (xy 174.212787 -126.492) (xy 174.216817 -126.407401) (xy 174.228871 -126.323567)
			(xy 174.248838 -126.241259) (xy 174.276539 -126.161222) (xy 174.311722 -126.08418) (xy 174.354069 -126.010831)
			(xy 174.403196 -125.941839) (xy 174.458659 -125.87783) (xy 174.519955 -125.819383) (xy 174.586529 -125.767026)
			(xy 174.657779 -125.721235) (xy 174.733058 -125.682424) (xy 174.811686 -125.650944) (xy 174.89295 -125.627081)
			(xy 174.976115 -125.61105) (xy 175.060426 -125.602997) (xy 175.102774 -125.602492) (xy 175.149169 -125.603084)
			(xy 175.241457 -125.612726) (xy 175.332241 -125.63192) (xy 175.420535 -125.660455) (xy 175.4632 -125.678692)
			(xy 175.473142 -125.682498) (xy 175.494406 -125.682498) (xy 175.504348 -125.678692) (xy 175.547014 -125.660456)
			(xy 175.635305 -125.63191) (xy 175.726089 -125.612714) (xy 175.818378 -125.603078) (xy 175.864774 -125.602492)
			(xy 175.907124 -125.602979) (xy 175.991441 -125.611028) (xy 176.074611 -125.627055) (xy 176.15588 -125.650916)
			(xy 176.234514 -125.682394) (xy 176.309799 -125.721204) (xy 176.381054 -125.766995) (xy 176.447634 -125.819352)
			(xy 176.508935 -125.877801) (xy 176.564402 -125.941813) (xy 176.613534 -126.010807) (xy 176.655885 -126.084159)
			(xy 176.691071 -126.161204) (xy 176.718774 -126.241246) (xy 176.738743 -126.323558) (xy 176.750798 -126.407396)
			(xy 176.754828 -126.492) (xy 186.404787 -126.492) (xy 186.408817 -126.407401) (xy 186.420871 -126.323567)
			(xy 186.440838 -126.241259) (xy 186.468539 -126.161222) (xy 186.503722 -126.08418) (xy 186.546069 -126.010831)
			(xy 186.595196 -125.941839) (xy 186.650659 -125.87783) (xy 186.711955 -125.819383) (xy 186.778529 -125.767026)
			(xy 186.849779 -125.721235) (xy 186.925058 -125.682424) (xy 187.003686 -125.650944) (xy 187.08495 -125.627081)
			(xy 187.168115 -125.61105) (xy 187.252426 -125.602997) (xy 187.294774 -125.602492) (xy 187.341169 -125.603084)
			(xy 187.433457 -125.612726) (xy 187.524241 -125.63192) (xy 187.612535 -125.660455) (xy 187.6552 -125.678692)
			(xy 187.665142 -125.682498) (xy 187.686406 -125.682498) (xy 187.696348 -125.678692) (xy 187.739014 -125.660456)
			(xy 187.827305 -125.63191) (xy 187.918089 -125.612714) (xy 188.010378 -125.603078) (xy 188.056774 -125.602492)
			(xy 188.099124 -125.602979) (xy 188.183441 -125.611028) (xy 188.266611 -125.627055) (xy 188.34788 -125.650916)
			(xy 188.426514 -125.682394) (xy 188.501799 -125.721204) (xy 188.573054 -125.766995) (xy 188.639634 -125.819352)
			(xy 188.700935 -125.877801) (xy 188.756402 -125.941813) (xy 188.805534 -126.010807) (xy 188.847885 -126.084159)
			(xy 188.883071 -126.161204) (xy 188.910774 -126.241246) (xy 188.930743 -126.323558) (xy 188.942798 -126.407396)
			(xy 188.946828 -126.492) (xy 188.942798 -126.576604) (xy 188.930743 -126.660442) (xy 188.910774 -126.742754)
			(xy 188.883071 -126.822796) (xy 188.847885 -126.899841) (xy 188.805534 -126.973193) (xy 188.756402 -127.042187)
			(xy 188.700935 -127.106199) (xy 188.639634 -127.164648) (xy 188.573054 -127.217005) (xy 188.501799 -127.262796)
			(xy 188.426514 -127.301606) (xy 188.34788 -127.333084) (xy 188.266611 -127.356945) (xy 188.183441 -127.372972)
			(xy 188.099124 -127.381021) (xy 188.056774 -127.381508) (xy 188.010379 -127.380899) (xy 187.918091 -127.371262)
			(xy 187.827308 -127.352073) (xy 187.739013 -127.323542) (xy 187.696348 -127.305308) (xy 187.686406 -127.301502)
			(xy 187.665142 -127.301502) (xy 187.6552 -127.305308) (xy 187.612541 -127.323561) (xy 187.524248 -127.352103)
			(xy 187.433462 -127.371294) (xy 187.34117 -127.380924) (xy 187.294774 -127.381508) (xy 187.252426 -127.381003)
			(xy 187.168115 -127.37295) (xy 187.08495 -127.356919) (xy 187.003686 -127.333056) (xy 186.925058 -127.301576)
			(xy 186.849779 -127.262765) (xy 186.778529 -127.216974) (xy 186.711955 -127.164617) (xy 186.650659 -127.10617)
			(xy 186.595196 -127.042161) (xy 186.546069 -126.973169) (xy 186.503722 -126.89982) (xy 186.468539 -126.822778)
			(xy 186.440838 -126.742741) (xy 186.420871 -126.660433) (xy 186.408817 -126.576599) (xy 186.404787 -126.492)
			(xy 176.754828 -126.492) (xy 176.750798 -126.576604) (xy 176.738743 -126.660442) (xy 176.718774 -126.742754)
			(xy 176.691071 -126.822796) (xy 176.655885 -126.899841) (xy 176.613534 -126.973193) (xy 176.564402 -127.042187)
			(xy 176.508935 -127.106199) (xy 176.447634 -127.164648) (xy 176.381054 -127.217005) (xy 176.309799 -127.262796)
			(xy 176.234514 -127.301606) (xy 176.15588 -127.333084) (xy 176.074611 -127.356945) (xy 175.991441 -127.372972)
			(xy 175.907124 -127.381021) (xy 175.864774 -127.381508) (xy 175.818379 -127.380899) (xy 175.726091 -127.371262)
			(xy 175.635308 -127.352073) (xy 175.547013 -127.323542) (xy 175.504348 -127.305308) (xy 175.494406 -127.301502)
			(xy 175.473142 -127.301502) (xy 175.4632 -127.305308) (xy 175.420541 -127.323561) (xy 175.332248 -127.352103)
			(xy 175.241462 -127.371294) (xy 175.14917 -127.380924) (xy 175.102774 -127.381508) (xy 175.060426 -127.381003)
			(xy 174.976115 -127.37295) (xy 174.89295 -127.356919) (xy 174.811686 -127.333056) (xy 174.733058 -127.301576)
			(xy 174.657779 -127.262765) (xy 174.586529 -127.216974) (xy 174.519955 -127.164617) (xy 174.458659 -127.10617)
			(xy 174.403196 -127.042161) (xy 174.354069 -126.973169) (xy 174.311722 -126.89982) (xy 174.276539 -126.822778)
			(xy 174.248838 -126.742741) (xy 174.228871 -126.660433) (xy 174.216817 -126.576599) (xy 174.212787 -126.492)
			(xy 164.562828 -126.492) (xy 164.558798 -126.576604) (xy 164.546743 -126.660442) (xy 164.526774 -126.742754)
			(xy 164.499071 -126.822796) (xy 164.463885 -126.899841) (xy 164.421534 -126.973193) (xy 164.372402 -127.042187)
			(xy 164.316935 -127.106199) (xy 164.255634 -127.164648) (xy 164.189054 -127.217005) (xy 164.117799 -127.262796)
			(xy 164.042514 -127.301606) (xy 163.96388 -127.333084) (xy 163.882611 -127.356945) (xy 163.799441 -127.372972)
			(xy 163.715124 -127.381021) (xy 163.672774 -127.381508) (xy 163.626379 -127.380899) (xy 163.534091 -127.371262)
			(xy 163.443308 -127.352073) (xy 163.355013 -127.323542) (xy 163.312348 -127.305308) (xy 163.302406 -127.301502)
			(xy 163.281142 -127.301502) (xy 163.2712 -127.305308) (xy 163.228541 -127.323561) (xy 163.140248 -127.352103)
			(xy 163.049462 -127.371294) (xy 162.95717 -127.380924) (xy 162.910774 -127.381508) (xy 162.868426 -127.381003)
			(xy 162.784115 -127.37295) (xy 162.70095 -127.356919) (xy 162.619686 -127.333056) (xy 162.541058 -127.301576)
			(xy 162.465779 -127.262765) (xy 162.394529 -127.216974) (xy 162.327955 -127.164617) (xy 162.266659 -127.10617)
			(xy 162.211196 -127.042161) (xy 162.162069 -126.973169) (xy 162.119722 -126.89982) (xy 162.084539 -126.822778)
			(xy 162.056838 -126.742741) (xy 162.036871 -126.660433) (xy 162.024817 -126.576599) (xy 162.020787 -126.492)
			(xy 148.946613 -126.492) (xy 148.942582 -126.576601) (xy 148.930529 -126.660436) (xy 148.910561 -126.742745)
			(xy 148.882859 -126.822784) (xy 148.847675 -126.899827) (xy 148.805326 -126.973177) (xy 148.756197 -127.042169)
			(xy 148.700732 -127.106179) (xy 148.639434 -127.164627) (xy 148.572858 -127.216983) (xy 148.501606 -127.262773)
			(xy 148.426325 -127.301584) (xy 148.347695 -127.333063) (xy 148.266428 -127.356924) (xy 148.183262 -127.372953)
			(xy 148.098948 -127.381004) (xy 148.0566 -127.381508) (xy 148.010204 -127.380925) (xy 147.917916 -127.37128)
			(xy 147.827132 -127.352084) (xy 147.738839 -127.323546) (xy 147.696174 -127.305308) (xy 147.686232 -127.301502)
			(xy 147.664968 -127.301502) (xy 147.655026 -127.305308) (xy 147.612364 -127.323553) (xy 147.524071 -127.352097)
			(xy 147.433286 -127.37129) (xy 147.340996 -127.380923) (xy 147.2946 -127.381508) (xy 147.252252 -127.381004)
			(xy 147.167938 -127.372953) (xy 147.084772 -127.356924) (xy 147.003505 -127.333063) (xy 146.924875 -127.301584)
			(xy 146.849594 -127.262773) (xy 146.778342 -127.216983) (xy 146.711766 -127.164627) (xy 146.650468 -127.106179)
			(xy 146.595003 -127.042169) (xy 146.545874 -126.973177) (xy 146.503525 -126.899827) (xy 146.468341 -126.822784)
			(xy 146.440639 -126.742745) (xy 146.420671 -126.660436) (xy 146.408618 -126.576601) (xy 146.404588 -126.492)
			(xy 136.754613 -126.492) (xy 136.750582 -126.576601) (xy 136.738529 -126.660436) (xy 136.718561 -126.742745)
			(xy 136.690859 -126.822784) (xy 136.655675 -126.899827) (xy 136.613326 -126.973177) (xy 136.564197 -127.042169)
			(xy 136.508732 -127.106179) (xy 136.447434 -127.164627) (xy 136.380858 -127.216983) (xy 136.309606 -127.262773)
			(xy 136.234325 -127.301584) (xy 136.155695 -127.333063) (xy 136.074428 -127.356924) (xy 135.991262 -127.372953)
			(xy 135.906948 -127.381004) (xy 135.8646 -127.381508) (xy 135.818204 -127.380925) (xy 135.725916 -127.37128)
			(xy 135.635132 -127.352084) (xy 135.546839 -127.323546) (xy 135.504174 -127.305308) (xy 135.494232 -127.301502)
			(xy 135.472968 -127.301502) (xy 135.463026 -127.305308) (xy 135.420364 -127.323553) (xy 135.332071 -127.352097)
			(xy 135.241286 -127.37129) (xy 135.148996 -127.380923) (xy 135.1026 -127.381508) (xy 135.060252 -127.381004)
			(xy 134.975938 -127.372953) (xy 134.892772 -127.356924) (xy 134.811505 -127.333063) (xy 134.732875 -127.301584)
			(xy 134.657594 -127.262773) (xy 134.586342 -127.216983) (xy 134.519766 -127.164627) (xy 134.458468 -127.106179)
			(xy 134.403003 -127.042169) (xy 134.353874 -126.973177) (xy 134.311525 -126.899827) (xy 134.276341 -126.822784)
			(xy 134.248639 -126.742745) (xy 134.228671 -126.660436) (xy 134.216618 -126.576601) (xy 134.212588 -126.492)
			(xy 124.562613 -126.492) (xy 124.558582 -126.576601) (xy 124.546529 -126.660436) (xy 124.526561 -126.742745)
			(xy 124.498859 -126.822784) (xy 124.463675 -126.899827) (xy 124.421326 -126.973177) (xy 124.372197 -127.042169)
			(xy 124.316732 -127.106179) (xy 124.255434 -127.164627) (xy 124.188858 -127.216983) (xy 124.117606 -127.262773)
			(xy 124.042325 -127.301584) (xy 123.963695 -127.333063) (xy 123.882428 -127.356924) (xy 123.799262 -127.372953)
			(xy 123.714948 -127.381004) (xy 123.6726 -127.381508) (xy 123.626204 -127.380925) (xy 123.533916 -127.37128)
			(xy 123.443132 -127.352084) (xy 123.354839 -127.323546) (xy 123.312174 -127.305308) (xy 123.302232 -127.301502)
			(xy 123.280968 -127.301502) (xy 123.271026 -127.305308) (xy 123.228364 -127.323553) (xy 123.140071 -127.352097)
			(xy 123.049286 -127.37129) (xy 122.956996 -127.380923) (xy 122.9106 -127.381508) (xy 122.868252 -127.381004)
			(xy 122.783938 -127.372953) (xy 122.700772 -127.356924) (xy 122.619505 -127.333063) (xy 122.540875 -127.301584)
			(xy 122.465594 -127.262773) (xy 122.394342 -127.216983) (xy 122.327766 -127.164627) (xy 122.266468 -127.106179)
			(xy 122.211003 -127.042169) (xy 122.161874 -126.973177) (xy 122.119525 -126.899827) (xy 122.084341 -126.822784)
			(xy 122.056639 -126.742745) (xy 122.036671 -126.660436) (xy 122.024618 -126.576601) (xy 122.020588 -126.492)
			(xy 108.946413 -126.492) (xy 108.942383 -126.576599) (xy 108.930329 -126.660433) (xy 108.910362 -126.742741)
			(xy 108.882661 -126.822778) (xy 108.847478 -126.89982) (xy 108.805131 -126.973169) (xy 108.756004 -127.042161)
			(xy 108.700541 -127.10617) (xy 108.639245 -127.164617) (xy 108.572671 -127.216974) (xy 108.501421 -127.262765)
			(xy 108.426142 -127.301576) (xy 108.347514 -127.333056) (xy 108.26625 -127.356919) (xy 108.183085 -127.37295)
			(xy 108.098774 -127.381003) (xy 108.056426 -127.381508) (xy 108.010031 -127.380916) (xy 107.917743 -127.371274)
			(xy 107.826959 -127.35208) (xy 107.738665 -127.323545) (xy 107.696 -127.305308) (xy 107.686058 -127.301502)
			(xy 107.664794 -127.301502) (xy 107.654852 -127.305308) (xy 107.612186 -127.323544) (xy 107.523895 -127.35209)
			(xy 107.433111 -127.371286) (xy 107.340822 -127.380922) (xy 107.294426 -127.381508) (xy 107.252076 -127.381021)
			(xy 107.167759 -127.372972) (xy 107.084589 -127.356945) (xy 107.00332 -127.333084) (xy 106.924686 -127.301606)
			(xy 106.849401 -127.262796) (xy 106.778146 -127.217005) (xy 106.711566 -127.164648) (xy 106.650265 -127.106199)
			(xy 106.594798 -127.042187) (xy 106.545666 -126.973193) (xy 106.503315 -126.899841) (xy 106.468129 -126.822796)
			(xy 106.440426 -126.742754) (xy 106.420457 -126.660442) (xy 106.408402 -126.576604) (xy 106.404372 -126.492)
			(xy 96.754413 -126.492) (xy 96.750383 -126.576599) (xy 96.738329 -126.660433) (xy 96.718362 -126.742741)
			(xy 96.690661 -126.822778) (xy 96.655478 -126.89982) (xy 96.613131 -126.973169) (xy 96.564004 -127.042161)
			(xy 96.508541 -127.10617) (xy 96.447245 -127.164617) (xy 96.380671 -127.216974) (xy 96.309421 -127.262765)
			(xy 96.234142 -127.301576) (xy 96.155514 -127.333056) (xy 96.07425 -127.356919) (xy 95.991085 -127.37295)
			(xy 95.906774 -127.381003) (xy 95.864426 -127.381508) (xy 95.818031 -127.380916) (xy 95.725743 -127.371274)
			(xy 95.634959 -127.35208) (xy 95.546665 -127.323545) (xy 95.504 -127.305308) (xy 95.494058 -127.301502)
			(xy 95.472794 -127.301502) (xy 95.462852 -127.305308) (xy 95.420186 -127.323544) (xy 95.331895 -127.35209)
			(xy 95.241111 -127.371286) (xy 95.148822 -127.380922) (xy 95.102426 -127.381508) (xy 95.060076 -127.381021)
			(xy 94.975759 -127.372972) (xy 94.892589 -127.356945) (xy 94.81132 -127.333084) (xy 94.732686 -127.301606)
			(xy 94.657401 -127.262796) (xy 94.586146 -127.217005) (xy 94.519566 -127.164648) (xy 94.458265 -127.106199)
			(xy 94.402798 -127.042187) (xy 94.353666 -126.973193) (xy 94.311315 -126.899841) (xy 94.276129 -126.822796)
			(xy 94.248426 -126.742754) (xy 94.228457 -126.660442) (xy 94.216402 -126.576604) (xy 94.212372 -126.492)
			(xy 84.562413 -126.492) (xy 84.558383 -126.576599) (xy 84.546329 -126.660433) (xy 84.526362 -126.742741)
			(xy 84.498661 -126.822778) (xy 84.463478 -126.89982) (xy 84.421131 -126.973169) (xy 84.372004 -127.042161)
			(xy 84.316541 -127.10617) (xy 84.255245 -127.164617) (xy 84.188671 -127.216974) (xy 84.117421 -127.262765)
			(xy 84.042142 -127.301576) (xy 83.963514 -127.333056) (xy 83.88225 -127.356919) (xy 83.799085 -127.37295)
			(xy 83.714774 -127.381003) (xy 83.672426 -127.381508) (xy 83.626031 -127.380916) (xy 83.533743 -127.371274)
			(xy 83.442959 -127.35208) (xy 83.354665 -127.323545) (xy 83.312 -127.305308) (xy 83.302058 -127.301502)
			(xy 83.280794 -127.301502) (xy 83.270852 -127.305308) (xy 83.228186 -127.323544) (xy 83.139895 -127.35209)
			(xy 83.049111 -127.371286) (xy 82.956822 -127.380922) (xy 82.910426 -127.381508) (xy 82.868076 -127.381021)
			(xy 82.783759 -127.372972) (xy 82.700589 -127.356945) (xy 82.61932 -127.333084) (xy 82.540686 -127.301606)
			(xy 82.465401 -127.262796) (xy 82.394146 -127.217005) (xy 82.327566 -127.164648) (xy 82.266265 -127.106199)
			(xy 82.210798 -127.042187) (xy 82.161666 -126.973193) (xy 82.119315 -126.899841) (xy 82.084129 -126.822796)
			(xy 82.056426 -126.742754) (xy 82.036457 -126.660442) (xy 82.024402 -126.576604) (xy 82.020372 -126.492)
			(xy 68.946513 -126.492) (xy 68.942482 -126.576601) (xy 68.930429 -126.660435) (xy 68.910461 -126.742744)
			(xy 68.88276 -126.822783) (xy 68.847575 -126.899826) (xy 68.805227 -126.973175) (xy 68.756099 -127.042167)
			(xy 68.700634 -127.106177) (xy 68.639337 -127.164624) (xy 68.572761 -127.216981) (xy 68.50151 -127.262771)
			(xy 68.426229 -127.301582) (xy 68.347599 -127.333061) (xy 68.266333 -127.356923) (xy 68.183167 -127.372953)
			(xy 68.098854 -127.381004) (xy 68.056506 -127.381508) (xy 68.01011 -127.380923) (xy 67.917822 -127.371279)
			(xy 67.827038 -127.352083) (xy 67.738745 -127.323546) (xy 67.69608 -127.305308) (xy 67.686138 -127.301502)
			(xy 67.664874 -127.301502) (xy 67.654932 -127.305308) (xy 67.612269 -127.323551) (xy 67.523977 -127.352095)
			(xy 67.433192 -127.371289) (xy 67.340902 -127.380923) (xy 67.294506 -127.381508) (xy 67.252157 -127.38102)
			(xy 67.167841 -127.37297) (xy 67.084673 -127.356941) (xy 67.003405 -127.333079) (xy 66.924773 -127.3016)
			(xy 66.849489 -127.262789) (xy 66.778236 -127.216998) (xy 66.711658 -127.16464) (xy 66.650358 -127.106192)
			(xy 66.594892 -127.042181) (xy 66.545762 -126.973187) (xy 66.503412 -126.899836) (xy 66.468227 -126.822791)
			(xy 66.440525 -126.742751) (xy 66.420556 -126.66044) (xy 66.408502 -126.576603) (xy 66.404472 -126.492)
			(xy 56.754513 -126.492) (xy 56.750482 -126.576601) (xy 56.738429 -126.660435) (xy 56.718461 -126.742744)
			(xy 56.69076 -126.822783) (xy 56.655575 -126.899826) (xy 56.613227 -126.973175) (xy 56.564099 -127.042167)
			(xy 56.508634 -127.106177) (xy 56.447337 -127.164624) (xy 56.380761 -127.216981) (xy 56.30951 -127.262771)
			(xy 56.234229 -127.301582) (xy 56.155599 -127.333061) (xy 56.074333 -127.356923) (xy 55.991167 -127.372953)
			(xy 55.906854 -127.381004) (xy 55.864506 -127.381508) (xy 55.81811 -127.380923) (xy 55.725822 -127.371279)
			(xy 55.635038 -127.352083) (xy 55.546745 -127.323546) (xy 55.50408 -127.305308) (xy 55.494138 -127.301502)
			(xy 55.472874 -127.301502) (xy 55.462932 -127.305308) (xy 55.420269 -127.323551) (xy 55.331977 -127.352095)
			(xy 55.241192 -127.371289) (xy 55.148902 -127.380923) (xy 55.102506 -127.381508) (xy 55.060157 -127.38102)
			(xy 54.975841 -127.37297) (xy 54.892673 -127.356941) (xy 54.811405 -127.333079) (xy 54.732773 -127.3016)
			(xy 54.657489 -127.262789) (xy 54.586236 -127.216998) (xy 54.519658 -127.16464) (xy 54.458358 -127.106192)
			(xy 54.402892 -127.042181) (xy 54.353762 -126.973187) (xy 54.311412 -126.899836) (xy 54.276227 -126.822791)
			(xy 54.248525 -126.742751) (xy 54.228556 -126.66044) (xy 54.216502 -126.576603) (xy 54.212472 -126.492)
			(xy 44.562513 -126.492) (xy 44.558482 -126.576601) (xy 44.546429 -126.660435) (xy 44.526461 -126.742744)
			(xy 44.49876 -126.822783) (xy 44.463575 -126.899826) (xy 44.421227 -126.973175) (xy 44.372099 -127.042167)
			(xy 44.316634 -127.106177) (xy 44.255337 -127.164624) (xy 44.188761 -127.216981) (xy 44.11751 -127.262771)
			(xy 44.042229 -127.301582) (xy 43.963599 -127.333061) (xy 43.882333 -127.356923) (xy 43.799167 -127.372953)
			(xy 43.714854 -127.381004) (xy 43.672506 -127.381508) (xy 43.62611 -127.380923) (xy 43.533822 -127.371279)
			(xy 43.443038 -127.352083) (xy 43.354745 -127.323546) (xy 43.31208 -127.305308) (xy 43.302138 -127.301502)
			(xy 43.280874 -127.301502) (xy 43.270932 -127.305308) (xy 43.228269 -127.323551) (xy 43.139977 -127.352095)
			(xy 43.049192 -127.371289) (xy 42.956902 -127.380923) (xy 42.910506 -127.381508) (xy 42.868157 -127.38102)
			(xy 42.783841 -127.37297) (xy 42.700673 -127.356941) (xy 42.619405 -127.333079) (xy 42.540773 -127.3016)
			(xy 42.465489 -127.262789) (xy 42.394236 -127.216998) (xy 42.327658 -127.16464) (xy 42.266358 -127.106192)
			(xy 42.210892 -127.042181) (xy 42.161762 -126.973187) (xy 42.119412 -126.899836) (xy 42.084227 -126.822791)
			(xy 42.056525 -126.742751) (xy 42.036556 -126.66044) (xy 42.024502 -126.576603) (xy 42.020472 -126.492)
			(xy 21.154006 -126.492) (xy 21.120007 -126.493527) (xy 21.02993 -126.494032) (xy 20.93918 -126.493524)
			(xy 20.757865 -126.48532) (xy 20.577106 -126.468929) (xy 20.397272 -126.444384) (xy 20.218732 -126.411736)
			(xy 20.04185 -126.371051) (xy 19.866988 -126.322413) (xy 19.694503 -126.265921) (xy 19.524747 -126.20169)
			(xy 19.358069 -126.129852) (xy 19.194807 -126.050553) (xy 19.035297 -125.963956) (xy 18.879864 -125.870238)
			(xy 18.728826 -125.76959) (xy 18.582492 -125.662218) (xy 18.44116 -125.548342) (xy 18.30512 -125.428193)
			(xy 18.17465 -125.302019) (xy 18.050016 -125.170076) (xy 17.931473 -125.032635) (xy 17.819264 -124.889976)
			(xy 17.713618 -124.742391) (xy 17.61475 -124.590181) (xy 17.522864 -124.433659) (xy 17.438146 -124.273143)
			(xy 17.399 -124.191268) (xy 17.393666 -124.179584) (xy 17.3736 -124.164598) (xy 17.264888 -124.148088)
			(xy 17.241266 -124.156216) (xy 17.232376 -124.165868) (xy 17.184455 -124.217229) (xy 17.083658 -124.315088)
			(xy 16.977503 -124.407108) (xy 16.866328 -124.492995) (xy 16.750487 -124.572477) (xy 16.630349 -124.6453)
			(xy 16.506295 -124.711232) (xy 16.37872 -124.770064) (xy 16.248031 -124.821609) (xy 16.114643 -124.865702)
			(xy 15.978981 -124.902204) (xy 15.841477 -124.930997) (xy 15.702568 -124.951991) (xy 15.562696 -124.965118)
			(xy 15.422307 -124.970337) (xy 15.281846 -124.967632) (xy 15.141762 -124.95701) (xy 15.002499 -124.938506)
			(xy 14.864501 -124.912178) (xy 14.728208 -124.87811) (xy 14.594052 -124.836411) (xy 14.462462 -124.787214)
			(xy 14.333855 -124.730674) (xy 14.208641 -124.666973) (xy 14.087218 -124.596312) (xy 13.969973 -124.518916)
			(xy 13.857279 -124.435032) (xy 13.749494 -124.344927) (xy 13.646962 -124.248887) (xy 13.550008 -124.147219)
			(xy 13.458942 -124.040245) (xy 13.374053 -123.928306) (xy 13.295611 -123.811758) (xy 13.223867 -123.690972)
			(xy 13.159047 -123.566333) (xy 13.101359 -123.438237) (xy 13.050986 -123.307092) (xy 13.008088 -123.173315)
			(xy 12.972802 -123.037332) (xy 12.94524 -122.899576) (xy 12.92549 -122.760485) (xy 12.913615 -122.620501)
			(xy 12.909653 -122.48007) (xy 10.609072 -122.48007) (xy 10.609072 -128.230122) (xy 10.608605 -128.27415)
			(xy 10.60093 -128.361872) (xy 10.585639 -128.448591) (xy 10.562848 -128.533648) (xy 10.532731 -128.616394)
			(xy 10.495516 -128.696201) (xy 10.451487 -128.77246) (xy 10.40098 -128.844592) (xy 10.344377 -128.912047)
			(xy 10.282112 -128.974313) (xy 10.214656 -129.030914) (xy 10.142523 -129.081422) (xy 10.066264 -129.12545)
			(xy 9.986457 -129.162664) (xy 9.90371 -129.192781) (xy 9.818654 -129.215571) (xy 9.731934 -129.230861)
			(xy 9.644212 -129.238536) (xy 9.600184 -129.23901) (xy 2.999994 -129.23901) (xy 2.930118 -129.2395)
			(xy 2.790585 -129.247336) (xy 2.651711 -129.262984) (xy 2.513933 -129.286393) (xy 2.377684 -129.317491)
			(xy 2.243393 -129.35618) (xy 2.111483 -129.402337) (xy 1.982368 -129.455818) (xy 1.856456 -129.516454)
			(xy 1.734141 -129.584055) (xy 1.615809 -129.658408) (xy 1.501832 -129.739279) (xy 1.392569 -129.826414)
			(xy 1.288363 -129.919537) (xy 1.189543 -130.018357) (xy 1.09642 -130.122563) (xy 1.009285 -130.231826)
			(xy 0.928414 -130.345803) (xy 0.854061 -130.464135) (xy 0.78646 -130.58645) (xy 0.725824 -130.712362)
			(xy 0.672343 -130.841477) (xy 0.626186 -130.973387) (xy 0.587497 -131.107678) (xy 0.556399 -131.243927)
			(xy 0.53299 -131.381705) (xy 0.517342 -131.520579) (xy 0.514454 -131.572) (xy 42.020472 -131.572)
			(xy 42.024502 -131.487397) (xy 42.036556 -131.40356) (xy 42.056525 -131.321249) (xy 42.084227 -131.241209)
			(xy 42.119412 -131.164164) (xy 42.161762 -131.090813) (xy 42.210892 -131.021819) (xy 42.266358 -130.957808)
			(xy 42.327658 -130.89936) (xy 42.394236 -130.847002) (xy 42.465489 -130.801211) (xy 42.540773 -130.7624)
			(xy 42.619405 -130.730921) (xy 42.700673 -130.707059) (xy 42.783841 -130.69103) (xy 42.868157 -130.68298)
			(xy 42.910506 -130.682492) (xy 42.956902 -130.683073) (xy 43.04919 -130.692718) (xy 43.139974 -130.711915)
			(xy 43.228267 -130.740454) (xy 43.270932 -130.758692) (xy 43.280874 -130.762498) (xy 43.302138 -130.762498)
			(xy 43.31208 -130.758692) (xy 43.354741 -130.740445) (xy 43.443034 -130.711902) (xy 43.533819 -130.692709)
			(xy 43.62611 -130.683077) (xy 43.672506 -130.682492) (xy 43.714854 -130.682996) (xy 43.799167 -130.691047)
			(xy 43.882333 -130.707077) (xy 43.963599 -130.730939) (xy 44.042229 -130.762418) (xy 44.11751 -130.801229)
			(xy 44.188761 -130.847019) (xy 44.255337 -130.899376) (xy 44.316634 -130.957823) (xy 44.372099 -131.021833)
			(xy 44.421227 -131.090825) (xy 44.463575 -131.164174) (xy 44.49876 -131.241217) (xy 44.526461 -131.321256)
			(xy 44.546429 -131.403565) (xy 44.558482 -131.487399) (xy 44.562513 -131.572) (xy 54.212472 -131.572)
			(xy 54.216502 -131.487397) (xy 54.228556 -131.40356) (xy 54.248525 -131.321249) (xy 54.276227 -131.241209)
			(xy 54.311412 -131.164164) (xy 54.353762 -131.090813) (xy 54.402892 -131.021819) (xy 54.458358 -130.957808)
			(xy 54.519658 -130.89936) (xy 54.586236 -130.847002) (xy 54.657489 -130.801211) (xy 54.732773 -130.7624)
			(xy 54.811405 -130.730921) (xy 54.892673 -130.707059) (xy 54.975841 -130.69103) (xy 55.060157 -130.68298)
			(xy 55.102506 -130.682492) (xy 55.148902 -130.683073) (xy 55.24119 -130.692718) (xy 55.331974 -130.711915)
			(xy 55.420267 -130.740454) (xy 55.462932 -130.758692) (xy 55.472874 -130.762498) (xy 55.494138 -130.762498)
			(xy 55.50408 -130.758692) (xy 55.546741 -130.740445) (xy 55.635034 -130.711902) (xy 55.725819 -130.692709)
			(xy 55.81811 -130.683077) (xy 55.864506 -130.682492) (xy 55.906854 -130.682996) (xy 55.991167 -130.691047)
			(xy 56.074333 -130.707077) (xy 56.155599 -130.730939) (xy 56.234229 -130.762418) (xy 56.30951 -130.801229)
			(xy 56.380761 -130.847019) (xy 56.447337 -130.899376) (xy 56.508634 -130.957823) (xy 56.564099 -131.021833)
			(xy 56.613227 -131.090825) (xy 56.655575 -131.164174) (xy 56.69076 -131.241217) (xy 56.718461 -131.321256)
			(xy 56.738429 -131.403565) (xy 56.750482 -131.487399) (xy 56.754513 -131.572) (xy 66.404472 -131.572)
			(xy 66.408502 -131.487397) (xy 66.420556 -131.40356) (xy 66.440525 -131.321249) (xy 66.468227 -131.241209)
			(xy 66.503412 -131.164164) (xy 66.545762 -131.090813) (xy 66.594892 -131.021819) (xy 66.650358 -130.957808)
			(xy 66.711658 -130.89936) (xy 66.778236 -130.847002) (xy 66.849489 -130.801211) (xy 66.924773 -130.7624)
			(xy 67.003405 -130.730921) (xy 67.084673 -130.707059) (xy 67.167841 -130.69103) (xy 67.252157 -130.68298)
			(xy 67.294506 -130.682492) (xy 67.340902 -130.683073) (xy 67.43319 -130.692718) (xy 67.523974 -130.711915)
			(xy 67.612267 -130.740454) (xy 67.654932 -130.758692) (xy 67.664874 -130.762498) (xy 67.686138 -130.762498)
			(xy 67.69608 -130.758692) (xy 67.738741 -130.740445) (xy 67.827034 -130.711902) (xy 67.917819 -130.692709)
			(xy 68.01011 -130.683077) (xy 68.056506 -130.682492) (xy 68.098854 -130.682996) (xy 68.183167 -130.691047)
			(xy 68.266333 -130.707077) (xy 68.347599 -130.730939) (xy 68.426229 -130.762418) (xy 68.50151 -130.801229)
			(xy 68.572761 -130.847019) (xy 68.639337 -130.899376) (xy 68.700634 -130.957823) (xy 68.756099 -131.021833)
			(xy 68.805227 -131.090825) (xy 68.847575 -131.164174) (xy 68.88276 -131.241217) (xy 68.910461 -131.321256)
			(xy 68.930429 -131.403565) (xy 68.942482 -131.487399) (xy 68.946513 -131.572) (xy 82.020372 -131.572)
			(xy 82.024402 -131.487396) (xy 82.036457 -131.403558) (xy 82.056426 -131.321246) (xy 82.084129 -131.241204)
			(xy 82.119315 -131.164159) (xy 82.161666 -131.090807) (xy 82.210798 -131.021813) (xy 82.266265 -130.957801)
			(xy 82.327566 -130.899352) (xy 82.394146 -130.846995) (xy 82.465401 -130.801204) (xy 82.540686 -130.762394)
			(xy 82.61932 -130.730916) (xy 82.700589 -130.707055) (xy 82.783759 -130.691028) (xy 82.868076 -130.682979)
			(xy 82.910426 -130.682492) (xy 82.956821 -130.683101) (xy 83.049109 -130.692738) (xy 83.139892 -130.711927)
			(xy 83.228187 -130.740458) (xy 83.270852 -130.758692) (xy 83.280794 -130.762498) (xy 83.302058 -130.762498)
			(xy 83.312 -130.758692) (xy 83.354659 -130.740439) (xy 83.442952 -130.711897) (xy 83.533738 -130.692706)
			(xy 83.62603 -130.683076) (xy 83.672426 -130.682492) (xy 83.714774 -130.682997) (xy 83.799085 -130.69105)
			(xy 83.88225 -130.707081) (xy 83.963514 -130.730944) (xy 84.042142 -130.762424) (xy 84.117421 -130.801235)
			(xy 84.188671 -130.847026) (xy 84.255245 -130.899383) (xy 84.316541 -130.95783) (xy 84.372004 -131.021839)
			(xy 84.421131 -131.090831) (xy 84.463478 -131.16418) (xy 84.498661 -131.241222) (xy 84.526362 -131.321259)
			(xy 84.546329 -131.403567) (xy 84.558383 -131.487401) (xy 84.562413 -131.572) (xy 94.212372 -131.572)
			(xy 94.216402 -131.487396) (xy 94.228457 -131.403558) (xy 94.248426 -131.321246) (xy 94.276129 -131.241204)
			(xy 94.311315 -131.164159) (xy 94.353666 -131.090807) (xy 94.402798 -131.021813) (xy 94.458265 -130.957801)
			(xy 94.519566 -130.899352) (xy 94.586146 -130.846995) (xy 94.657401 -130.801204) (xy 94.732686 -130.762394)
			(xy 94.81132 -130.730916) (xy 94.892589 -130.707055) (xy 94.975759 -130.691028) (xy 95.060076 -130.682979)
			(xy 95.102426 -130.682492) (xy 95.148821 -130.683101) (xy 95.241109 -130.692738) (xy 95.331892 -130.711927)
			(xy 95.420187 -130.740458) (xy 95.462852 -130.758692) (xy 95.472794 -130.762498) (xy 95.494058 -130.762498)
			(xy 95.504 -130.758692) (xy 95.546659 -130.740439) (xy 95.634952 -130.711897) (xy 95.725738 -130.692706)
			(xy 95.81803 -130.683076) (xy 95.864426 -130.682492) (xy 95.906774 -130.682997) (xy 95.991085 -130.69105)
			(xy 96.07425 -130.707081) (xy 96.155514 -130.730944) (xy 96.234142 -130.762424) (xy 96.309421 -130.801235)
			(xy 96.380671 -130.847026) (xy 96.447245 -130.899383) (xy 96.508541 -130.95783) (xy 96.564004 -131.021839)
			(xy 96.613131 -131.090831) (xy 96.655478 -131.16418) (xy 96.690661 -131.241222) (xy 96.718362 -131.321259)
			(xy 96.738329 -131.403567) (xy 96.750383 -131.487401) (xy 96.754413 -131.572) (xy 106.404372 -131.572)
			(xy 106.408402 -131.487396) (xy 106.420457 -131.403558) (xy 106.440426 -131.321246) (xy 106.468129 -131.241204)
			(xy 106.503315 -131.164159) (xy 106.545666 -131.090807) (xy 106.594798 -131.021813) (xy 106.650265 -130.957801)
			(xy 106.711566 -130.899352) (xy 106.778146 -130.846995) (xy 106.849401 -130.801204) (xy 106.924686 -130.762394)
			(xy 107.00332 -130.730916) (xy 107.084589 -130.707055) (xy 107.167759 -130.691028) (xy 107.252076 -130.682979)
			(xy 107.294426 -130.682492) (xy 107.340821 -130.683101) (xy 107.433109 -130.692738) (xy 107.523892 -130.711927)
			(xy 107.612187 -130.740458) (xy 107.654852 -130.758692) (xy 107.664794 -130.762498) (xy 107.686058 -130.762498)
			(xy 107.696 -130.758692) (xy 107.738659 -130.740439) (xy 107.826952 -130.711897) (xy 107.917738 -130.692706)
			(xy 108.01003 -130.683076) (xy 108.056426 -130.682492) (xy 108.098774 -130.682997) (xy 108.183085 -130.69105)
			(xy 108.26625 -130.707081) (xy 108.347514 -130.730944) (xy 108.426142 -130.762424) (xy 108.501421 -130.801235)
			(xy 108.572671 -130.847026) (xy 108.639245 -130.899383) (xy 108.700541 -130.95783) (xy 108.756004 -131.021839)
			(xy 108.805131 -131.090831) (xy 108.847478 -131.16418) (xy 108.882661 -131.241222) (xy 108.910362 -131.321259)
			(xy 108.930329 -131.403567) (xy 108.942383 -131.487401) (xy 108.946413 -131.572) (xy 122.020588 -131.572)
			(xy 122.024618 -131.487399) (xy 122.036671 -131.403564) (xy 122.056639 -131.321255) (xy 122.084341 -131.241216)
			(xy 122.119525 -131.164173) (xy 122.161874 -131.090823) (xy 122.211003 -131.021831) (xy 122.266468 -130.957821)
			(xy 122.327766 -130.899373) (xy 122.394342 -130.847017) (xy 122.465594 -130.801227) (xy 122.540875 -130.762416)
			(xy 122.619505 -130.730937) (xy 122.700772 -130.707076) (xy 122.783938 -130.691047) (xy 122.868252 -130.682996)
			(xy 122.9106 -130.682492) (xy 122.956996 -130.683075) (xy 123.049284 -130.69272) (xy 123.140068 -130.711916)
			(xy 123.228361 -130.740454) (xy 123.271026 -130.758692) (xy 123.280968 -130.762498) (xy 123.302232 -130.762498)
			(xy 123.312174 -130.758692) (xy 123.354836 -130.740447) (xy 123.443129 -130.711903) (xy 123.533914 -130.69271)
			(xy 123.626204 -130.683077) (xy 123.6726 -130.682492) (xy 123.714948 -130.682996) (xy 123.799262 -130.691047)
			(xy 123.882428 -130.707076) (xy 123.963695 -130.730937) (xy 124.042325 -130.762416) (xy 124.117606 -130.801227)
			(xy 124.188858 -130.847017) (xy 124.255434 -130.899373) (xy 124.316732 -130.957821) (xy 124.372197 -131.021831)
			(xy 124.421326 -131.090823) (xy 124.463675 -131.164173) (xy 124.498859 -131.241216) (xy 124.526561 -131.321255)
			(xy 124.546529 -131.403564) (xy 124.558582 -131.487399) (xy 124.562613 -131.572) (xy 134.212588 -131.572)
			(xy 134.216618 -131.487399) (xy 134.228671 -131.403564) (xy 134.248639 -131.321255) (xy 134.276341 -131.241216)
			(xy 134.311525 -131.164173) (xy 134.353874 -131.090823) (xy 134.403003 -131.021831) (xy 134.458468 -130.957821)
			(xy 134.519766 -130.899373) (xy 134.586342 -130.847017) (xy 134.657594 -130.801227) (xy 134.732875 -130.762416)
			(xy 134.811505 -130.730937) (xy 134.892772 -130.707076) (xy 134.975938 -130.691047) (xy 135.060252 -130.682996)
			(xy 135.1026 -130.682492) (xy 135.148996 -130.683075) (xy 135.241284 -130.69272) (xy 135.332068 -130.711916)
			(xy 135.420361 -130.740454) (xy 135.463026 -130.758692) (xy 135.472968 -130.762498) (xy 135.494232 -130.762498)
			(xy 135.504174 -130.758692) (xy 135.546836 -130.740447) (xy 135.635129 -130.711903) (xy 135.725914 -130.69271)
			(xy 135.818204 -130.683077) (xy 135.8646 -130.682492) (xy 135.906948 -130.682996) (xy 135.991262 -130.691047)
			(xy 136.074428 -130.707076) (xy 136.155695 -130.730937) (xy 136.234325 -130.762416) (xy 136.309606 -130.801227)
			(xy 136.380858 -130.847017) (xy 136.447434 -130.899373) (xy 136.508732 -130.957821) (xy 136.564197 -131.021831)
			(xy 136.613326 -131.090823) (xy 136.655675 -131.164173) (xy 136.690859 -131.241216) (xy 136.718561 -131.321255)
			(xy 136.738529 -131.403564) (xy 136.750582 -131.487399) (xy 136.754613 -131.572) (xy 146.404588 -131.572)
			(xy 146.408618 -131.487399) (xy 146.420671 -131.403564) (xy 146.440639 -131.321255) (xy 146.468341 -131.241216)
			(xy 146.503525 -131.164173) (xy 146.545874 -131.090823) (xy 146.595003 -131.021831) (xy 146.650468 -130.957821)
			(xy 146.711766 -130.899373) (xy 146.778342 -130.847017) (xy 146.849594 -130.801227) (xy 146.924875 -130.762416)
			(xy 147.003505 -130.730937) (xy 147.084772 -130.707076) (xy 147.167938 -130.691047) (xy 147.252252 -130.682996)
			(xy 147.2946 -130.682492) (xy 147.340996 -130.683075) (xy 147.433284 -130.69272) (xy 147.524068 -130.711916)
			(xy 147.612361 -130.740454) (xy 147.655026 -130.758692) (xy 147.664968 -130.762498) (xy 147.686232 -130.762498)
			(xy 147.696174 -130.758692) (xy 147.738836 -130.740447) (xy 147.827129 -130.711903) (xy 147.917914 -130.69271)
			(xy 148.010204 -130.683077) (xy 148.0566 -130.682492) (xy 148.098948 -130.682996) (xy 148.183262 -130.691047)
			(xy 148.266428 -130.707076) (xy 148.347695 -130.730937) (xy 148.426325 -130.762416) (xy 148.501606 -130.801227)
			(xy 148.572858 -130.847017) (xy 148.639434 -130.899373) (xy 148.700732 -130.957821) (xy 148.756197 -131.021831)
			(xy 148.805326 -131.090823) (xy 148.847675 -131.164173) (xy 148.882859 -131.241216) (xy 148.910561 -131.321255)
			(xy 148.930529 -131.403564) (xy 148.942582 -131.487399) (xy 148.946613 -131.572) (xy 162.020787 -131.572)
			(xy 162.024817 -131.487401) (xy 162.036871 -131.403567) (xy 162.056838 -131.321259) (xy 162.084539 -131.241222)
			(xy 162.119722 -131.16418) (xy 162.162069 -131.090831) (xy 162.211196 -131.021839) (xy 162.266659 -130.95783)
			(xy 162.327955 -130.899383) (xy 162.394529 -130.847026) (xy 162.465779 -130.801235) (xy 162.541058 -130.762424)
			(xy 162.619686 -130.730944) (xy 162.70095 -130.707081) (xy 162.784115 -130.69105) (xy 162.868426 -130.682997)
			(xy 162.910774 -130.682492) (xy 162.957169 -130.683084) (xy 163.049457 -130.692726) (xy 163.140241 -130.71192)
			(xy 163.228535 -130.740455) (xy 163.2712 -130.758692) (xy 163.281142 -130.762498) (xy 163.302406 -130.762498)
			(xy 163.312348 -130.758692) (xy 163.355014 -130.740456) (xy 163.443305 -130.71191) (xy 163.534089 -130.692714)
			(xy 163.626378 -130.683078) (xy 163.672774 -130.682492) (xy 163.715124 -130.682979) (xy 163.799441 -130.691028)
			(xy 163.882611 -130.707055) (xy 163.96388 -130.730916) (xy 164.042514 -130.762394) (xy 164.117799 -130.801204)
			(xy 164.189054 -130.846995) (xy 164.255634 -130.899352) (xy 164.316935 -130.957801) (xy 164.372402 -131.021813)
			(xy 164.421534 -131.090807) (xy 164.463885 -131.164159) (xy 164.499071 -131.241204) (xy 164.526774 -131.321246)
			(xy 164.546743 -131.403558) (xy 164.558798 -131.487396) (xy 164.562828 -131.572) (xy 174.212787 -131.572)
			(xy 174.216817 -131.487401) (xy 174.228871 -131.403567) (xy 174.248838 -131.321259) (xy 174.276539 -131.241222)
			(xy 174.311722 -131.16418) (xy 174.354069 -131.090831) (xy 174.403196 -131.021839) (xy 174.458659 -130.95783)
			(xy 174.519955 -130.899383) (xy 174.586529 -130.847026) (xy 174.657779 -130.801235) (xy 174.733058 -130.762424)
			(xy 174.811686 -130.730944) (xy 174.89295 -130.707081) (xy 174.976115 -130.69105) (xy 175.060426 -130.682997)
			(xy 175.102774 -130.682492) (xy 175.149169 -130.683084) (xy 175.241457 -130.692726) (xy 175.332241 -130.71192)
			(xy 175.420535 -130.740455) (xy 175.4632 -130.758692) (xy 175.473142 -130.762498) (xy 175.494406 -130.762498)
			(xy 175.504348 -130.758692) (xy 175.547014 -130.740456) (xy 175.635305 -130.71191) (xy 175.726089 -130.692714)
			(xy 175.818378 -130.683078) (xy 175.864774 -130.682492) (xy 175.907124 -130.682979) (xy 175.991441 -130.691028)
			(xy 176.074611 -130.707055) (xy 176.15588 -130.730916) (xy 176.234514 -130.762394) (xy 176.309799 -130.801204)
			(xy 176.381054 -130.846995) (xy 176.447634 -130.899352) (xy 176.508935 -130.957801) (xy 176.564402 -131.021813)
			(xy 176.613534 -131.090807) (xy 176.655885 -131.164159) (xy 176.691071 -131.241204) (xy 176.718774 -131.321246)
			(xy 176.738743 -131.403558) (xy 176.750798 -131.487396) (xy 176.754828 -131.572) (xy 186.404787 -131.572)
			(xy 186.408817 -131.487401) (xy 186.420871 -131.403567) (xy 186.440838 -131.321259) (xy 186.468539 -131.241222)
			(xy 186.503722 -131.16418) (xy 186.546069 -131.090831) (xy 186.595196 -131.021839) (xy 186.650659 -130.95783)
			(xy 186.711955 -130.899383) (xy 186.778529 -130.847026) (xy 186.849779 -130.801235) (xy 186.925058 -130.762424)
			(xy 187.003686 -130.730944) (xy 187.08495 -130.707081) (xy 187.168115 -130.69105) (xy 187.252426 -130.682997)
			(xy 187.294774 -130.682492) (xy 187.341169 -130.683084) (xy 187.433457 -130.692726) (xy 187.524241 -130.71192)
			(xy 187.612535 -130.740455) (xy 187.6552 -130.758692) (xy 187.665142 -130.762498) (xy 187.686406 -130.762498)
			(xy 187.696348 -130.758692) (xy 187.739014 -130.740456) (xy 187.827305 -130.71191) (xy 187.918089 -130.692714)
			(xy 188.010378 -130.683078) (xy 188.056774 -130.682492) (xy 188.099124 -130.682979) (xy 188.183441 -130.691028)
			(xy 188.266611 -130.707055) (xy 188.34788 -130.730916) (xy 188.426514 -130.762394) (xy 188.501799 -130.801204)
			(xy 188.573054 -130.846995) (xy 188.639634 -130.899352) (xy 188.700935 -130.957801) (xy 188.756402 -131.021813)
			(xy 188.805534 -131.090807) (xy 188.847885 -131.164159) (xy 188.883071 -131.241204) (xy 188.910774 -131.321246)
			(xy 188.930743 -131.403558) (xy 188.942798 -131.487396) (xy 188.946828 -131.572) (xy 188.942798 -131.656604)
			(xy 188.930743 -131.740442) (xy 188.910774 -131.822754) (xy 188.883071 -131.902796) (xy 188.847885 -131.979841)
			(xy 188.805534 -132.053193) (xy 188.756402 -132.122187) (xy 188.700935 -132.186199) (xy 188.639634 -132.244648)
			(xy 188.573054 -132.297005) (xy 188.501799 -132.342796) (xy 188.426514 -132.381606) (xy 188.34788 -132.413084)
			(xy 188.266611 -132.436945) (xy 188.183441 -132.452972) (xy 188.099124 -132.461021) (xy 188.056774 -132.461508)
			(xy 188.010379 -132.460899) (xy 187.918091 -132.451262) (xy 187.827308 -132.432073) (xy 187.739013 -132.403542)
			(xy 187.696348 -132.385308) (xy 187.686406 -132.381502) (xy 187.665142 -132.381502) (xy 187.6552 -132.385308)
			(xy 187.612541 -132.403561) (xy 187.524248 -132.432103) (xy 187.433462 -132.451294) (xy 187.34117 -132.460924)
			(xy 187.294774 -132.461508) (xy 187.252426 -132.461003) (xy 187.168115 -132.45295) (xy 187.08495 -132.436919)
			(xy 187.003686 -132.413056) (xy 186.925058 -132.381576) (xy 186.849779 -132.342765) (xy 186.778529 -132.296974)
			(xy 186.711955 -132.244617) (xy 186.650659 -132.18617) (xy 186.595196 -132.122161) (xy 186.546069 -132.053169)
			(xy 186.503722 -131.97982) (xy 186.468539 -131.902778) (xy 186.440838 -131.822741) (xy 186.420871 -131.740433)
			(xy 186.408817 -131.656599) (xy 186.404787 -131.572) (xy 176.754828 -131.572) (xy 176.750798 -131.656604)
			(xy 176.738743 -131.740442) (xy 176.718774 -131.822754) (xy 176.691071 -131.902796) (xy 176.655885 -131.979841)
			(xy 176.613534 -132.053193) (xy 176.564402 -132.122187) (xy 176.508935 -132.186199) (xy 176.447634 -132.244648)
			(xy 176.381054 -132.297005) (xy 176.309799 -132.342796) (xy 176.234514 -132.381606) (xy 176.15588 -132.413084)
			(xy 176.074611 -132.436945) (xy 175.991441 -132.452972) (xy 175.907124 -132.461021) (xy 175.864774 -132.461508)
			(xy 175.818379 -132.460899) (xy 175.726091 -132.451262) (xy 175.635308 -132.432073) (xy 175.547013 -132.403542)
			(xy 175.504348 -132.385308) (xy 175.494406 -132.381502) (xy 175.473142 -132.381502) (xy 175.4632 -132.385308)
			(xy 175.420541 -132.403561) (xy 175.332248 -132.432103) (xy 175.241462 -132.451294) (xy 175.14917 -132.460924)
			(xy 175.102774 -132.461508) (xy 175.060426 -132.461003) (xy 174.976115 -132.45295) (xy 174.89295 -132.436919)
			(xy 174.811686 -132.413056) (xy 174.733058 -132.381576) (xy 174.657779 -132.342765) (xy 174.586529 -132.296974)
			(xy 174.519955 -132.244617) (xy 174.458659 -132.18617) (xy 174.403196 -132.122161) (xy 174.354069 -132.053169)
			(xy 174.311722 -131.97982) (xy 174.276539 -131.902778) (xy 174.248838 -131.822741) (xy 174.228871 -131.740433)
			(xy 174.216817 -131.656599) (xy 174.212787 -131.572) (xy 164.562828 -131.572) (xy 164.558798 -131.656604)
			(xy 164.546743 -131.740442) (xy 164.526774 -131.822754) (xy 164.499071 -131.902796) (xy 164.463885 -131.979841)
			(xy 164.421534 -132.053193) (xy 164.372402 -132.122187) (xy 164.316935 -132.186199) (xy 164.255634 -132.244648)
			(xy 164.189054 -132.297005) (xy 164.117799 -132.342796) (xy 164.042514 -132.381606) (xy 163.96388 -132.413084)
			(xy 163.882611 -132.436945) (xy 163.799441 -132.452972) (xy 163.715124 -132.461021) (xy 163.672774 -132.461508)
			(xy 163.626379 -132.460899) (xy 163.534091 -132.451262) (xy 163.443308 -132.432073) (xy 163.355013 -132.403542)
			(xy 163.312348 -132.385308) (xy 163.302406 -132.381502) (xy 163.281142 -132.381502) (xy 163.2712 -132.385308)
			(xy 163.228541 -132.403561) (xy 163.140248 -132.432103) (xy 163.049462 -132.451294) (xy 162.95717 -132.460924)
			(xy 162.910774 -132.461508) (xy 162.868426 -132.461003) (xy 162.784115 -132.45295) (xy 162.70095 -132.436919)
			(xy 162.619686 -132.413056) (xy 162.541058 -132.381576) (xy 162.465779 -132.342765) (xy 162.394529 -132.296974)
			(xy 162.327955 -132.244617) (xy 162.266659 -132.18617) (xy 162.211196 -132.122161) (xy 162.162069 -132.053169)
			(xy 162.119722 -131.97982) (xy 162.084539 -131.902778) (xy 162.056838 -131.822741) (xy 162.036871 -131.740433)
			(xy 162.024817 -131.656599) (xy 162.020787 -131.572) (xy 148.946613 -131.572) (xy 148.942582 -131.656601)
			(xy 148.930529 -131.740436) (xy 148.910561 -131.822745) (xy 148.882859 -131.902784) (xy 148.847675 -131.979827)
			(xy 148.805326 -132.053177) (xy 148.756197 -132.122169) (xy 148.700732 -132.186179) (xy 148.639434 -132.244627)
			(xy 148.572858 -132.296983) (xy 148.501606 -132.342773) (xy 148.426325 -132.381584) (xy 148.347695 -132.413063)
			(xy 148.266428 -132.436924) (xy 148.183262 -132.452953) (xy 148.098948 -132.461004) (xy 148.0566 -132.461508)
			(xy 148.010204 -132.460925) (xy 147.917916 -132.45128) (xy 147.827132 -132.432084) (xy 147.738839 -132.403546)
			(xy 147.696174 -132.385308) (xy 147.686232 -132.381502) (xy 147.664968 -132.381502) (xy 147.655026 -132.385308)
			(xy 147.612364 -132.403553) (xy 147.524071 -132.432097) (xy 147.433286 -132.45129) (xy 147.340996 -132.460923)
			(xy 147.2946 -132.461508) (xy 147.252252 -132.461004) (xy 147.167938 -132.452953) (xy 147.084772 -132.436924)
			(xy 147.003505 -132.413063) (xy 146.924875 -132.381584) (xy 146.849594 -132.342773) (xy 146.778342 -132.296983)
			(xy 146.711766 -132.244627) (xy 146.650468 -132.186179) (xy 146.595003 -132.122169) (xy 146.545874 -132.053177)
			(xy 146.503525 -131.979827) (xy 146.468341 -131.902784) (xy 146.440639 -131.822745) (xy 146.420671 -131.740436)
			(xy 146.408618 -131.656601) (xy 146.404588 -131.572) (xy 136.754613 -131.572) (xy 136.750582 -131.656601)
			(xy 136.738529 -131.740436) (xy 136.718561 -131.822745) (xy 136.690859 -131.902784) (xy 136.655675 -131.979827)
			(xy 136.613326 -132.053177) (xy 136.564197 -132.122169) (xy 136.508732 -132.186179) (xy 136.447434 -132.244627)
			(xy 136.380858 -132.296983) (xy 136.309606 -132.342773) (xy 136.234325 -132.381584) (xy 136.155695 -132.413063)
			(xy 136.074428 -132.436924) (xy 135.991262 -132.452953) (xy 135.906948 -132.461004) (xy 135.8646 -132.461508)
			(xy 135.818204 -132.460925) (xy 135.725916 -132.45128) (xy 135.635132 -132.432084) (xy 135.546839 -132.403546)
			(xy 135.504174 -132.385308) (xy 135.494232 -132.381502) (xy 135.472968 -132.381502) (xy 135.463026 -132.385308)
			(xy 135.420364 -132.403553) (xy 135.332071 -132.432097) (xy 135.241286 -132.45129) (xy 135.148996 -132.460923)
			(xy 135.1026 -132.461508) (xy 135.060252 -132.461004) (xy 134.975938 -132.452953) (xy 134.892772 -132.436924)
			(xy 134.811505 -132.413063) (xy 134.732875 -132.381584) (xy 134.657594 -132.342773) (xy 134.586342 -132.296983)
			(xy 134.519766 -132.244627) (xy 134.458468 -132.186179) (xy 134.403003 -132.122169) (xy 134.353874 -132.053177)
			(xy 134.311525 -131.979827) (xy 134.276341 -131.902784) (xy 134.248639 -131.822745) (xy 134.228671 -131.740436)
			(xy 134.216618 -131.656601) (xy 134.212588 -131.572) (xy 124.562613 -131.572) (xy 124.558582 -131.656601)
			(xy 124.546529 -131.740436) (xy 124.526561 -131.822745) (xy 124.498859 -131.902784) (xy 124.463675 -131.979827)
			(xy 124.421326 -132.053177) (xy 124.372197 -132.122169) (xy 124.316732 -132.186179) (xy 124.255434 -132.244627)
			(xy 124.188858 -132.296983) (xy 124.117606 -132.342773) (xy 124.042325 -132.381584) (xy 123.963695 -132.413063)
			(xy 123.882428 -132.436924) (xy 123.799262 -132.452953) (xy 123.714948 -132.461004) (xy 123.6726 -132.461508)
			(xy 123.626204 -132.460925) (xy 123.533916 -132.45128) (xy 123.443132 -132.432084) (xy 123.354839 -132.403546)
			(xy 123.312174 -132.385308) (xy 123.302232 -132.381502) (xy 123.280968 -132.381502) (xy 123.271026 -132.385308)
			(xy 123.228364 -132.403553) (xy 123.140071 -132.432097) (xy 123.049286 -132.45129) (xy 122.956996 -132.460923)
			(xy 122.9106 -132.461508) (xy 122.868252 -132.461004) (xy 122.783938 -132.452953) (xy 122.700772 -132.436924)
			(xy 122.619505 -132.413063) (xy 122.540875 -132.381584) (xy 122.465594 -132.342773) (xy 122.394342 -132.296983)
			(xy 122.327766 -132.244627) (xy 122.266468 -132.186179) (xy 122.211003 -132.122169) (xy 122.161874 -132.053177)
			(xy 122.119525 -131.979827) (xy 122.084341 -131.902784) (xy 122.056639 -131.822745) (xy 122.036671 -131.740436)
			(xy 122.024618 -131.656601) (xy 122.020588 -131.572) (xy 108.946413 -131.572) (xy 108.942383 -131.656599)
			(xy 108.930329 -131.740433) (xy 108.910362 -131.822741) (xy 108.882661 -131.902778) (xy 108.847478 -131.97982)
			(xy 108.805131 -132.053169) (xy 108.756004 -132.122161) (xy 108.700541 -132.18617) (xy 108.639245 -132.244617)
			(xy 108.572671 -132.296974) (xy 108.501421 -132.342765) (xy 108.426142 -132.381576) (xy 108.347514 -132.413056)
			(xy 108.26625 -132.436919) (xy 108.183085 -132.45295) (xy 108.098774 -132.461003) (xy 108.056426 -132.461508)
			(xy 108.010031 -132.460916) (xy 107.917743 -132.451274) (xy 107.826959 -132.43208) (xy 107.738665 -132.403545)
			(xy 107.696 -132.385308) (xy 107.686058 -132.381502) (xy 107.664794 -132.381502) (xy 107.654852 -132.385308)
			(xy 107.612186 -132.403544) (xy 107.523895 -132.43209) (xy 107.433111 -132.451286) (xy 107.340822 -132.460922)
			(xy 107.294426 -132.461508) (xy 107.252076 -132.461021) (xy 107.167759 -132.452972) (xy 107.084589 -132.436945)
			(xy 107.00332 -132.413084) (xy 106.924686 -132.381606) (xy 106.849401 -132.342796) (xy 106.778146 -132.297005)
			(xy 106.711566 -132.244648) (xy 106.650265 -132.186199) (xy 106.594798 -132.122187) (xy 106.545666 -132.053193)
			(xy 106.503315 -131.979841) (xy 106.468129 -131.902796) (xy 106.440426 -131.822754) (xy 106.420457 -131.740442)
			(xy 106.408402 -131.656604) (xy 106.404372 -131.572) (xy 96.754413 -131.572) (xy 96.750383 -131.656599)
			(xy 96.738329 -131.740433) (xy 96.718362 -131.822741) (xy 96.690661 -131.902778) (xy 96.655478 -131.97982)
			(xy 96.613131 -132.053169) (xy 96.564004 -132.122161) (xy 96.508541 -132.18617) (xy 96.447245 -132.244617)
			(xy 96.380671 -132.296974) (xy 96.309421 -132.342765) (xy 96.234142 -132.381576) (xy 96.155514 -132.413056)
			(xy 96.07425 -132.436919) (xy 95.991085 -132.45295) (xy 95.906774 -132.461003) (xy 95.864426 -132.461508)
			(xy 95.818031 -132.460916) (xy 95.725743 -132.451274) (xy 95.634959 -132.43208) (xy 95.546665 -132.403545)
			(xy 95.504 -132.385308) (xy 95.494058 -132.381502) (xy 95.472794 -132.381502) (xy 95.462852 -132.385308)
			(xy 95.420186 -132.403544) (xy 95.331895 -132.43209) (xy 95.241111 -132.451286) (xy 95.148822 -132.460922)
			(xy 95.102426 -132.461508) (xy 95.060076 -132.461021) (xy 94.975759 -132.452972) (xy 94.892589 -132.436945)
			(xy 94.81132 -132.413084) (xy 94.732686 -132.381606) (xy 94.657401 -132.342796) (xy 94.586146 -132.297005)
			(xy 94.519566 -132.244648) (xy 94.458265 -132.186199) (xy 94.402798 -132.122187) (xy 94.353666 -132.053193)
			(xy 94.311315 -131.979841) (xy 94.276129 -131.902796) (xy 94.248426 -131.822754) (xy 94.228457 -131.740442)
			(xy 94.216402 -131.656604) (xy 94.212372 -131.572) (xy 84.562413 -131.572) (xy 84.558383 -131.656599)
			(xy 84.546329 -131.740433) (xy 84.526362 -131.822741) (xy 84.498661 -131.902778) (xy 84.463478 -131.97982)
			(xy 84.421131 -132.053169) (xy 84.372004 -132.122161) (xy 84.316541 -132.18617) (xy 84.255245 -132.244617)
			(xy 84.188671 -132.296974) (xy 84.117421 -132.342765) (xy 84.042142 -132.381576) (xy 83.963514 -132.413056)
			(xy 83.88225 -132.436919) (xy 83.799085 -132.45295) (xy 83.714774 -132.461003) (xy 83.672426 -132.461508)
			(xy 83.626031 -132.460916) (xy 83.533743 -132.451274) (xy 83.442959 -132.43208) (xy 83.354665 -132.403545)
			(xy 83.312 -132.385308) (xy 83.302058 -132.381502) (xy 83.280794 -132.381502) (xy 83.270852 -132.385308)
			(xy 83.228186 -132.403544) (xy 83.139895 -132.43209) (xy 83.049111 -132.451286) (xy 82.956822 -132.460922)
			(xy 82.910426 -132.461508) (xy 82.868076 -132.461021) (xy 82.783759 -132.452972) (xy 82.700589 -132.436945)
			(xy 82.61932 -132.413084) (xy 82.540686 -132.381606) (xy 82.465401 -132.342796) (xy 82.394146 -132.297005)
			(xy 82.327566 -132.244648) (xy 82.266265 -132.186199) (xy 82.210798 -132.122187) (xy 82.161666 -132.053193)
			(xy 82.119315 -131.979841) (xy 82.084129 -131.902796) (xy 82.056426 -131.822754) (xy 82.036457 -131.740442)
			(xy 82.024402 -131.656604) (xy 82.020372 -131.572) (xy 68.946513 -131.572) (xy 68.942482 -131.656601)
			(xy 68.930429 -131.740435) (xy 68.910461 -131.822744) (xy 68.88276 -131.902783) (xy 68.847575 -131.979826)
			(xy 68.805227 -132.053175) (xy 68.756099 -132.122167) (xy 68.700634 -132.186177) (xy 68.639337 -132.244624)
			(xy 68.572761 -132.296981) (xy 68.50151 -132.342771) (xy 68.426229 -132.381582) (xy 68.347599 -132.413061)
			(xy 68.266333 -132.436923) (xy 68.183167 -132.452953) (xy 68.098854 -132.461004) (xy 68.056506 -132.461508)
			(xy 68.01011 -132.460923) (xy 67.917822 -132.451279) (xy 67.827038 -132.432083) (xy 67.738745 -132.403546)
			(xy 67.69608 -132.385308) (xy 67.686138 -132.381502) (xy 67.664874 -132.381502) (xy 67.654932 -132.385308)
			(xy 67.612269 -132.403551) (xy 67.523977 -132.432095) (xy 67.433192 -132.451289) (xy 67.340902 -132.460923)
			(xy 67.294506 -132.461508) (xy 67.252157 -132.46102) (xy 67.167841 -132.45297) (xy 67.084673 -132.436941)
			(xy 67.003405 -132.413079) (xy 66.924773 -132.3816) (xy 66.849489 -132.342789) (xy 66.778236 -132.296998)
			(xy 66.711658 -132.24464) (xy 66.650358 -132.186192) (xy 66.594892 -132.122181) (xy 66.545762 -132.053187)
			(xy 66.503412 -131.979836) (xy 66.468227 -131.902791) (xy 66.440525 -131.822751) (xy 66.420556 -131.74044)
			(xy 66.408502 -131.656603) (xy 66.404472 -131.572) (xy 56.754513 -131.572) (xy 56.750482 -131.656601)
			(xy 56.738429 -131.740435) (xy 56.718461 -131.822744) (xy 56.69076 -131.902783) (xy 56.655575 -131.979826)
			(xy 56.613227 -132.053175) (xy 56.564099 -132.122167) (xy 56.508634 -132.186177) (xy 56.447337 -132.244624)
			(xy 56.380761 -132.296981) (xy 56.30951 -132.342771) (xy 56.234229 -132.381582) (xy 56.155599 -132.413061)
			(xy 56.074333 -132.436923) (xy 55.991167 -132.452953) (xy 55.906854 -132.461004) (xy 55.864506 -132.461508)
			(xy 55.81811 -132.460923) (xy 55.725822 -132.451279) (xy 55.635038 -132.432083) (xy 55.546745 -132.403546)
			(xy 55.50408 -132.385308) (xy 55.494138 -132.381502) (xy 55.472874 -132.381502) (xy 55.462932 -132.385308)
			(xy 55.420269 -132.403551) (xy 55.331977 -132.432095) (xy 55.241192 -132.451289) (xy 55.148902 -132.460923)
			(xy 55.102506 -132.461508) (xy 55.060157 -132.46102) (xy 54.975841 -132.45297) (xy 54.892673 -132.436941)
			(xy 54.811405 -132.413079) (xy 54.732773 -132.3816) (xy 54.657489 -132.342789) (xy 54.586236 -132.296998)
			(xy 54.519658 -132.24464) (xy 54.458358 -132.186192) (xy 54.402892 -132.122181) (xy 54.353762 -132.053187)
			(xy 54.311412 -131.979836) (xy 54.276227 -131.902791) (xy 54.248525 -131.822751) (xy 54.228556 -131.74044)
			(xy 54.216502 -131.656603) (xy 54.212472 -131.572) (xy 44.562513 -131.572) (xy 44.558482 -131.656601)
			(xy 44.546429 -131.740435) (xy 44.526461 -131.822744) (xy 44.49876 -131.902783) (xy 44.463575 -131.979826)
			(xy 44.421227 -132.053175) (xy 44.372099 -132.122167) (xy 44.316634 -132.186177) (xy 44.255337 -132.244624)
			(xy 44.188761 -132.296981) (xy 44.11751 -132.342771) (xy 44.042229 -132.381582) (xy 43.963599 -132.413061)
			(xy 43.882333 -132.436923) (xy 43.799167 -132.452953) (xy 43.714854 -132.461004) (xy 43.672506 -132.461508)
			(xy 43.62611 -132.460923) (xy 43.533822 -132.451279) (xy 43.443038 -132.432083) (xy 43.354745 -132.403546)
			(xy 43.31208 -132.385308) (xy 43.302138 -132.381502) (xy 43.280874 -132.381502) (xy 43.270932 -132.385308)
			(xy 43.228269 -132.403551) (xy 43.139977 -132.432095) (xy 43.049192 -132.451289) (xy 42.956902 -132.460923)
			(xy 42.910506 -132.461508) (xy 42.868157 -132.46102) (xy 42.783841 -132.45297) (xy 42.700673 -132.436941)
			(xy 42.619405 -132.413079) (xy 42.540773 -132.3816) (xy 42.465489 -132.342789) (xy 42.394236 -132.296998)
			(xy 42.327658 -132.24464) (xy 42.266358 -132.186192) (xy 42.210892 -132.122181) (xy 42.161762 -132.053187)
			(xy 42.119412 -131.979836) (xy 42.084227 -131.902791) (xy 42.056525 -131.822751) (xy 42.036556 -131.74044)
			(xy 42.024502 -131.656603) (xy 42.020472 -131.572) (xy 0.514454 -131.572) (xy 0.509506 -131.660112)
			(xy 0.509016 -131.729988) (xy 0.509016 -132.959856) (xy 213.088728 -132.959856) (xy 213.089328 -132.913461)
			(xy 213.098967 -132.821173) (xy 213.118158 -132.730389) (xy 213.146692 -132.642095) (xy 213.164928 -132.59943)
			(xy 213.168758 -132.589495) (xy 213.168741 -132.568225) (xy 213.164928 -132.558282) (xy 213.146671 -132.515625)
			(xy 213.11813 -132.427331) (xy 213.09894 -132.336544) (xy 213.089311 -132.244253) (xy 213.088728 -132.197856)
			(xy 213.089328 -132.151461) (xy 213.098967 -132.059173) (xy 213.118158 -131.968389) (xy 213.146692 -131.880095)
			(xy 213.164928 -131.83743) (xy 213.168758 -131.827495) (xy 213.168741 -131.806225) (xy 213.164928 -131.796282)
			(xy 213.146671 -131.753625) (xy 213.11813 -131.665331) (xy 213.09894 -131.574544) (xy 213.089311 -131.482253)
			(xy 213.088728 -131.435856) (xy 213.089328 -131.389461) (xy 213.098967 -131.297173) (xy 213.118158 -131.206389)
			(xy 213.146692 -131.118095) (xy 213.164928 -131.07543) (xy 213.168758 -131.065495) (xy 213.168741 -131.044225)
			(xy 213.164928 -131.034282) (xy 213.146671 -130.991625) (xy 213.11813 -130.903331) (xy 213.09894 -130.812544)
			(xy 213.089311 -130.720253) (xy 213.088728 -130.673856) (xy 213.089328 -130.627461) (xy 213.098967 -130.535173)
			(xy 213.118158 -130.444389) (xy 213.146692 -130.356095) (xy 213.164928 -130.31343) (xy 213.168758 -130.303495)
			(xy 213.168741 -130.282225) (xy 213.164928 -130.272282) (xy 213.146671 -130.229625) (xy 213.11813 -130.141331)
			(xy 213.09894 -130.050544) (xy 213.089311 -129.958253) (xy 213.088728 -129.911856) (xy 213.089328 -129.865461)
			(xy 213.098967 -129.773173) (xy 213.118158 -129.682389) (xy 213.146692 -129.594095) (xy 213.164928 -129.55143)
			(xy 213.168758 -129.541495) (xy 213.168741 -129.520225) (xy 213.164928 -129.510282) (xy 213.146671 -129.467625)
			(xy 213.11813 -129.379331) (xy 213.09894 -129.288544) (xy 213.089311 -129.196253) (xy 213.088728 -129.149856)
			(xy 213.089328 -129.103461) (xy 213.098967 -129.011173) (xy 213.118158 -128.920389) (xy 213.146692 -128.832095)
			(xy 213.164928 -128.78943) (xy 213.168758 -128.779495) (xy 213.168741 -128.758225) (xy 213.164928 -128.748282)
			(xy 213.146671 -128.705625) (xy 213.11813 -128.617331) (xy 213.09894 -128.526544) (xy 213.089311 -128.434253)
			(xy 213.088728 -128.387856) (xy 213.089328 -128.341461) (xy 213.098967 -128.249173) (xy 213.118158 -128.158389)
			(xy 213.146692 -128.070095) (xy 213.164928 -128.02743) (xy 213.168758 -128.017495) (xy 213.168741 -127.996225)
			(xy 213.164928 -127.986282) (xy 213.146671 -127.943625) (xy 213.11813 -127.855331) (xy 213.09894 -127.764544)
			(xy 213.089311 -127.672253) (xy 213.088728 -127.625856) (xy 213.089125 -127.584752) (xy 213.096714 -127.502894)
			(xy 213.111824 -127.422086) (xy 213.134325 -127.343017) (xy 213.164026 -127.266361) (xy 213.200673 -127.192773)
			(xy 213.243953 -127.12288) (xy 213.293498 -127.057278) (xy 213.348884 -126.996528) (xy 213.40964 -126.941147)
			(xy 213.475246 -126.891608) (xy 213.545143 -126.848334) (xy 213.618734 -126.811693) (xy 213.695393 -126.781999)
			(xy 213.774464 -126.759505) (xy 213.855273 -126.744403) (xy 213.937132 -126.736821) (xy 213.978236 -126.736348)
			(xy 214.019707 -126.736821) (xy 214.102292 -126.744496) (xy 214.183804 -126.759823) (xy 214.263536 -126.782669)
			(xy 214.30234 -126.797308) (xy 214.311828 -126.800522) (xy 214.331839 -126.800112) (xy 214.341202 -126.796546)
			(xy 214.383373 -126.778847) (xy 214.47054 -126.751148) (xy 214.560087 -126.732532) (xy 214.651071 -126.723195)
			(xy 214.696802 -126.722632) (xy 214.743198 -126.723211) (xy 214.835486 -126.732857) (xy 214.92627 -126.752054)
			(xy 215.014563 -126.780593) (xy 215.057228 -126.798832) (xy 215.06717 -126.802638) (xy 215.088434 -126.802638)
			(xy 215.098376 -126.798832) (xy 215.141039 -126.780589) (xy 215.229331 -126.752044) (xy 215.320116 -126.73285)
			(xy 215.412406 -126.723217) (xy 215.458802 -126.722632) (xy 215.502226 -126.723118) (xy 215.588665 -126.731536)
			(xy 215.673869 -126.748349) (xy 215.757026 -126.773398) (xy 215.797384 -126.789434) (xy 215.806818 -126.792777)
			(xy 215.826812 -126.792777) (xy 215.836246 -126.789434) (xy 215.87661 -126.77342) (xy 215.959771 -126.748397)
			(xy 216.044973 -126.731586) (xy 216.131406 -126.723147) (xy 216.174828 -126.722632) (xy 216.221223 -126.723237)
			(xy 216.313511 -126.732875) (xy 216.404295 -126.752064) (xy 216.492589 -126.780597) (xy 216.535254 -126.798832)
			(xy 216.545196 -126.802638) (xy 216.56646 -126.802638) (xy 216.576402 -126.798832) (xy 216.619061 -126.78058)
			(xy 216.707355 -126.752038) (xy 216.798141 -126.732846) (xy 216.890432 -126.723215) (xy 216.936828 -126.722632)
			(xy 216.977933 -126.723025) (xy 217.059791 -126.730613) (xy 217.140601 -126.745722) (xy 217.219671 -126.768223)
			(xy 217.296329 -126.797923) (xy 217.369918 -126.834569) (xy 217.439813 -126.87785) (xy 217.505416 -126.927394)
			(xy 217.566167 -126.982781) (xy 217.621549 -127.043537) (xy 217.671089 -127.109143) (xy 217.714364 -127.179041)
			(xy 217.751005 -127.252634) (xy 217.780699 -127.329293) (xy 217.803193 -127.408365) (xy 217.818296 -127.489176)
			(xy 217.825878 -127.571035) (xy 217.826336 -127.61214) (xy 217.82573 -127.658535) (xy 217.816091 -127.750823)
			(xy 217.796902 -127.841606) (xy 217.76837 -127.929901) (xy 217.750136 -127.972566) (xy 217.746305 -127.982501)
			(xy 217.746321 -128.003772) (xy 217.750136 -128.013714) (xy 217.768396 -128.05637) (xy 217.796935 -128.144665)
			(xy 217.816124 -128.235452) (xy 217.825753 -128.327743) (xy 217.826336 -128.37414) (xy 217.82573 -128.420535)
			(xy 217.816091 -128.512823) (xy 217.796902 -128.603606) (xy 217.76837 -128.691901) (xy 217.750136 -128.734566)
			(xy 217.746305 -128.744501) (xy 217.746321 -128.765772) (xy 217.750136 -128.775714) (xy 217.768396 -128.81837)
			(xy 217.796935 -128.906665) (xy 217.816124 -128.997452) (xy 217.825753 -129.089743) (xy 217.826336 -129.13614)
			(xy 217.82573 -129.182535) (xy 217.816091 -129.274823) (xy 217.796902 -129.365606) (xy 217.76837 -129.453901)
			(xy 217.750136 -129.496566) (xy 217.746305 -129.506501) (xy 217.746321 -129.527772) (xy 217.750136 -129.537714)
			(xy 217.768396 -129.58037) (xy 217.796935 -129.668665) (xy 217.816124 -129.759452) (xy 217.825753 -129.851743)
			(xy 217.826336 -129.89814) (xy 217.82573 -129.944535) (xy 217.816091 -130.036823) (xy 217.796902 -130.127606)
			(xy 217.76837 -130.215901) (xy 217.750136 -130.258566) (xy 217.746305 -130.268501) (xy 217.746321 -130.289772)
			(xy 217.750136 -130.299714) (xy 217.768396 -130.34237) (xy 217.796935 -130.430665) (xy 217.816124 -130.521452)
			(xy 217.825753 -130.613743) (xy 217.826336 -130.66014) (xy 217.82573 -130.706535) (xy 217.816091 -130.798823)
			(xy 217.796902 -130.889606) (xy 217.76837 -130.977901) (xy 217.750136 -131.020566) (xy 217.746305 -131.030501)
			(xy 217.746321 -131.051772) (xy 217.750136 -131.061714) (xy 217.768396 -131.10437) (xy 217.770454 -131.110736)
			(xy 230.701596 -131.110736) (xy 230.702191 -131.064341) (xy 230.711833 -130.972053) (xy 230.731025 -130.881269)
			(xy 230.75956 -130.792975) (xy 230.777796 -130.75031) (xy 230.78158 -130.740361) (xy 230.781594 -130.719104)
			(xy 230.777796 -130.709162) (xy 230.759563 -130.666495) (xy 230.731016 -130.578204) (xy 230.71182 -130.487421)
			(xy 230.702183 -130.395132) (xy 230.701596 -130.348736) (xy 230.702191 -130.302341) (xy 230.711833 -130.210053)
			(xy 230.731025 -130.119269) (xy 230.75956 -130.030975) (xy 230.777796 -129.98831) (xy 230.78158 -129.978361)
			(xy 230.781594 -129.957104) (xy 230.777796 -129.947162) (xy 230.759563 -129.904495) (xy 230.731016 -129.816204)
			(xy 230.71182 -129.725421) (xy 230.702183 -129.633132) (xy 230.701596 -129.586736) (xy 230.702191 -129.540341)
			(xy 230.711833 -129.448053) (xy 230.731025 -129.357269) (xy 230.75956 -129.268975) (xy 230.777796 -129.22631)
			(xy 230.78158 -129.216361) (xy 230.781594 -129.195104) (xy 230.777796 -129.185162) (xy 230.759563 -129.142495)
			(xy 230.731016 -129.054204) (xy 230.71182 -128.963421) (xy 230.702183 -128.871132) (xy 230.701596 -128.824736)
			(xy 230.702191 -128.778341) (xy 230.711833 -128.686053) (xy 230.731025 -128.595269) (xy 230.75956 -128.506975)
			(xy 230.777796 -128.46431) (xy 230.78158 -128.454361) (xy 230.781594 -128.433104) (xy 230.777796 -128.423162)
			(xy 230.759563 -128.380495) (xy 230.731016 -128.292204) (xy 230.71182 -128.201421) (xy 230.702183 -128.109132)
			(xy 230.701596 -128.062736) (xy 230.702191 -128.016341) (xy 230.711833 -127.924053) (xy 230.731025 -127.833269)
			(xy 230.75956 -127.744975) (xy 230.777796 -127.70231) (xy 230.78158 -127.692361) (xy 230.781594 -127.671104)
			(xy 230.777796 -127.661162) (xy 230.759563 -127.618495) (xy 230.731016 -127.530204) (xy 230.71182 -127.439421)
			(xy 230.702183 -127.347132) (xy 230.701596 -127.300736) (xy 230.702147 -127.256691) (xy 230.710849 -127.169033)
			(xy 230.72817 -127.082663) (xy 230.753941 -126.998427) (xy 230.77043 -126.957582) (xy 230.773801 -126.948582)
			(xy 230.774177 -126.92938) (xy 230.771192 -126.920244) (xy 230.757686 -126.882861) (xy 230.736583 -126.806223)
			(xy 230.722406 -126.728008) (xy 230.715266 -126.648839) (xy 230.714804 -126.609094) (xy 230.715307 -126.567981)
			(xy 230.722894 -126.486105) (xy 230.738004 -126.405278) (xy 230.760506 -126.326191) (xy 230.790209 -126.249516)
			(xy 230.82686 -126.17591) (xy 230.870147 -126.105999) (xy 230.919698 -126.04038) (xy 230.975093 -125.979613)
			(xy 231.035859 -125.924216) (xy 231.101476 -125.874662) (xy 231.171385 -125.831374) (xy 231.244991 -125.794721)
			(xy 231.321664 -125.765015) (xy 231.400751 -125.74251) (xy 231.481577 -125.727398) (xy 231.563453 -125.719808)
			(xy 231.604566 -125.719332) (xy 231.650969 -125.719939) (xy 231.743266 -125.729636) (xy 231.834052 -125.748895)
			(xy 231.922336 -125.777508) (xy 231.964992 -125.795786) (xy 231.974934 -125.799592) (xy 231.996198 -125.799592)
			(xy 232.00614 -125.795786) (xy 232.048804 -125.777532) (xy 232.137091 -125.748938) (xy 232.227873 -125.729678)
			(xy 232.320165 -125.719963) (xy 232.366566 -125.719332) (xy 232.409139 -125.719856) (xy 232.493893 -125.728015)
			(xy 232.577478 -125.744243) (xy 232.659128 -125.768389) (xy 232.698798 -125.783848) (xy 232.70805 -125.787101)
			(xy 232.727646 -125.787101) (xy 232.736898 -125.783848) (xy 232.776567 -125.768388) (xy 232.858222 -125.74426)
			(xy 232.941806 -125.728033) (xy 233.026558 -125.719855) (xy 233.06913 -125.719332) (xy 233.115532 -125.719952)
			(xy 233.20783 -125.729645) (xy 233.298615 -125.7489) (xy 233.3869 -125.77751) (xy 233.429556 -125.795786)
			(xy 233.439498 -125.799592) (xy 233.460762 -125.799592) (xy 233.470704 -125.795786) (xy 233.51336 -125.777511)
			(xy 233.60165 -125.748922) (xy 233.692434 -125.729668) (xy 233.784729 -125.719959) (xy 233.83113 -125.719332)
			(xy 233.877532 -125.719952) (xy 233.96983 -125.729645) (xy 234.060615 -125.7489) (xy 234.1489 -125.77751)
			(xy 234.191556 -125.795786) (xy 234.201498 -125.799592) (xy 234.222762 -125.799592) (xy 234.232704 -125.795786)
			(xy 234.27536 -125.777511) (xy 234.36365 -125.748922) (xy 234.454434 -125.729668) (xy 234.546729 -125.719959)
			(xy 234.59313 -125.719332) (xy 234.634245 -125.719784) (xy 234.716123 -125.727374) (xy 234.796951 -125.742486)
			(xy 234.876041 -125.764991) (xy 234.952716 -125.794697) (xy 235.026324 -125.831352) (xy 235.067746 -125.857)
			(xy 268.350492 -125.857) (xy 268.351075 -125.810604) (xy 268.36072 -125.718316) (xy 268.379916 -125.627532)
			(xy 268.408454 -125.539239) (xy 268.426692 -125.496574) (xy 268.430498 -125.486632) (xy 268.430498 -125.465368)
			(xy 268.426692 -125.455426) (xy 268.408447 -125.412764) (xy 268.379903 -125.324471) (xy 268.36071 -125.233686)
			(xy 268.351077 -125.141396) (xy 268.350492 -125.095) (xy 268.351075 -125.048604) (xy 268.36072 -124.956316)
			(xy 268.379916 -124.865532) (xy 268.408454 -124.777239) (xy 268.426692 -124.734574) (xy 268.430498 -124.724632)
			(xy 268.430498 -124.703368) (xy 268.426692 -124.693426) (xy 268.408447 -124.650764) (xy 268.379903 -124.562471)
			(xy 268.36071 -124.471686) (xy 268.351077 -124.379396) (xy 268.350492 -124.333) (xy 268.351075 -124.286604)
			(xy 268.36072 -124.194316) (xy 268.379916 -124.103532) (xy 268.408454 -124.015239) (xy 268.426692 -123.972574)
			(xy 268.430498 -123.962632) (xy 268.430498 -123.941368) (xy 268.426692 -123.931426) (xy 268.408447 -123.888764)
			(xy 268.379903 -123.800471) (xy 268.36071 -123.709686) (xy 268.351077 -123.617396) (xy 268.350492 -123.571)
			(xy 268.351075 -123.524604) (xy 268.36072 -123.432316) (xy 268.379916 -123.341532) (xy 268.408454 -123.253239)
			(xy 268.426692 -123.210574) (xy 268.430498 -123.200632) (xy 268.430498 -123.179368) (xy 268.426692 -123.169426)
			(xy 268.408447 -123.126764) (xy 268.379903 -123.038471) (xy 268.36071 -122.947686) (xy 268.351077 -122.855396)
			(xy 268.350492 -122.809) (xy 268.351075 -122.762604) (xy 268.36072 -122.670316) (xy 268.379916 -122.579532)
			(xy 268.408454 -122.491239) (xy 268.426692 -122.448574) (xy 268.430498 -122.438632) (xy 268.430498 -122.417368)
			(xy 268.426692 -122.407426) (xy 268.408447 -122.364764) (xy 268.379903 -122.276471) (xy 268.36071 -122.185686)
			(xy 268.351077 -122.093396) (xy 268.350492 -122.047) (xy 268.350967 -122.005898) (xy 268.358552 -121.924043)
			(xy 268.373657 -121.843238) (xy 268.396153 -121.764171) (xy 268.425849 -121.687517) (xy 268.462491 -121.61393)
			(xy 268.505766 -121.544038) (xy 268.555306 -121.478437) (xy 268.610687 -121.417687) (xy 268.671437 -121.362306)
			(xy 268.737038 -121.312766) (xy 268.80693 -121.269491) (xy 268.880517 -121.232849) (xy 268.957171 -121.203153)
			(xy 269.036238 -121.180657) (xy 269.117043 -121.165552) (xy 269.198898 -121.157967) (xy 269.24 -121.157492)
			(xy 269.286396 -121.158075) (xy 269.378684 -121.16772) (xy 269.469468 -121.186916) (xy 269.557761 -121.215454)
			(xy 269.600426 -121.233692) (xy 269.610368 -121.237498) (xy 269.631632 -121.237498) (xy 269.641574 -121.233692)
			(xy 269.684236 -121.215447) (xy 269.772529 -121.186903) (xy 269.863314 -121.16771) (xy 269.955604 -121.158077)
			(xy 270.002 -121.157492) (xy 270.048396 -121.158075) (xy 270.140684 -121.16772) (xy 270.231468 -121.186916)
			(xy 270.319761 -121.215454) (xy 270.362426 -121.233692) (xy 270.372368 -121.237498) (xy 270.393632 -121.237498)
			(xy 270.403574 -121.233692) (xy 270.446236 -121.215447) (xy 270.534529 -121.186903) (xy 270.625314 -121.16771)
			(xy 270.717604 -121.158077) (xy 270.764 -121.157492) (xy 270.810396 -121.158075) (xy 270.902684 -121.16772)
			(xy 270.993468 -121.186916) (xy 271.081761 -121.215454) (xy 271.124426 -121.233692) (xy 271.134368 -121.237498)
			(xy 271.155632 -121.237498) (xy 271.165574 -121.233692) (xy 271.208236 -121.215447) (xy 271.296529 -121.186903)
			(xy 271.387314 -121.16771) (xy 271.479604 -121.158077) (xy 271.526 -121.157492) (xy 271.572396 -121.158075)
			(xy 271.664684 -121.16772) (xy 271.755468 -121.186916) (xy 271.843761 -121.215454) (xy 271.886426 -121.233692)
			(xy 271.896368 -121.237498) (xy 271.917632 -121.237498) (xy 271.927574 -121.233692) (xy 271.970236 -121.215447)
			(xy 272.058529 -121.186903) (xy 272.149314 -121.16771) (xy 272.241604 -121.158077) (xy 272.288 -121.157492)
			(xy 272.329102 -121.157967) (xy 272.410957 -121.165552) (xy 272.491762 -121.180657) (xy 272.570829 -121.203153)
			(xy 272.647483 -121.232849) (xy 272.72107 -121.269491) (xy 272.790962 -121.312766) (xy 272.856563 -121.362306)
			(xy 272.917313 -121.417687) (xy 272.972694 -121.478437) (xy 273.022234 -121.544038) (xy 273.065509 -121.61393)
			(xy 273.102151 -121.687517) (xy 273.131847 -121.764171) (xy 273.154343 -121.843238) (xy 273.169448 -121.924043)
			(xy 273.177033 -122.005898) (xy 273.177508 -122.047) (xy 273.176925 -122.093396) (xy 273.16728 -122.185684)
			(xy 273.148084 -122.276468) (xy 273.119546 -122.364761) (xy 273.101308 -122.407426) (xy 273.097502 -122.417368)
			(xy 273.097502 -122.438632) (xy 273.101308 -122.448574) (xy 273.119553 -122.491236) (xy 273.148097 -122.579529)
			(xy 273.16729 -122.670314) (xy 273.176923 -122.762604) (xy 273.177508 -122.809) (xy 273.177033 -122.850102)
			(xy 273.169448 -122.931957) (xy 273.154343 -123.012762) (xy 273.131847 -123.091829) (xy 273.102151 -123.168483)
			(xy 273.065509 -123.24207) (xy 273.022234 -123.311962) (xy 272.972694 -123.377563) (xy 272.917313 -123.438313)
			(xy 272.856563 -123.493694) (xy 272.790962 -123.543234) (xy 272.72107 -123.586509) (xy 272.647483 -123.623151)
			(xy 272.570829 -123.652847) (xy 272.491762 -123.675343) (xy 272.410957 -123.690448) (xy 272.329102 -123.698033)
			(xy 272.288 -123.698508) (xy 272.241604 -123.697925) (xy 272.149316 -123.68828) (xy 272.058532 -123.669084)
			(xy 271.970239 -123.640546) (xy 271.927574 -123.622308) (xy 271.917632 -123.618502) (xy 271.896368 -123.618502)
			(xy 271.886426 -123.622308) (xy 271.853507 -123.636537) (xy 271.785822 -123.660257) (xy 271.716442 -123.678437)
			(xy 271.681194 -123.685046) (xy 271.67107 -123.687344) (xy 271.653749 -123.698749) (xy 271.642344 -123.71607)
			(xy 271.640046 -123.726194) (xy 271.633416 -123.761437) (xy 271.61522 -123.83081) (xy 271.591513 -123.898498)
			(xy 271.577308 -123.931426) (xy 271.573502 -123.941368) (xy 271.573502 -123.962632) (xy 271.577308 -123.972574)
			(xy 271.591537 -124.005493) (xy 271.615257 -124.073178) (xy 271.633437 -124.142558) (xy 271.640046 -124.177806)
			(xy 271.642344 -124.18793) (xy 271.653749 -124.205251) (xy 271.67107 -124.216656) (xy 271.681194 -124.218954)
			(xy 271.716437 -124.225584) (xy 271.78581 -124.24378) (xy 271.853498 -124.267487) (xy 271.886426 -124.281692)
			(xy 271.896368 -124.285498) (xy 271.917632 -124.285498) (xy 271.927574 -124.281692) (xy 271.970236 -124.263447)
			(xy 272.058529 -124.234903) (xy 272.149314 -124.21571) (xy 272.241604 -124.206077) (xy 272.288 -124.205492)
			(xy 272.329102 -124.205967) (xy 272.410957 -124.213552) (xy 272.491762 -124.228657) (xy 272.570829 -124.251153)
			(xy 272.647483 -124.280849) (xy 272.72107 -124.317491) (xy 272.790962 -124.360766) (xy 272.856563 -124.410306)
			(xy 272.917313 -124.465687) (xy 272.972694 -124.526437) (xy 273.022234 -124.592038) (xy 273.065509 -124.66193)
			(xy 273.102151 -124.735517) (xy 273.131847 -124.812171) (xy 273.154343 -124.891238) (xy 273.169448 -124.972043)
			(xy 273.177033 -125.053898) (xy 273.177508 -125.095) (xy 273.176925 -125.141396) (xy 273.16728 -125.233684)
			(xy 273.148084 -125.324468) (xy 273.119546 -125.412761) (xy 273.101308 -125.455426) (xy 273.097502 -125.465368)
			(xy 273.097502 -125.486632) (xy 273.101308 -125.496574) (xy 273.119553 -125.539236) (xy 273.148097 -125.627529)
			(xy 273.16729 -125.718314) (xy 273.176923 -125.810604) (xy 273.177508 -125.857) (xy 273.177033 -125.898102)
			(xy 273.169448 -125.979957) (xy 273.154343 -126.060762) (xy 273.131847 -126.139829) (xy 273.102151 -126.216483)
			(xy 273.065509 -126.29007) (xy 273.022234 -126.359962) (xy 272.972694 -126.425563) (xy 272.917313 -126.486313)
			(xy 272.856563 -126.541694) (xy 272.790962 -126.591234) (xy 272.72107 -126.634509) (xy 272.647483 -126.671151)
			(xy 272.570829 -126.700847) (xy 272.491762 -126.723343) (xy 272.410957 -126.738448) (xy 272.329102 -126.746033)
			(xy 272.288 -126.746508) (xy 272.241604 -126.745925) (xy 272.149316 -126.73628) (xy 272.058532 -126.717084)
			(xy 271.970239 -126.688546) (xy 271.927574 -126.670308) (xy 271.917632 -126.666502) (xy 271.896368 -126.666502)
			(xy 271.886426 -126.670308) (xy 271.843764 -126.688553) (xy 271.755471 -126.717097) (xy 271.664686 -126.73629)
			(xy 271.572396 -126.745923) (xy 271.526 -126.746508) (xy 271.479604 -126.745925) (xy 271.387316 -126.73628)
			(xy 271.296532 -126.717084) (xy 271.208239 -126.688546) (xy 271.165574 -126.670308) (xy 271.155632 -126.666502)
			(xy 271.134368 -126.666502) (xy 271.124426 -126.670308) (xy 271.081764 -126.688553) (xy 270.993471 -126.717097)
			(xy 270.902686 -126.73629) (xy 270.810396 -126.745923) (xy 270.764 -126.746508) (xy 270.717604 -126.745925)
			(xy 270.625316 -126.73628) (xy 270.534532 -126.717084) (xy 270.446239 -126.688546) (xy 270.403574 -126.670308)
			(xy 270.393632 -126.666502) (xy 270.372368 -126.666502) (xy 270.362426 -126.670308) (xy 270.319764 -126.688553)
			(xy 270.231471 -126.717097) (xy 270.140686 -126.73629) (xy 270.048396 -126.745923) (xy 270.002 -126.746508)
			(xy 269.955604 -126.745925) (xy 269.863316 -126.73628) (xy 269.772532 -126.717084) (xy 269.684239 -126.688546)
			(xy 269.641574 -126.670308) (xy 269.631632 -126.666502) (xy 269.610368 -126.666502) (xy 269.600426 -126.670308)
			(xy 269.557764 -126.688553) (xy 269.469471 -126.717097) (xy 269.378686 -126.73629) (xy 269.286396 -126.745923)
			(xy 269.24 -126.746508) (xy 269.198898 -126.746033) (xy 269.117043 -126.738448) (xy 269.036238 -126.723343)
			(xy 268.957171 -126.700847) (xy 268.880517 -126.671151) (xy 268.80693 -126.634509) (xy 268.737038 -126.591234)
			(xy 268.671437 -126.541694) (xy 268.610687 -126.486313) (xy 268.555306 -126.425563) (xy 268.505766 -126.359962)
			(xy 268.462491 -126.29007) (xy 268.425849 -126.216483) (xy 268.396153 -126.139829) (xy 268.373657 -126.060762)
			(xy 268.358552 -125.979957) (xy 268.350967 -125.898102) (xy 268.350492 -125.857) (xy 235.067746 -125.857)
			(xy 235.096236 -125.874641) (xy 235.161855 -125.924196) (xy 235.222622 -125.979595) (xy 235.278019 -126.040363)
			(xy 235.327572 -126.105984) (xy 235.37086 -126.175897) (xy 235.407512 -126.249506) (xy 235.437217 -126.326182)
			(xy 235.45972 -126.405272) (xy 235.474829 -126.486101) (xy 235.482417 -126.567979) (xy 235.482892 -126.609094)
			(xy 235.482318 -126.653145) (xy 235.473542 -126.740808) (xy 235.456153 -126.827177) (xy 235.430321 -126.911407)
			(xy 235.413804 -126.952248) (xy 235.410474 -126.961259) (xy 235.410073 -126.98045) (xy 235.413042 -126.989586)
			(xy 235.426531 -127.026969) (xy 235.447571 -127.103614) (xy 235.461682 -127.181831) (xy 235.46875 -127.260996)
			(xy 235.469176 -127.300736) (xy 235.468573 -127.347131) (xy 235.458934 -127.439419) (xy 235.439744 -127.530203)
			(xy 235.411211 -127.618497) (xy 235.392976 -127.661162) (xy 235.389151 -127.671098) (xy 235.389165 -127.692367)
			(xy 235.392976 -127.70231) (xy 235.411231 -127.744968) (xy 235.439773 -127.833262) (xy 235.458963 -127.924048)
			(xy 235.468593 -128.01634) (xy 235.469176 -128.062736) (xy 235.468573 -128.109131) (xy 235.458934 -128.201419)
			(xy 235.439744 -128.292203) (xy 235.411211 -128.380497) (xy 235.392976 -128.423162) (xy 235.389151 -128.433098)
			(xy 235.389165 -128.454367) (xy 235.392976 -128.46431) (xy 235.411231 -128.506968) (xy 235.439773 -128.595262)
			(xy 235.458963 -128.686048) (xy 235.468593 -128.77834) (xy 235.469176 -128.824736) (xy 235.468573 -128.871131)
			(xy 235.458934 -128.963419) (xy 235.455402 -128.980127) (xy 270.348706 -128.980127) (xy 270.348706 -128.895405)
			(xy 270.356759 -128.811068) (xy 270.372793 -128.727878) (xy 270.396661 -128.646588) (xy 270.428149 -128.567936)
			(xy 270.466971 -128.492633) (xy 270.512774 -128.421361) (xy 270.565145 -128.354765) (xy 270.62361 -128.29345)
			(xy 270.687638 -128.237969) (xy 270.75665 -128.188826) (xy 270.83002 -128.146466) (xy 270.907085 -128.111271)
			(xy 270.987147 -128.083562) (xy 271.06948 -128.063588) (xy 271.153339 -128.051531) (xy 271.237964 -128.0475)
			(xy 271.322589 -128.051531) (xy 271.406448 -128.063588) (xy 271.488781 -128.083562) (xy 271.568843 -128.111271)
			(xy 271.645908 -128.146466) (xy 271.719278 -128.188826) (xy 271.78829 -128.237969) (xy 271.852318 -128.29345)
			(xy 271.910783 -128.354765) (xy 271.963154 -128.421361) (xy 272.008957 -128.492633) (xy 272.047779 -128.567936)
			(xy 272.079267 -128.646588) (xy 272.103135 -128.727878) (xy 272.119169 -128.811068) (xy 272.127222 -128.895405)
			(xy 272.127726 -128.937766) (xy 272.127222 -128.980127) (xy 272.119169 -129.064464) (xy 272.103135 -129.147654)
			(xy 272.079267 -129.228944) (xy 272.047779 -129.307596) (xy 272.008957 -129.382899) (xy 271.963154 -129.454171)
			(xy 271.910783 -129.520767) (xy 271.852318 -129.582082) (xy 271.78829 -129.637563) (xy 271.719278 -129.686706)
			(xy 271.645908 -129.729066) (xy 271.568843 -129.764261) (xy 271.488781 -129.79197) (xy 271.406448 -129.811944)
			(xy 271.322589 -129.824001) (xy 271.237964 -129.828033) (xy 271.153339 -129.824001) (xy 271.06948 -129.811944)
			(xy 270.987147 -129.79197) (xy 270.907085 -129.764261) (xy 270.83002 -129.729066) (xy 270.75665 -129.686706)
			(xy 270.687638 -129.637563) (xy 270.62361 -129.582082) (xy 270.565145 -129.520767) (xy 270.512774 -129.454171)
			(xy 270.466971 -129.382899) (xy 270.428149 -129.307596) (xy 270.396661 -129.228944) (xy 270.372793 -129.147654)
			(xy 270.356759 -129.064464) (xy 270.348706 -128.980127) (xy 235.455402 -128.980127) (xy 235.439744 -129.054203)
			(xy 235.411211 -129.142497) (xy 235.392976 -129.185162) (xy 235.389151 -129.195098) (xy 235.389165 -129.216367)
			(xy 235.392976 -129.22631) (xy 235.411231 -129.268968) (xy 235.439773 -129.357262) (xy 235.458963 -129.448048)
			(xy 235.468593 -129.54034) (xy 235.469176 -129.586736) (xy 235.468573 -129.633131) (xy 235.458934 -129.725419)
			(xy 235.439744 -129.816203) (xy 235.411211 -129.904497) (xy 235.392976 -129.947162) (xy 235.389151 -129.957098)
			(xy 235.389165 -129.978367) (xy 235.392976 -129.98831) (xy 235.411231 -130.030968) (xy 235.439773 -130.119262)
			(xy 235.458963 -130.210048) (xy 235.468593 -130.30234) (xy 235.469176 -130.348736) (xy 235.468573 -130.395131)
			(xy 235.458934 -130.487419) (xy 235.449335 -130.532829) (xy 268.757142 -130.532829) (xy 268.757142 -130.448107)
			(xy 268.765195 -130.36377) (xy 268.781229 -130.28058) (xy 268.805097 -130.19929) (xy 268.836585 -130.120638)
			(xy 268.875407 -130.045335) (xy 268.92121 -129.974063) (xy 268.973581 -129.907467) (xy 269.032046 -129.846152)
			(xy 269.096074 -129.790671) (xy 269.165086 -129.741528) (xy 269.238456 -129.699168) (xy 269.315521 -129.663973)
			(xy 269.395583 -129.636264) (xy 269.477916 -129.61629) (xy 269.561775 -129.604233) (xy 269.6464 -129.600202)
			(xy 269.731025 -129.604233) (xy 269.814884 -129.61629) (xy 269.897217 -129.636264) (xy 269.977279 -129.663973)
			(xy 270.054344 -129.699168) (xy 270.127714 -129.741528) (xy 270.196726 -129.790671) (xy 270.260754 -129.846152)
			(xy 270.319219 -129.907467) (xy 270.37159 -129.974063) (xy 270.417393 -130.045335) (xy 270.456215 -130.120638)
			(xy 270.487703 -130.19929) (xy 270.511571 -130.28058) (xy 270.527605 -130.36377) (xy 270.535658 -130.448107)
			(xy 270.536162 -130.490468) (xy 270.535658 -130.532829) (xy 270.527605 -130.617166) (xy 270.511571 -130.700356)
			(xy 270.487703 -130.781646) (xy 270.456215 -130.860298) (xy 270.417393 -130.935601) (xy 270.37159 -131.006873)
			(xy 270.319219 -131.073469) (xy 270.260754 -131.134784) (xy 270.196726 -131.190265) (xy 270.127714 -131.239408)
			(xy 270.054344 -131.281768) (xy 269.977279 -131.316963) (xy 269.897217 -131.344672) (xy 269.814884 -131.364646)
			(xy 269.731025 -131.376703) (xy 269.6464 -131.380735) (xy 269.561775 -131.376703) (xy 269.477916 -131.364646)
			(xy 269.395583 -131.344672) (xy 269.315521 -131.316963) (xy 269.238456 -131.281768) (xy 269.165086 -131.239408)
			(xy 269.096074 -131.190265) (xy 269.032046 -131.134784) (xy 268.973581 -131.073469) (xy 268.92121 -131.006873)
			(xy 268.875407 -130.935601) (xy 268.836585 -130.860298) (xy 268.805097 -130.781646) (xy 268.781229 -130.700356)
			(xy 268.765195 -130.617166) (xy 268.757142 -130.532829) (xy 235.449335 -130.532829) (xy 235.439744 -130.578203)
			(xy 235.411211 -130.666497) (xy 235.392976 -130.709162) (xy 235.389151 -130.719098) (xy 235.389165 -130.740367)
			(xy 235.392976 -130.75031) (xy 235.411231 -130.792968) (xy 235.439773 -130.881262) (xy 235.458963 -130.972048)
			(xy 235.468593 -131.06434) (xy 235.469176 -131.110736) (xy 235.4687 -131.152245) (xy 235.460981 -131.234903)
			(xy 235.445588 -131.316482) (xy 235.422653 -131.396269) (xy 235.407962 -131.435094) (xy 235.404787 -131.444591)
			(xy 235.405179 -131.464591) (xy 235.408724 -131.473956) (xy 235.42646 -131.51612) (xy 235.451388 -131.594352)
			(xy 277.69185 -131.594352) (xy 277.69185 -61.165994) (xy 277.692371 -61.132734) (xy 277.701058 -61.066783)
			(xy 277.718283 -61.002531) (xy 277.743751 -60.941079) (xy 277.777025 -60.883479) (xy 277.817536 -60.830717)
			(xy 277.840694 -60.806838) (xy 279.28951 -59.358022) (xy 279.313407 -59.334883) (xy 279.366164 -59.294369)
			(xy 279.423761 -59.261092) (xy 279.48521 -59.235621) (xy 279.549458 -59.218392) (xy 279.615407 -59.209702)
			(xy 279.648666 -59.209178) (xy 298.525184 -59.209178) (xy 298.558444 -59.209705) (xy 298.624395 -59.21839)
			(xy 298.688647 -59.235613) (xy 298.750099 -59.261079) (xy 298.807699 -59.294353) (xy 298.860461 -59.334864)
			(xy 298.88434 -59.358022) (xy 300.12259 -60.596272) (xy 300.145761 -60.620139) (xy 300.186271 -60.672903)
			(xy 300.219544 -60.730506) (xy 300.245009 -60.791961) (xy 300.262231 -60.856215) (xy 300.270914 -60.922167)
			(xy 300.271434 -60.955428) (xy 300.271434 -72.65289) (xy 300.271856 -72.66296) (xy 300.279578 -72.681558)
			(xy 300.28642 -72.688958) (xy 300.477428 -72.879966) (xy 310.009801 -72.879966) (xy 310.013811 -72.774063)
			(xy 310.025819 -72.668767) (xy 310.045756 -72.564681) (xy 310.073508 -72.462401) (xy 310.108916 -72.362512)
			(xy 310.151777 -72.265588) (xy 310.201845 -72.172182) (xy 310.258835 -72.082831) (xy 310.322418 -71.998045)
			(xy 310.392232 -71.918311) (xy 310.467876 -71.844086) (xy 310.548916 -71.775793) (xy 310.63489 -71.713826)
			(xy 310.725304 -71.658538) (xy 310.81964 -71.610246) (xy 310.917359 -71.569227) (xy 311.017899 -71.535716)
			(xy 311.120687 -71.509904) (xy 311.225131 -71.49194) (xy 311.330636 -71.481927) (xy 311.436595 -71.479921)
			(xy 311.542403 -71.485935) (xy 311.647453 -71.499934) (xy 311.751143 -71.521837) (xy 311.85288 -71.55152)
			(xy 311.952081 -71.588811) (xy 312.048177 -71.633499) (xy 312.140618 -71.685326) (xy 312.228875 -71.743996)
			(xy 312.312442 -71.809173) (xy 312.390841 -71.880483) (xy 312.463622 -71.957517) (xy 312.530368 -72.039836)
			(xy 312.590698 -72.126967) (xy 312.644265 -72.218411) (xy 312.690763 -72.313644) (xy 312.729925 -72.412121)
			(xy 312.761528 -72.513278) (xy 312.785389 -72.616536) (xy 312.801374 -72.721302) (xy 312.809389 -72.826977)
			(xy 312.80989 -72.879966) (xy 312.809389 -72.932955) (xy 312.801374 -73.03863) (xy 312.785389 -73.143396)
			(xy 312.761528 -73.246654) (xy 312.729925 -73.347811) (xy 312.690763 -73.446288) (xy 312.644265 -73.541521)
			(xy 312.590698 -73.632965) (xy 312.530368 -73.720096) (xy 312.463622 -73.802415) (xy 312.390841 -73.879449)
			(xy 312.312442 -73.950759) (xy 312.228875 -74.015936) (xy 312.140618 -74.074606) (xy 312.048177 -74.126433)
			(xy 311.952081 -74.171121) (xy 311.85288 -74.208412) (xy 311.751143 -74.238095) (xy 311.647453 -74.259998)
			(xy 311.542403 -74.273997) (xy 311.436595 -74.280011) (xy 311.330636 -74.278005) (xy 311.225131 -74.267992)
			(xy 311.120687 -74.250028) (xy 311.017899 -74.224216) (xy 310.917359 -74.190705) (xy 310.81964 -74.149686)
			(xy 310.725304 -74.101394) (xy 310.63489 -74.046106) (xy 310.548916 -73.984139) (xy 310.467876 -73.915846)
			(xy 310.392232 -73.841621) (xy 310.322418 -73.761887) (xy 310.258835 -73.677101) (xy 310.201845 -73.58775)
			(xy 310.151777 -73.494344) (xy 310.108916 -73.39742) (xy 310.073508 -73.297531) (xy 310.045756 -73.195251)
			(xy 310.025819 -73.091165) (xy 310.013811 -72.985869) (xy 310.009801 -72.879966) (xy 300.477428 -72.879966)
			(xy 300.613826 -73.016364) (xy 300.621227 -73.023203) (xy 300.639825 -73.030924) (xy 300.649894 -73.03135)
			(xy 306.38115 -73.03135) (xy 306.414411 -73.031843) (xy 306.480363 -73.040536) (xy 306.544615 -73.057766)
			(xy 306.606067 -73.083239) (xy 306.663667 -73.116518) (xy 306.716428 -73.157033) (xy 306.740306 -73.180194)
			(xy 308.856126 -75.296014) (xy 308.863521 -75.30286) (xy 308.882124 -75.310576) (xy 308.892194 -75.311)
			(xy 319.8876 -75.311) (xy 319.920859 -75.311539) (xy 319.986809 -75.320225) (xy 320.05106 -75.337447)
			(xy 320.112511 -75.362911) (xy 320.170112 -75.396182) (xy 320.222876 -75.436688) (xy 320.246756 -75.459844)
			(xy 321.288156 -76.501244) (xy 321.311308 -76.525129) (xy 321.351821 -76.577889) (xy 321.385097 -76.635488)
			(xy 321.410566 -76.696939) (xy 321.427791 -76.76119) (xy 321.436479 -76.82714) (xy 321.437 -76.8604)
			(xy 321.437 -120.904) (xy 321.436461 -120.937259) (xy 321.427775 -121.003209) (xy 321.410553 -121.06746)
			(xy 321.385089 -121.128911) (xy 321.351818 -121.186512) (xy 321.311312 -121.239276) (xy 321.288156 -121.263156)
			(xy 319.992756 -122.558556) (xy 319.968871 -122.581708) (xy 319.916111 -122.622221) (xy 319.858512 -122.655497)
			(xy 319.797061 -122.680966) (xy 319.73281 -122.698191) (xy 319.66686 -122.706879) (xy 319.6336 -122.7074)
			(xy 304.015394 -122.7074) (xy 304.005321 -122.707796) (xy 303.986722 -122.715534) (xy 303.979326 -122.722386)
			(xy 300.28642 -126.415292) (xy 300.279594 -126.422703) (xy 300.271865 -126.441294) (xy 300.271434 -126.45136)
			(xy 300.271434 -131.730496) (xy 300.270911 -131.763756) (xy 300.262225 -131.829707) (xy 300.245001 -131.893959)
			(xy 300.219534 -131.955411) (xy 300.18626 -132.013011) (xy 300.145749 -132.065773) (xy 300.12259 -132.089652)
			(xy 298.892722 -133.31952) (xy 298.868863 -133.3427) (xy 298.816096 -133.383208) (xy 298.758492 -133.416478)
			(xy 298.697036 -133.441942) (xy 298.632781 -133.459163) (xy 298.566827 -133.467845) (xy 298.533566 -133.468364)
			(xy 279.565862 -133.468364) (xy 279.532601 -133.46786) (xy 279.46665 -133.459168) (xy 279.402398 -133.44194)
			(xy 279.340946 -133.416469) (xy 279.283346 -133.383193) (xy 279.230585 -133.342679) (xy 279.206706 -133.31952)
			(xy 277.840694 -131.953508) (xy 277.81751 -131.929653) (xy 277.777002 -131.876886) (xy 277.743731 -131.81928)
			(xy 277.718269 -131.757823) (xy 277.701049 -131.693568) (xy 277.692368 -131.627614) (xy 277.69185 -131.594352)
			(xy 235.451388 -131.594352) (xy 235.454232 -131.603278) (xy 235.472912 -131.692826) (xy 235.482304 -131.783818)
			(xy 235.482892 -131.829556) (xy 235.482406 -131.870659) (xy 235.474825 -131.952514) (xy 235.459723 -132.033321)
			(xy 235.437229 -132.11239) (xy 235.407535 -132.189045) (xy 235.370895 -132.262634) (xy 235.327621 -132.332528)
			(xy 235.278083 -132.39813) (xy 235.222702 -132.458882) (xy 235.161952 -132.514265) (xy 235.096351 -132.563805)
			(xy 235.026458 -132.607082) (xy 234.952871 -132.643724) (xy 234.876216 -132.67342) (xy 234.797148 -132.695916)
			(xy 234.716342 -132.711021) (xy 234.634487 -132.718605) (xy 234.593384 -132.719064) (xy 234.546988 -132.718491)
			(xy 234.454699 -132.708843) (xy 234.363916 -132.689645) (xy 234.275622 -132.661103) (xy 234.232958 -132.642864)
			(xy 234.223016 -132.639058) (xy 234.201752 -132.639058) (xy 234.19181 -132.642864) (xy 234.149149 -132.661111)
			(xy 234.060856 -132.689655) (xy 233.970071 -132.708848) (xy 233.87778 -132.71848) (xy 233.831384 -132.719064)
			(xy 233.784988 -132.718491) (xy 233.692699 -132.708843) (xy 233.601916 -132.689645) (xy 233.513622 -132.661103)
			(xy 233.470958 -132.642864) (xy 233.461016 -132.639058) (xy 233.439752 -132.639058) (xy 233.42981 -132.642864)
			(xy 233.387149 -132.661111) (xy 233.298856 -132.689655) (xy 233.208071 -132.708848) (xy 233.11578 -132.71848)
			(xy 233.069384 -132.719064) (xy 233.026817 -132.718594) (xy 232.942069 -132.710485) (xy 232.858485 -132.694314)
			(xy 232.776829 -132.670229) (xy 232.737152 -132.654802) (xy 232.7279 -132.651549) (xy 232.708304 -132.651549)
			(xy 232.699052 -132.654802) (xy 232.65938 -132.670239) (xy 232.57772 -132.694311) (xy 232.494134 -132.710474)
			(xy 232.409387 -132.718579) (xy 232.36682 -132.719064) (xy 232.320424 -132.718478) (xy 232.228136 -132.708834)
			(xy 232.137352 -132.689639) (xy 232.049059 -132.661102) (xy 232.006394 -132.642864) (xy 231.996452 -132.639058)
			(xy 231.975188 -132.639058) (xy 231.965246 -132.642864) (xy 231.92258 -132.661099) (xy 231.834289 -132.689647)
			(xy 231.743505 -132.708842) (xy 231.651216 -132.718478) (xy 231.60482 -132.719064) (xy 231.563716 -132.718629)
			(xy 231.481858 -132.711045) (xy 231.401049 -132.69594) (xy 231.321979 -132.673444) (xy 231.245322 -132.643747)
			(xy 231.171732 -132.607104) (xy 231.101838 -132.563827) (xy 231.036234 -132.514285) (xy 230.975482 -132.458901)
			(xy 230.9201 -132.398147) (xy 230.87056 -132.332543) (xy 230.827284 -132.262647) (xy 230.790643 -132.189056)
			(xy 230.760949 -132.112398) (xy 230.738454 -132.033327) (xy 230.723352 -131.952518) (xy 230.71577 -131.87066)
			(xy 230.715312 -131.829556) (xy 230.715787 -131.788047) (xy 230.723505 -131.705388) (xy 230.7389 -131.62381)
			(xy 230.761835 -131.544023) (xy 230.776526 -131.505198) (xy 230.779706 -131.495702) (xy 230.779312 -131.475701)
			(xy 230.775764 -131.466336) (xy 230.758025 -131.424174) (xy 230.730254 -131.337015) (xy 230.711574 -131.247467)
			(xy 230.702183 -131.156474) (xy 230.701596 -131.110736) (xy 217.770454 -131.110736) (xy 217.796935 -131.192665)
			(xy 217.816124 -131.283452) (xy 217.825753 -131.375743) (xy 217.826336 -131.42214) (xy 217.82573 -131.468535)
			(xy 217.816091 -131.560823) (xy 217.796902 -131.651606) (xy 217.76837 -131.739901) (xy 217.750136 -131.782566)
			(xy 217.746305 -131.792501) (xy 217.746321 -131.813772) (xy 217.750136 -131.823714) (xy 217.768396 -131.86637)
			(xy 217.796935 -131.954665) (xy 217.816124 -132.045452) (xy 217.825753 -132.137743) (xy 217.826336 -132.18414)
			(xy 217.82573 -132.230535) (xy 217.816091 -132.322823) (xy 217.796902 -132.413606) (xy 217.76837 -132.501901)
			(xy 217.750136 -132.544566) (xy 217.746305 -132.554501) (xy 217.746321 -132.575772) (xy 217.750136 -132.585714)
			(xy 217.768396 -132.62837) (xy 217.796935 -132.716665) (xy 217.816124 -132.807452) (xy 217.825753 -132.899743)
			(xy 217.826336 -132.94614) (xy 217.825872 -132.987242) (xy 217.818283 -133.069096) (xy 217.803175 -133.1499)
			(xy 217.780677 -133.228966) (xy 217.750979 -133.305619) (xy 217.714335 -133.379205) (xy 217.671059 -133.449096)
			(xy 217.621519 -133.514696) (xy 217.566137 -133.575446) (xy 217.505387 -133.630826) (xy 217.439786 -133.680366)
			(xy 217.369894 -133.723641) (xy 217.296308 -133.760284) (xy 217.219655 -133.78998) (xy 217.140589 -133.812478)
			(xy 217.059784 -133.827585) (xy 216.97793 -133.835172) (xy 216.936828 -133.835648) (xy 216.890433 -133.83506)
			(xy 216.798144 -133.825417) (xy 216.70736 -133.806223) (xy 216.619067 -133.777686) (xy 216.576402 -133.759448)
			(xy 216.56646 -133.755642) (xy 216.545196 -133.755642) (xy 216.535254 -133.759448) (xy 216.492589 -133.777686)
			(xy 216.404298 -133.806231) (xy 216.313513 -133.825426) (xy 216.221224 -133.835062) (xy 216.174828 -133.835648)
			(xy 216.131404 -133.835154) (xy 216.044966 -133.826739) (xy 215.959761 -133.809928) (xy 215.876604 -133.784881)
			(xy 215.836246 -133.768846) (xy 215.826836 -133.765374) (xy 215.806794 -133.765374) (xy 215.797384 -133.768846)
			(xy 215.757016 -133.78485) (xy 215.673856 -133.809876) (xy 215.588656 -133.826689) (xy 215.502224 -133.835131)
			(xy 215.458802 -133.835648) (xy 215.412406 -133.835069) (xy 215.320118 -133.825424) (xy 215.229334 -133.806227)
			(xy 215.141041 -133.777687) (xy 215.098376 -133.759448) (xy 215.088434 -133.755642) (xy 215.06717 -133.755642)
			(xy 215.057228 -133.759448) (xy 215.014567 -133.777695) (xy 214.926274 -133.806238) (xy 214.835489 -133.82543)
			(xy 214.743198 -133.835063) (xy 214.696802 -133.835648) (xy 214.655331 -133.835195) (xy 214.572745 -133.827514)
			(xy 214.491233 -133.812181) (xy 214.411501 -133.78933) (xy 214.372698 -133.774688) (xy 214.363204 -133.771495)
			(xy 214.343199 -133.771892) (xy 214.333836 -133.77545) (xy 214.291673 -133.793169) (xy 214.204503 -133.820863)
			(xy 214.114954 -133.839474) (xy 214.023968 -133.848804) (xy 213.978236 -133.849364) (xy 213.937132 -133.848913)
			(xy 213.855275 -133.841331) (xy 213.774466 -133.826228) (xy 213.695396 -133.803733) (xy 213.618739 -133.774037)
			(xy 213.54515 -133.737395) (xy 213.475255 -133.694119) (xy 213.409651 -133.644578) (xy 213.348899 -133.589195)
			(xy 213.293517 -133.528442) (xy 213.243976 -133.462839) (xy 213.200701 -133.392943) (xy 213.164059 -133.319353)
			(xy 213.134365 -133.242696) (xy 213.11187 -133.163626) (xy 213.096768 -133.082817) (xy 213.089186 -133.00096)
			(xy 213.088728 -132.959856) (xy 0.509016 -132.959856) (xy 0.509016 -136.959232) (xy 40.624242 -136.959232)
			(xy 40.624242 -136.852768) (xy 40.632198 -136.746601) (xy 40.648065 -136.641325) (xy 40.671756 -136.53753)
			(xy 40.703137 -136.435795) (xy 40.742033 -136.33669) (xy 40.788226 -136.240768) (xy 40.841459 -136.148567)
			(xy 40.901432 -136.060602) (xy 40.967812 -135.977365) (xy 41.040226 -135.89932) (xy 41.118271 -135.826906)
			(xy 41.201508 -135.760526) (xy 41.289473 -135.700553) (xy 41.381674 -135.64732) (xy 41.477596 -135.601127)
			(xy 41.576701 -135.562231) (xy 41.678436 -135.53085) (xy 41.782231 -135.507159) (xy 41.887507 -135.491292)
			(xy 41.993674 -135.483336) (xy 42.100138 -135.483336) (xy 42.206305 -135.491292) (xy 42.311581 -135.507159)
			(xy 42.415376 -135.53085) (xy 42.517111 -135.562231) (xy 42.616216 -135.601127) (xy 42.712138 -135.64732)
			(xy 42.804339 -135.700553) (xy 42.892304 -135.760526) (xy 42.975541 -135.826906) (xy 43.053586 -135.89932)
			(xy 43.126 -135.977365) (xy 43.19238 -136.060602) (xy 43.252353 -136.148567) (xy 43.305586 -136.240768)
			(xy 43.351779 -136.33669) (xy 43.390675 -136.435795) (xy 43.422056 -136.53753) (xy 43.445747 -136.641325)
			(xy 43.461614 -136.746601) (xy 43.46957 -136.852768) (xy 43.470068 -136.906) (xy 43.46957 -136.959232)
			(xy 52.816242 -136.959232) (xy 52.816242 -136.852768) (xy 52.824198 -136.746601) (xy 52.840065 -136.641325)
			(xy 52.863756 -136.53753) (xy 52.895137 -136.435795) (xy 52.934033 -136.33669) (xy 52.980226 -136.240768)
			(xy 53.033459 -136.148567) (xy 53.093432 -136.060602) (xy 53.159812 -135.977365) (xy 53.232226 -135.89932)
			(xy 53.310271 -135.826906) (xy 53.393508 -135.760526) (xy 53.481473 -135.700553) (xy 53.573674 -135.64732)
			(xy 53.669596 -135.601127) (xy 53.768701 -135.562231) (xy 53.870436 -135.53085) (xy 53.974231 -135.507159)
			(xy 54.079507 -135.491292) (xy 54.185674 -135.483336) (xy 54.292138 -135.483336) (xy 54.398305 -135.491292)
			(xy 54.503581 -135.507159) (xy 54.607376 -135.53085) (xy 54.709111 -135.562231) (xy 54.808216 -135.601127)
			(xy 54.904138 -135.64732) (xy 54.996339 -135.700553) (xy 55.084304 -135.760526) (xy 55.167541 -135.826906)
			(xy 55.245586 -135.89932) (xy 55.318 -135.977365) (xy 55.38438 -136.060602) (xy 55.444353 -136.148567)
			(xy 55.497586 -136.240768) (xy 55.543779 -136.33669) (xy 55.582675 -136.435795) (xy 55.614056 -136.53753)
			(xy 55.637747 -136.641325) (xy 55.653614 -136.746601) (xy 55.66157 -136.852768) (xy 55.662068 -136.906)
			(xy 55.66157 -136.959232) (xy 65.008242 -136.959232) (xy 65.008242 -136.852768) (xy 65.016198 -136.746601)
			(xy 65.032065 -136.641325) (xy 65.055756 -136.53753) (xy 65.087137 -136.435795) (xy 65.126033 -136.33669)
			(xy 65.172226 -136.240768) (xy 65.225459 -136.148567) (xy 65.285432 -136.060602) (xy 65.351812 -135.977365)
			(xy 65.424226 -135.89932) (xy 65.502271 -135.826906) (xy 65.585508 -135.760526) (xy 65.673473 -135.700553)
			(xy 65.765674 -135.64732) (xy 65.861596 -135.601127) (xy 65.960701 -135.562231) (xy 66.062436 -135.53085)
			(xy 66.166231 -135.507159) (xy 66.271507 -135.491292) (xy 66.377674 -135.483336) (xy 66.484138 -135.483336)
			(xy 66.590305 -135.491292) (xy 66.695581 -135.507159) (xy 66.799376 -135.53085) (xy 66.901111 -135.562231)
			(xy 67.000216 -135.601127) (xy 67.096138 -135.64732) (xy 67.188339 -135.700553) (xy 67.276304 -135.760526)
			(xy 67.359541 -135.826906) (xy 67.437586 -135.89932) (xy 67.51 -135.977365) (xy 67.57638 -136.060602)
			(xy 67.636353 -136.148567) (xy 67.689586 -136.240768) (xy 67.735779 -136.33669) (xy 67.774675 -136.435795)
			(xy 67.806056 -136.53753) (xy 67.829747 -136.641325) (xy 67.845614 -136.746601) (xy 67.85357 -136.852768)
			(xy 67.854068 -136.906) (xy 67.85357 -136.959232) (xy 80.624162 -136.959232) (xy 80.624162 -136.852768)
			(xy 80.632118 -136.746601) (xy 80.647985 -136.641325) (xy 80.671676 -136.53753) (xy 80.703057 -136.435795)
			(xy 80.741953 -136.33669) (xy 80.788146 -136.240768) (xy 80.841379 -136.148567) (xy 80.901352 -136.060602)
			(xy 80.967732 -135.977365) (xy 81.040146 -135.89932) (xy 81.118191 -135.826906) (xy 81.201428 -135.760526)
			(xy 81.289393 -135.700553) (xy 81.381594 -135.64732) (xy 81.477516 -135.601127) (xy 81.576621 -135.562231)
			(xy 81.678356 -135.53085) (xy 81.782151 -135.507159) (xy 81.887427 -135.491292) (xy 81.993594 -135.483336)
			(xy 82.100058 -135.483336) (xy 82.206225 -135.491292) (xy 82.311501 -135.507159) (xy 82.415296 -135.53085)
			(xy 82.517031 -135.562231) (xy 82.616136 -135.601127) (xy 82.712058 -135.64732) (xy 82.804259 -135.700553)
			(xy 82.892224 -135.760526) (xy 82.975461 -135.826906) (xy 83.053506 -135.89932) (xy 83.12592 -135.977365)
			(xy 83.1923 -136.060602) (xy 83.252273 -136.148567) (xy 83.305506 -136.240768) (xy 83.351699 -136.33669)
			(xy 83.390595 -136.435795) (xy 83.421976 -136.53753) (xy 83.445667 -136.641325) (xy 83.461534 -136.746601)
			(xy 83.46949 -136.852768) (xy 83.469988 -136.906) (xy 83.46949 -136.959232) (xy 92.816162 -136.959232)
			(xy 92.816162 -136.852768) (xy 92.824118 -136.746601) (xy 92.839985 -136.641325) (xy 92.863676 -136.53753)
			(xy 92.895057 -136.435795) (xy 92.933953 -136.33669) (xy 92.980146 -136.240768) (xy 93.033379 -136.148567)
			(xy 93.093352 -136.060602) (xy 93.159732 -135.977365) (xy 93.232146 -135.89932) (xy 93.310191 -135.826906)
			(xy 93.393428 -135.760526) (xy 93.481393 -135.700553) (xy 93.573594 -135.64732) (xy 93.669516 -135.601127)
			(xy 93.768621 -135.562231) (xy 93.870356 -135.53085) (xy 93.974151 -135.507159) (xy 94.079427 -135.491292)
			(xy 94.185594 -135.483336) (xy 94.292058 -135.483336) (xy 94.398225 -135.491292) (xy 94.503501 -135.507159)
			(xy 94.607296 -135.53085) (xy 94.709031 -135.562231) (xy 94.808136 -135.601127) (xy 94.904058 -135.64732)
			(xy 94.996259 -135.700553) (xy 95.084224 -135.760526) (xy 95.167461 -135.826906) (xy 95.245506 -135.89932)
			(xy 95.31792 -135.977365) (xy 95.3843 -136.060602) (xy 95.444273 -136.148567) (xy 95.497506 -136.240768)
			(xy 95.543699 -136.33669) (xy 95.582595 -136.435795) (xy 95.613976 -136.53753) (xy 95.637667 -136.641325)
			(xy 95.653534 -136.746601) (xy 95.66149 -136.852768) (xy 95.661988 -136.906) (xy 95.66149 -136.959232)
			(xy 105.008162 -136.959232) (xy 105.008162 -136.852768) (xy 105.016118 -136.746601) (xy 105.031985 -136.641325)
			(xy 105.055676 -136.53753) (xy 105.087057 -136.435795) (xy 105.125953 -136.33669) (xy 105.172146 -136.240768)
			(xy 105.225379 -136.148567) (xy 105.285352 -136.060602) (xy 105.351732 -135.977365) (xy 105.424146 -135.89932)
			(xy 105.502191 -135.826906) (xy 105.585428 -135.760526) (xy 105.673393 -135.700553) (xy 105.765594 -135.64732)
			(xy 105.861516 -135.601127) (xy 105.960621 -135.562231) (xy 106.062356 -135.53085) (xy 106.166151 -135.507159)
			(xy 106.271427 -135.491292) (xy 106.377594 -135.483336) (xy 106.484058 -135.483336) (xy 106.590225 -135.491292)
			(xy 106.695501 -135.507159) (xy 106.799296 -135.53085) (xy 106.901031 -135.562231) (xy 107.000136 -135.601127)
			(xy 107.096058 -135.64732) (xy 107.188259 -135.700553) (xy 107.276224 -135.760526) (xy 107.359461 -135.826906)
			(xy 107.437506 -135.89932) (xy 107.50992 -135.977365) (xy 107.5763 -136.060602) (xy 107.636273 -136.148567)
			(xy 107.689506 -136.240768) (xy 107.735699 -136.33669) (xy 107.774595 -136.435795) (xy 107.805976 -136.53753)
			(xy 107.829667 -136.641325) (xy 107.845534 -136.746601) (xy 107.85349 -136.852768) (xy 107.853988 -136.906)
			(xy 107.85349 -136.959232) (xy 120.624336 -136.959232) (xy 120.624336 -136.852768) (xy 120.632292 -136.746601)
			(xy 120.648159 -136.641325) (xy 120.67185 -136.53753) (xy 120.703231 -136.435795) (xy 120.742127 -136.33669)
			(xy 120.78832 -136.240768) (xy 120.841553 -136.148567) (xy 120.901526 -136.060602) (xy 120.967906 -135.977365)
			(xy 121.04032 -135.89932) (xy 121.118365 -135.826906) (xy 121.201602 -135.760526) (xy 121.289567 -135.700553)
			(xy 121.381768 -135.64732) (xy 121.47769 -135.601127) (xy 121.576795 -135.562231) (xy 121.67853 -135.53085)
			(xy 121.782325 -135.507159) (xy 121.887601 -135.491292) (xy 121.993768 -135.483336) (xy 122.100232 -135.483336)
			(xy 122.206399 -135.491292) (xy 122.311675 -135.507159) (xy 122.41547 -135.53085) (xy 122.517205 -135.562231)
			(xy 122.61631 -135.601127) (xy 122.712232 -135.64732) (xy 122.804433 -135.700553) (xy 122.892398 -135.760526)
			(xy 122.975635 -135.826906) (xy 123.05368 -135.89932) (xy 123.126094 -135.977365) (xy 123.192474 -136.060602)
			(xy 123.252447 -136.148567) (xy 123.30568 -136.240768) (xy 123.351873 -136.33669) (xy 123.390769 -136.435795)
			(xy 123.42215 -136.53753) (xy 123.445841 -136.641325) (xy 123.461708 -136.746601) (xy 123.469664 -136.852768)
			(xy 123.470162 -136.906) (xy 123.469664 -136.959232) (xy 132.816336 -136.959232) (xy 132.816336 -136.852768)
			(xy 132.824292 -136.746601) (xy 132.840159 -136.641325) (xy 132.86385 -136.53753) (xy 132.895231 -136.435795)
			(xy 132.934127 -136.33669) (xy 132.98032 -136.240768) (xy 133.033553 -136.148567) (xy 133.093526 -136.060602)
			(xy 133.159906 -135.977365) (xy 133.23232 -135.89932) (xy 133.310365 -135.826906) (xy 133.393602 -135.760526)
			(xy 133.481567 -135.700553) (xy 133.573768 -135.64732) (xy 133.66969 -135.601127) (xy 133.768795 -135.562231)
			(xy 133.87053 -135.53085) (xy 133.974325 -135.507159) (xy 134.079601 -135.491292) (xy 134.185768 -135.483336)
			(xy 134.292232 -135.483336) (xy 134.398399 -135.491292) (xy 134.503675 -135.507159) (xy 134.60747 -135.53085)
			(xy 134.709205 -135.562231) (xy 134.80831 -135.601127) (xy 134.904232 -135.64732) (xy 134.996433 -135.700553)
			(xy 135.084398 -135.760526) (xy 135.167635 -135.826906) (xy 135.24568 -135.89932) (xy 135.318094 -135.977365)
			(xy 135.384474 -136.060602) (xy 135.444447 -136.148567) (xy 135.49768 -136.240768) (xy 135.543873 -136.33669)
			(xy 135.582769 -136.435795) (xy 135.61415 -136.53753) (xy 135.637841 -136.641325) (xy 135.653708 -136.746601)
			(xy 135.661664 -136.852768) (xy 135.662162 -136.906) (xy 135.661664 -136.959232) (xy 145.008336 -136.959232)
			(xy 145.008336 -136.852768) (xy 145.016292 -136.746601) (xy 145.032159 -136.641325) (xy 145.05585 -136.53753)
			(xy 145.087231 -136.435795) (xy 145.126127 -136.33669) (xy 145.17232 -136.240768) (xy 145.225553 -136.148567)
			(xy 145.285526 -136.060602) (xy 145.351906 -135.977365) (xy 145.42432 -135.89932) (xy 145.502365 -135.826906)
			(xy 145.585602 -135.760526) (xy 145.673567 -135.700553) (xy 145.765768 -135.64732) (xy 145.86169 -135.601127)
			(xy 145.960795 -135.562231) (xy 146.06253 -135.53085) (xy 146.166325 -135.507159) (xy 146.271601 -135.491292)
			(xy 146.377768 -135.483336) (xy 146.484232 -135.483336) (xy 146.590399 -135.491292) (xy 146.695675 -135.507159)
			(xy 146.79947 -135.53085) (xy 146.901205 -135.562231) (xy 147.00031 -135.601127) (xy 147.096232 -135.64732)
			(xy 147.188433 -135.700553) (xy 147.276398 -135.760526) (xy 147.359635 -135.826906) (xy 147.43768 -135.89932)
			(xy 147.510094 -135.977365) (xy 147.576474 -136.060602) (xy 147.636447 -136.148567) (xy 147.68968 -136.240768)
			(xy 147.735873 -136.33669) (xy 147.774769 -136.435795) (xy 147.80615 -136.53753) (xy 147.829841 -136.641325)
			(xy 147.845708 -136.746601) (xy 147.853664 -136.852768) (xy 147.854162 -136.906) (xy 147.853664 -136.959232)
			(xy 160.62451 -136.959232) (xy 160.62451 -136.852768) (xy 160.632466 -136.746601) (xy 160.648333 -136.641325)
			(xy 160.672024 -136.53753) (xy 160.703405 -136.435795) (xy 160.742301 -136.33669) (xy 160.788494 -136.240768)
			(xy 160.841727 -136.148567) (xy 160.9017 -136.060602) (xy 160.96808 -135.977365) (xy 161.040494 -135.89932)
			(xy 161.118539 -135.826906) (xy 161.201776 -135.760526) (xy 161.289741 -135.700553) (xy 161.381942 -135.64732)
			(xy 161.477864 -135.601127) (xy 161.576969 -135.562231) (xy 161.678704 -135.53085) (xy 161.782499 -135.507159)
			(xy 161.887775 -135.491292) (xy 161.993942 -135.483336) (xy 162.100406 -135.483336) (xy 162.206573 -135.491292)
			(xy 162.311849 -135.507159) (xy 162.415644 -135.53085) (xy 162.517379 -135.562231) (xy 162.616484 -135.601127)
			(xy 162.712406 -135.64732) (xy 162.804607 -135.700553) (xy 162.892572 -135.760526) (xy 162.975809 -135.826906)
			(xy 163.053854 -135.89932) (xy 163.126268 -135.977365) (xy 163.192648 -136.060602) (xy 163.252621 -136.148567)
			(xy 163.305854 -136.240768) (xy 163.352047 -136.33669) (xy 163.390943 -136.435795) (xy 163.422324 -136.53753)
			(xy 163.446015 -136.641325) (xy 163.461882 -136.746601) (xy 163.469838 -136.852768) (xy 163.470336 -136.906)
			(xy 163.469838 -136.959232) (xy 172.81651 -136.959232) (xy 172.81651 -136.852768) (xy 172.824466 -136.746601)
			(xy 172.840333 -136.641325) (xy 172.864024 -136.53753) (xy 172.895405 -136.435795) (xy 172.934301 -136.33669)
			(xy 172.980494 -136.240768) (xy 173.033727 -136.148567) (xy 173.0937 -136.060602) (xy 173.16008 -135.977365)
			(xy 173.232494 -135.89932) (xy 173.310539 -135.826906) (xy 173.393776 -135.760526) (xy 173.481741 -135.700553)
			(xy 173.573942 -135.64732) (xy 173.669864 -135.601127) (xy 173.768969 -135.562231) (xy 173.870704 -135.53085)
			(xy 173.974499 -135.507159) (xy 174.079775 -135.491292) (xy 174.185942 -135.483336) (xy 174.292406 -135.483336)
			(xy 174.398573 -135.491292) (xy 174.503849 -135.507159) (xy 174.607644 -135.53085) (xy 174.709379 -135.562231)
			(xy 174.808484 -135.601127) (xy 174.904406 -135.64732) (xy 174.996607 -135.700553) (xy 175.084572 -135.760526)
			(xy 175.167809 -135.826906) (xy 175.245854 -135.89932) (xy 175.318268 -135.977365) (xy 175.384648 -136.060602)
			(xy 175.444621 -136.148567) (xy 175.497854 -136.240768) (xy 175.544047 -136.33669) (xy 175.582943 -136.435795)
			(xy 175.614324 -136.53753) (xy 175.638015 -136.641325) (xy 175.653882 -136.746601) (xy 175.661838 -136.852768)
			(xy 175.662336 -136.906) (xy 175.661838 -136.959232) (xy 185.00851 -136.959232) (xy 185.00851 -136.852768)
			(xy 185.016466 -136.746601) (xy 185.032333 -136.641325) (xy 185.056024 -136.53753) (xy 185.087405 -136.435795)
			(xy 185.126301 -136.33669) (xy 185.172494 -136.240768) (xy 185.225727 -136.148567) (xy 185.2857 -136.060602)
			(xy 185.35208 -135.977365) (xy 185.424494 -135.89932) (xy 185.502539 -135.826906) (xy 185.585776 -135.760526)
			(xy 185.673741 -135.700553) (xy 185.765942 -135.64732) (xy 185.861864 -135.601127) (xy 185.960969 -135.562231)
			(xy 186.062704 -135.53085) (xy 186.166499 -135.507159) (xy 186.271775 -135.491292) (xy 186.377942 -135.483336)
			(xy 186.484406 -135.483336) (xy 186.590573 -135.491292) (xy 186.695849 -135.507159) (xy 186.799644 -135.53085)
			(xy 186.901379 -135.562231) (xy 187.000484 -135.601127) (xy 187.096406 -135.64732) (xy 187.188607 -135.700553)
			(xy 187.276572 -135.760526) (xy 187.359809 -135.826906) (xy 187.437854 -135.89932) (xy 187.510268 -135.977365)
			(xy 187.576648 -136.060602) (xy 187.636621 -136.148567) (xy 187.689854 -136.240768) (xy 187.736047 -136.33669)
			(xy 187.774943 -136.435795) (xy 187.806324 -136.53753) (xy 187.830015 -136.641325) (xy 187.845882 -136.746601)
			(xy 187.853838 -136.852768) (xy 187.854336 -136.906) (xy 187.853838 -136.959232) (xy 187.845882 -137.065399)
			(xy 187.830015 -137.170675) (xy 187.806324 -137.27447) (xy 187.774943 -137.376205) (xy 187.736047 -137.47531)
			(xy 187.689854 -137.571232) (xy 187.636621 -137.663433) (xy 187.576648 -137.751398) (xy 187.510268 -137.834635)
			(xy 187.437854 -137.91268) (xy 187.359809 -137.985094) (xy 187.276572 -138.051474) (xy 187.188607 -138.111447)
			(xy 187.096406 -138.16468) (xy 187.000484 -138.210873) (xy 186.901379 -138.249769) (xy 186.799644 -138.28115)
			(xy 186.695849 -138.304841) (xy 186.590573 -138.320708) (xy 186.484406 -138.328664) (xy 186.377942 -138.328664)
			(xy 186.271775 -138.320708) (xy 186.166499 -138.304841) (xy 186.062704 -138.28115) (xy 185.960969 -138.249769)
			(xy 185.861864 -138.210873) (xy 185.765942 -138.16468) (xy 185.673741 -138.111447) (xy 185.585776 -138.051474)
			(xy 185.502539 -137.985094) (xy 185.424494 -137.91268) (xy 185.35208 -137.834635) (xy 185.2857 -137.751398)
			(xy 185.225727 -137.663433) (xy 185.172494 -137.571232) (xy 185.126301 -137.47531) (xy 185.087405 -137.376205)
			(xy 185.056024 -137.27447) (xy 185.032333 -137.170675) (xy 185.016466 -137.065399) (xy 185.00851 -136.959232)
			(xy 175.661838 -136.959232) (xy 175.653882 -137.065399) (xy 175.638015 -137.170675) (xy 175.614324 -137.27447)
			(xy 175.582943 -137.376205) (xy 175.544047 -137.47531) (xy 175.497854 -137.571232) (xy 175.444621 -137.663433)
			(xy 175.384648 -137.751398) (xy 175.318268 -137.834635) (xy 175.245854 -137.91268) (xy 175.167809 -137.985094)
			(xy 175.084572 -138.051474) (xy 174.996607 -138.111447) (xy 174.904406 -138.16468) (xy 174.808484 -138.210873)
			(xy 174.709379 -138.249769) (xy 174.607644 -138.28115) (xy 174.503849 -138.304841) (xy 174.398573 -138.320708)
			(xy 174.292406 -138.328664) (xy 174.185942 -138.328664) (xy 174.079775 -138.320708) (xy 173.974499 -138.304841)
			(xy 173.870704 -138.28115) (xy 173.768969 -138.249769) (xy 173.669864 -138.210873) (xy 173.573942 -138.16468)
			(xy 173.481741 -138.111447) (xy 173.393776 -138.051474) (xy 173.310539 -137.985094) (xy 173.232494 -137.91268)
			(xy 173.16008 -137.834635) (xy 173.0937 -137.751398) (xy 173.033727 -137.663433) (xy 172.980494 -137.571232)
			(xy 172.934301 -137.47531) (xy 172.895405 -137.376205) (xy 172.864024 -137.27447) (xy 172.840333 -137.170675)
			(xy 172.824466 -137.065399) (xy 172.81651 -136.959232) (xy 163.469838 -136.959232) (xy 163.461882 -137.065399)
			(xy 163.446015 -137.170675) (xy 163.422324 -137.27447) (xy 163.390943 -137.376205) (xy 163.352047 -137.47531)
			(xy 163.305854 -137.571232) (xy 163.252621 -137.663433) (xy 163.192648 -137.751398) (xy 163.126268 -137.834635)
			(xy 163.053854 -137.91268) (xy 162.975809 -137.985094) (xy 162.892572 -138.051474) (xy 162.804607 -138.111447)
			(xy 162.712406 -138.16468) (xy 162.616484 -138.210873) (xy 162.517379 -138.249769) (xy 162.415644 -138.28115)
			(xy 162.311849 -138.304841) (xy 162.206573 -138.320708) (xy 162.100406 -138.328664) (xy 161.993942 -138.328664)
			(xy 161.887775 -138.320708) (xy 161.782499 -138.304841) (xy 161.678704 -138.28115) (xy 161.576969 -138.249769)
			(xy 161.477864 -138.210873) (xy 161.381942 -138.16468) (xy 161.289741 -138.111447) (xy 161.201776 -138.051474)
			(xy 161.118539 -137.985094) (xy 161.040494 -137.91268) (xy 160.96808 -137.834635) (xy 160.9017 -137.751398)
			(xy 160.841727 -137.663433) (xy 160.788494 -137.571232) (xy 160.742301 -137.47531) (xy 160.703405 -137.376205)
			(xy 160.672024 -137.27447) (xy 160.648333 -137.170675) (xy 160.632466 -137.065399) (xy 160.62451 -136.959232)
			(xy 147.853664 -136.959232) (xy 147.845708 -137.065399) (xy 147.829841 -137.170675) (xy 147.80615 -137.27447)
			(xy 147.774769 -137.376205) (xy 147.735873 -137.47531) (xy 147.68968 -137.571232) (xy 147.636447 -137.663433)
			(xy 147.576474 -137.751398) (xy 147.510094 -137.834635) (xy 147.43768 -137.91268) (xy 147.359635 -137.985094)
			(xy 147.276398 -138.051474) (xy 147.188433 -138.111447) (xy 147.096232 -138.16468) (xy 147.00031 -138.210873)
			(xy 146.901205 -138.249769) (xy 146.79947 -138.28115) (xy 146.695675 -138.304841) (xy 146.590399 -138.320708)
			(xy 146.484232 -138.328664) (xy 146.377768 -138.328664) (xy 146.271601 -138.320708) (xy 146.166325 -138.304841)
			(xy 146.06253 -138.28115) (xy 145.960795 -138.249769) (xy 145.86169 -138.210873) (xy 145.765768 -138.16468)
			(xy 145.673567 -138.111447) (xy 145.585602 -138.051474) (xy 145.502365 -137.985094) (xy 145.42432 -137.91268)
			(xy 145.351906 -137.834635) (xy 145.285526 -137.751398) (xy 145.225553 -137.663433) (xy 145.17232 -137.571232)
			(xy 145.126127 -137.47531) (xy 145.087231 -137.376205) (xy 145.05585 -137.27447) (xy 145.032159 -137.170675)
			(xy 145.016292 -137.065399) (xy 145.008336 -136.959232) (xy 135.661664 -136.959232) (xy 135.653708 -137.065399)
			(xy 135.637841 -137.170675) (xy 135.61415 -137.27447) (xy 135.582769 -137.376205) (xy 135.543873 -137.47531)
			(xy 135.49768 -137.571232) (xy 135.444447 -137.663433) (xy 135.384474 -137.751398) (xy 135.318094 -137.834635)
			(xy 135.24568 -137.91268) (xy 135.167635 -137.985094) (xy 135.084398 -138.051474) (xy 134.996433 -138.111447)
			(xy 134.904232 -138.16468) (xy 134.80831 -138.210873) (xy 134.709205 -138.249769) (xy 134.60747 -138.28115)
			(xy 134.503675 -138.304841) (xy 134.398399 -138.320708) (xy 134.292232 -138.328664) (xy 134.185768 -138.328664)
			(xy 134.079601 -138.320708) (xy 133.974325 -138.304841) (xy 133.87053 -138.28115) (xy 133.768795 -138.249769)
			(xy 133.66969 -138.210873) (xy 133.573768 -138.16468) (xy 133.481567 -138.111447) (xy 133.393602 -138.051474)
			(xy 133.310365 -137.985094) (xy 133.23232 -137.91268) (xy 133.159906 -137.834635) (xy 133.093526 -137.751398)
			(xy 133.033553 -137.663433) (xy 132.98032 -137.571232) (xy 132.934127 -137.47531) (xy 132.895231 -137.376205)
			(xy 132.86385 -137.27447) (xy 132.840159 -137.170675) (xy 132.824292 -137.065399) (xy 132.816336 -136.959232)
			(xy 123.469664 -136.959232) (xy 123.461708 -137.065399) (xy 123.445841 -137.170675) (xy 123.42215 -137.27447)
			(xy 123.390769 -137.376205) (xy 123.351873 -137.47531) (xy 123.30568 -137.571232) (xy 123.252447 -137.663433)
			(xy 123.192474 -137.751398) (xy 123.126094 -137.834635) (xy 123.05368 -137.91268) (xy 122.975635 -137.985094)
			(xy 122.892398 -138.051474) (xy 122.804433 -138.111447) (xy 122.712232 -138.16468) (xy 122.61631 -138.210873)
			(xy 122.517205 -138.249769) (xy 122.41547 -138.28115) (xy 122.311675 -138.304841) (xy 122.206399 -138.320708)
			(xy 122.100232 -138.328664) (xy 121.993768 -138.328664) (xy 121.887601 -138.320708) (xy 121.782325 -138.304841)
			(xy 121.67853 -138.28115) (xy 121.576795 -138.249769) (xy 121.47769 -138.210873) (xy 121.381768 -138.16468)
			(xy 121.289567 -138.111447) (xy 121.201602 -138.051474) (xy 121.118365 -137.985094) (xy 121.04032 -137.91268)
			(xy 120.967906 -137.834635) (xy 120.901526 -137.751398) (xy 120.841553 -137.663433) (xy 120.78832 -137.571232)
			(xy 120.742127 -137.47531) (xy 120.703231 -137.376205) (xy 120.67185 -137.27447) (xy 120.648159 -137.170675)
			(xy 120.632292 -137.065399) (xy 120.624336 -136.959232) (xy 107.85349 -136.959232) (xy 107.845534 -137.065399)
			(xy 107.829667 -137.170675) (xy 107.805976 -137.27447) (xy 107.774595 -137.376205) (xy 107.735699 -137.47531)
			(xy 107.689506 -137.571232) (xy 107.636273 -137.663433) (xy 107.5763 -137.751398) (xy 107.50992 -137.834635)
			(xy 107.437506 -137.91268) (xy 107.359461 -137.985094) (xy 107.276224 -138.051474) (xy 107.188259 -138.111447)
			(xy 107.096058 -138.16468) (xy 107.000136 -138.210873) (xy 106.901031 -138.249769) (xy 106.799296 -138.28115)
			(xy 106.695501 -138.304841) (xy 106.590225 -138.320708) (xy 106.484058 -138.328664) (xy 106.377594 -138.328664)
			(xy 106.271427 -138.320708) (xy 106.166151 -138.304841) (xy 106.062356 -138.28115) (xy 105.960621 -138.249769)
			(xy 105.861516 -138.210873) (xy 105.765594 -138.16468) (xy 105.673393 -138.111447) (xy 105.585428 -138.051474)
			(xy 105.502191 -137.985094) (xy 105.424146 -137.91268) (xy 105.351732 -137.834635) (xy 105.285352 -137.751398)
			(xy 105.225379 -137.663433) (xy 105.172146 -137.571232) (xy 105.125953 -137.47531) (xy 105.087057 -137.376205)
			(xy 105.055676 -137.27447) (xy 105.031985 -137.170675) (xy 105.016118 -137.065399) (xy 105.008162 -136.959232)
			(xy 95.66149 -136.959232) (xy 95.653534 -137.065399) (xy 95.637667 -137.170675) (xy 95.613976 -137.27447)
			(xy 95.582595 -137.376205) (xy 95.543699 -137.47531) (xy 95.497506 -137.571232) (xy 95.444273 -137.663433)
			(xy 95.3843 -137.751398) (xy 95.31792 -137.834635) (xy 95.245506 -137.91268) (xy 95.167461 -137.985094)
			(xy 95.084224 -138.051474) (xy 94.996259 -138.111447) (xy 94.904058 -138.16468) (xy 94.808136 -138.210873)
			(xy 94.709031 -138.249769) (xy 94.607296 -138.28115) (xy 94.503501 -138.304841) (xy 94.398225 -138.320708)
			(xy 94.292058 -138.328664) (xy 94.185594 -138.328664) (xy 94.079427 -138.320708) (xy 93.974151 -138.304841)
			(xy 93.870356 -138.28115) (xy 93.768621 -138.249769) (xy 93.669516 -138.210873) (xy 93.573594 -138.16468)
			(xy 93.481393 -138.111447) (xy 93.393428 -138.051474) (xy 93.310191 -137.985094) (xy 93.232146 -137.91268)
			(xy 93.159732 -137.834635) (xy 93.093352 -137.751398) (xy 93.033379 -137.663433) (xy 92.980146 -137.571232)
			(xy 92.933953 -137.47531) (xy 92.895057 -137.376205) (xy 92.863676 -137.27447) (xy 92.839985 -137.170675)
			(xy 92.824118 -137.065399) (xy 92.816162 -136.959232) (xy 83.46949 -136.959232) (xy 83.461534 -137.065399)
			(xy 83.445667 -137.170675) (xy 83.421976 -137.27447) (xy 83.390595 -137.376205) (xy 83.351699 -137.47531)
			(xy 83.305506 -137.571232) (xy 83.252273 -137.663433) (xy 83.1923 -137.751398) (xy 83.12592 -137.834635)
			(xy 83.053506 -137.91268) (xy 82.975461 -137.985094) (xy 82.892224 -138.051474) (xy 82.804259 -138.111447)
			(xy 82.712058 -138.16468) (xy 82.616136 -138.210873) (xy 82.517031 -138.249769) (xy 82.415296 -138.28115)
			(xy 82.311501 -138.304841) (xy 82.206225 -138.320708) (xy 82.100058 -138.328664) (xy 81.993594 -138.328664)
			(xy 81.887427 -138.320708) (xy 81.782151 -138.304841) (xy 81.678356 -138.28115) (xy 81.576621 -138.249769)
			(xy 81.477516 -138.210873) (xy 81.381594 -138.16468) (xy 81.289393 -138.111447) (xy 81.201428 -138.051474)
			(xy 81.118191 -137.985094) (xy 81.040146 -137.91268) (xy 80.967732 -137.834635) (xy 80.901352 -137.751398)
			(xy 80.841379 -137.663433) (xy 80.788146 -137.571232) (xy 80.741953 -137.47531) (xy 80.703057 -137.376205)
			(xy 80.671676 -137.27447) (xy 80.647985 -137.170675) (xy 80.632118 -137.065399) (xy 80.624162 -136.959232)
			(xy 67.85357 -136.959232) (xy 67.845614 -137.065399) (xy 67.829747 -137.170675) (xy 67.806056 -137.27447)
			(xy 67.774675 -137.376205) (xy 67.735779 -137.47531) (xy 67.689586 -137.571232) (xy 67.636353 -137.663433)
			(xy 67.57638 -137.751398) (xy 67.51 -137.834635) (xy 67.437586 -137.91268) (xy 67.359541 -137.985094)
			(xy 67.276304 -138.051474) (xy 67.188339 -138.111447) (xy 67.096138 -138.16468) (xy 67.000216 -138.210873)
			(xy 66.901111 -138.249769) (xy 66.799376 -138.28115) (xy 66.695581 -138.304841) (xy 66.590305 -138.320708)
			(xy 66.484138 -138.328664) (xy 66.377674 -138.328664) (xy 66.271507 -138.320708) (xy 66.166231 -138.304841)
			(xy 66.062436 -138.28115) (xy 65.960701 -138.249769) (xy 65.861596 -138.210873) (xy 65.765674 -138.16468)
			(xy 65.673473 -138.111447) (xy 65.585508 -138.051474) (xy 65.502271 -137.985094) (xy 65.424226 -137.91268)
			(xy 65.351812 -137.834635) (xy 65.285432 -137.751398) (xy 65.225459 -137.663433) (xy 65.172226 -137.571232)
			(xy 65.126033 -137.47531) (xy 65.087137 -137.376205) (xy 65.055756 -137.27447) (xy 65.032065 -137.170675)
			(xy 65.016198 -137.065399) (xy 65.008242 -136.959232) (xy 55.66157 -136.959232) (xy 55.653614 -137.065399)
			(xy 55.637747 -137.170675) (xy 55.614056 -137.27447) (xy 55.582675 -137.376205) (xy 55.543779 -137.47531)
			(xy 55.497586 -137.571232) (xy 55.444353 -137.663433) (xy 55.38438 -137.751398) (xy 55.318 -137.834635)
			(xy 55.245586 -137.91268) (xy 55.167541 -137.985094) (xy 55.084304 -138.051474) (xy 54.996339 -138.111447)
			(xy 54.904138 -138.16468) (xy 54.808216 -138.210873) (xy 54.709111 -138.249769) (xy 54.607376 -138.28115)
			(xy 54.503581 -138.304841) (xy 54.398305 -138.320708) (xy 54.292138 -138.328664) (xy 54.185674 -138.328664)
			(xy 54.079507 -138.320708) (xy 53.974231 -138.304841) (xy 53.870436 -138.28115) (xy 53.768701 -138.249769)
			(xy 53.669596 -138.210873) (xy 53.573674 -138.16468) (xy 53.481473 -138.111447) (xy 53.393508 -138.051474)
			(xy 53.310271 -137.985094) (xy 53.232226 -137.91268) (xy 53.159812 -137.834635) (xy 53.093432 -137.751398)
			(xy 53.033459 -137.663433) (xy 52.980226 -137.571232) (xy 52.934033 -137.47531) (xy 52.895137 -137.376205)
			(xy 52.863756 -137.27447) (xy 52.840065 -137.170675) (xy 52.824198 -137.065399) (xy 52.816242 -136.959232)
			(xy 43.46957 -136.959232) (xy 43.461614 -137.065399) (xy 43.445747 -137.170675) (xy 43.422056 -137.27447)
			(xy 43.390675 -137.376205) (xy 43.351779 -137.47531) (xy 43.305586 -137.571232) (xy 43.252353 -137.663433)
			(xy 43.19238 -137.751398) (xy 43.126 -137.834635) (xy 43.053586 -137.91268) (xy 42.975541 -137.985094)
			(xy 42.892304 -138.051474) (xy 42.804339 -138.111447) (xy 42.712138 -138.16468) (xy 42.616216 -138.210873)
			(xy 42.517111 -138.249769) (xy 42.415376 -138.28115) (xy 42.311581 -138.304841) (xy 42.206305 -138.320708)
			(xy 42.100138 -138.328664) (xy 41.993674 -138.328664) (xy 41.887507 -138.320708) (xy 41.782231 -138.304841)
			(xy 41.678436 -138.28115) (xy 41.576701 -138.249769) (xy 41.477596 -138.210873) (xy 41.381674 -138.16468)
			(xy 41.289473 -138.111447) (xy 41.201508 -138.051474) (xy 41.118271 -137.985094) (xy 41.040226 -137.91268)
			(xy 40.967812 -137.834635) (xy 40.901432 -137.751398) (xy 40.841459 -137.663433) (xy 40.788226 -137.571232)
			(xy 40.742033 -137.47531) (xy 40.703137 -137.376205) (xy 40.671756 -137.27447) (xy 40.648065 -137.170675)
			(xy 40.632198 -137.065399) (xy 40.624242 -136.959232) (xy 0.509016 -136.959232) (xy 0.509016 -141.95405)
			(xy 220.791775 -141.95405) (xy 220.791775 -141.82491) (xy 220.799725 -141.696015) (xy 220.815595 -141.567855)
			(xy 220.839324 -141.440914) (xy 220.870823 -141.315675) (xy 220.909972 -141.192612) (xy 220.956623 -141.072193)
			(xy 221.010598 -140.954874) (xy 221.071693 -140.8411) (xy 221.139676 -140.731303) (xy 221.21429 -140.6259)
			(xy 221.295251 -140.52529) (xy 221.382251 -140.429855) (xy 221.474962 -140.339956) (xy 221.573032 -140.255935)
			(xy 221.676087 -140.178111) (xy 221.783738 -140.106779) (xy 221.895577 -140.042209) (xy 222.011178 -139.984647)
			(xy 222.130103 -139.93431) (xy 222.251902 -139.89139) (xy 222.376112 -139.856049) (xy 222.502261 -139.828422)
			(xy 222.629873 -139.808613) (xy 222.758462 -139.796697) (xy 222.88754 -139.792721) (xy 223.016618 -139.796697)
			(xy 223.145207 -139.808613) (xy 223.272819 -139.828422) (xy 223.398968 -139.856049) (xy 223.523178 -139.89139)
			(xy 223.644977 -139.93431) (xy 223.763902 -139.984647) (xy 223.879503 -140.042209) (xy 223.991342 -140.106779)
			(xy 224.098993 -140.178111) (xy 224.202048 -140.255935) (xy 224.300118 -140.339956) (xy 224.392829 -140.429855)
			(xy 224.422133 -140.462) (xy 270.001492 -140.462) (xy 270.002075 -140.415604) (xy 270.01172 -140.323316)
			(xy 270.030916 -140.232532) (xy 270.059454 -140.144239) (xy 270.077692 -140.101574) (xy 270.081498 -140.091632)
			(xy 270.081498 -140.070368) (xy 270.077692 -140.060426) (xy 270.059447 -140.017764) (xy 270.030903 -139.929471)
			(xy 270.01171 -139.838686) (xy 270.002077 -139.746396) (xy 270.001492 -139.7) (xy 270.002075 -139.653604)
			(xy 270.01172 -139.561316) (xy 270.030916 -139.470532) (xy 270.059454 -139.382239) (xy 270.077692 -139.339574)
			(xy 270.081498 -139.329632) (xy 270.081498 -139.308368) (xy 270.077692 -139.298426) (xy 270.059447 -139.255764)
			(xy 270.030903 -139.167471) (xy 270.01171 -139.076686) (xy 270.002077 -138.984396) (xy 270.001492 -138.938)
			(xy 270.002075 -138.891604) (xy 270.01172 -138.799316) (xy 270.030916 -138.708532) (xy 270.059454 -138.620239)
			(xy 270.077692 -138.577574) (xy 270.081498 -138.567632) (xy 270.081498 -138.546368) (xy 270.077692 -138.536426)
			(xy 270.059447 -138.493764) (xy 270.030903 -138.405471) (xy 270.01171 -138.314686) (xy 270.002077 -138.222396)
			(xy 270.001492 -138.176) (xy 270.002075 -138.129604) (xy 270.01172 -138.037316) (xy 270.030916 -137.946532)
			(xy 270.059454 -137.858239) (xy 270.077692 -137.815574) (xy 270.081498 -137.805632) (xy 270.081498 -137.784368)
			(xy 270.077692 -137.774426) (xy 270.059447 -137.731764) (xy 270.030903 -137.643471) (xy 270.01171 -137.552686)
			(xy 270.002077 -137.460396) (xy 270.001492 -137.414) (xy 270.002075 -137.367604) (xy 270.01172 -137.275316)
			(xy 270.030916 -137.184532) (xy 270.059454 -137.096239) (xy 270.077692 -137.053574) (xy 270.081498 -137.043632)
			(xy 270.081498 -137.022368) (xy 270.077692 -137.012426) (xy 270.059447 -136.969764) (xy 270.030903 -136.881471)
			(xy 270.01171 -136.790686) (xy 270.002077 -136.698396) (xy 270.001492 -136.652) (xy 270.001967 -136.610898)
			(xy 270.009552 -136.529043) (xy 270.024657 -136.448238) (xy 270.047153 -136.369171) (xy 270.076849 -136.292517)
			(xy 270.113491 -136.21893) (xy 270.156766 -136.149038) (xy 270.206306 -136.083437) (xy 270.261687 -136.022687)
			(xy 270.322437 -135.967306) (xy 270.388038 -135.917766) (xy 270.45793 -135.874491) (xy 270.531517 -135.837849)
			(xy 270.608171 -135.808153) (xy 270.687238 -135.785657) (xy 270.768043 -135.770552) (xy 270.849898 -135.762967)
			(xy 270.891 -135.762492) (xy 270.937396 -135.763075) (xy 271.029684 -135.77272) (xy 271.120468 -135.791916)
			(xy 271.208761 -135.820454) (xy 271.251426 -135.838692) (xy 271.261368 -135.842498) (xy 271.282632 -135.842498)
			(xy 271.292574 -135.838692) (xy 271.335236 -135.820447) (xy 271.423529 -135.791903) (xy 271.514314 -135.77271)
			(xy 271.606604 -135.763077) (xy 271.653 -135.762492) (xy 271.694102 -135.762967) (xy 271.775957 -135.770552)
			(xy 271.856762 -135.785657) (xy 271.935829 -135.808153) (xy 272.012483 -135.837849) (xy 272.08607 -135.874491)
			(xy 272.155962 -135.917766) (xy 272.221563 -135.967306) (xy 272.282313 -136.022687) (xy 272.337694 -136.083437)
			(xy 272.387234 -136.149038) (xy 272.430509 -136.21893) (xy 272.467151 -136.292517) (xy 272.496847 -136.369171)
			(xy 272.519343 -136.448238) (xy 272.534448 -136.529043) (xy 272.542033 -136.610898) (xy 272.542508 -136.652)
			(xy 272.541925 -136.698396) (xy 272.53228 -136.790684) (xy 272.513084 -136.881468) (xy 272.484546 -136.969761)
			(xy 272.466308 -137.012426) (xy 272.462502 -137.022368) (xy 272.462502 -137.043632) (xy 272.466308 -137.053574)
			(xy 272.484553 -137.096236) (xy 272.513097 -137.184529) (xy 272.53229 -137.275314) (xy 272.541923 -137.367604)
			(xy 272.542508 -137.414) (xy 272.541925 -137.460396) (xy 272.53228 -137.552684) (xy 272.513084 -137.643468)
			(xy 272.484546 -137.731761) (xy 272.466308 -137.774426) (xy 272.462502 -137.784368) (xy 272.462502 -137.805632)
			(xy 272.466308 -137.815574) (xy 272.484553 -137.858236) (xy 272.513097 -137.946529) (xy 272.53229 -138.037314)
			(xy 272.541923 -138.129604) (xy 272.542508 -138.176) (xy 272.541925 -138.222396) (xy 272.53228 -138.314684)
			(xy 272.513084 -138.405468) (xy 272.484546 -138.493761) (xy 272.466308 -138.536426) (xy 272.462502 -138.546368)
			(xy 272.462502 -138.567632) (xy 272.466308 -138.577574) (xy 272.484553 -138.620236) (xy 272.513097 -138.708529)
			(xy 272.53229 -138.799314) (xy 272.541923 -138.891604) (xy 272.542508 -138.938) (xy 272.541925 -138.984396)
			(xy 272.53228 -139.076684) (xy 272.513084 -139.167468) (xy 272.484546 -139.255761) (xy 272.466308 -139.298426)
			(xy 272.462502 -139.308368) (xy 272.462502 -139.329632) (xy 272.466308 -139.339574) (xy 272.484553 -139.382236)
			(xy 272.513097 -139.470529) (xy 272.53229 -139.561314) (xy 272.541923 -139.653604) (xy 272.542508 -139.7)
			(xy 272.541925 -139.746396) (xy 272.53228 -139.838684) (xy 272.513084 -139.929468) (xy 272.484546 -140.017761)
			(xy 272.466308 -140.060426) (xy 272.462502 -140.070368) (xy 272.462502 -140.091632) (xy 272.466308 -140.101574)
			(xy 272.484553 -140.144236) (xy 272.513097 -140.232529) (xy 272.53229 -140.323314) (xy 272.541923 -140.415604)
			(xy 272.542508 -140.462) (xy 272.542033 -140.503102) (xy 272.534448 -140.584957) (xy 272.519343 -140.665762)
			(xy 272.496847 -140.744829) (xy 272.467151 -140.821483) (xy 272.430509 -140.89507) (xy 272.387234 -140.964962)
			(xy 272.337694 -141.030563) (xy 272.282313 -141.091313) (xy 272.221563 -141.146694) (xy 272.155962 -141.196234)
			(xy 272.08607 -141.239509) (xy 272.012483 -141.276151) (xy 271.935829 -141.305847) (xy 271.856762 -141.328343)
			(xy 271.775957 -141.343448) (xy 271.694102 -141.351033) (xy 271.653 -141.351508) (xy 271.606604 -141.350925)
			(xy 271.514316 -141.34128) (xy 271.423532 -141.322084) (xy 271.335239 -141.293546) (xy 271.292574 -141.275308)
			(xy 271.282632 -141.271502) (xy 271.261368 -141.271502) (xy 271.251426 -141.275308) (xy 271.208764 -141.293553)
			(xy 271.120471 -141.322097) (xy 271.029686 -141.34129) (xy 270.937396 -141.350923) (xy 270.891 -141.351508)
			(xy 270.849898 -141.351033) (xy 270.768043 -141.343448) (xy 270.687238 -141.328343) (xy 270.608171 -141.305847)
			(xy 270.531517 -141.276151) (xy 270.45793 -141.239509) (xy 270.388038 -141.196234) (xy 270.322437 -141.146694)
			(xy 270.261687 -141.091313) (xy 270.206306 -141.030563) (xy 270.156766 -140.964962) (xy 270.113491 -140.89507)
			(xy 270.076849 -140.821483) (xy 270.047153 -140.744829) (xy 270.024657 -140.665762) (xy 270.009552 -140.584957)
			(xy 270.001967 -140.503102) (xy 270.001492 -140.462) (xy 224.422133 -140.462) (xy 224.479829 -140.52529)
			(xy 224.56079 -140.6259) (xy 224.635404 -140.731303) (xy 224.703387 -140.8411) (xy 224.764482 -140.954874)
			(xy 224.818457 -141.072193) (xy 224.865108 -141.192612) (xy 224.904257 -141.315675) (xy 224.935756 -141.440914)
			(xy 224.959485 -141.567855) (xy 224.975355 -141.696015) (xy 224.983305 -141.82491) (xy 224.983802 -141.88948)
			(xy 224.983305 -141.95405) (xy 224.975355 -142.082945) (xy 224.959485 -142.211105) (xy 224.935756 -142.338046)
			(xy 224.904257 -142.463285) (xy 224.865108 -142.586348) (xy 224.818457 -142.706767) (xy 224.764482 -142.824086)
			(xy 224.703387 -142.93786) (xy 224.635404 -143.047657) (xy 224.56079 -143.15306) (xy 224.479829 -143.25367)
			(xy 224.392829 -143.349105) (xy 224.300118 -143.439004) (xy 224.202048 -143.523025) (xy 224.098993 -143.600849)
			(xy 223.991342 -143.672181) (xy 223.879503 -143.736751) (xy 223.763902 -143.794313) (xy 223.644977 -143.84465)
			(xy 223.523178 -143.88757) (xy 223.398968 -143.922911) (xy 223.272819 -143.950538) (xy 223.145207 -143.970347)
			(xy 223.016618 -143.982263) (xy 222.88754 -143.98624) (xy 222.758462 -143.982263) (xy 222.629873 -143.970347)
			(xy 222.502261 -143.950538) (xy 222.376112 -143.922911) (xy 222.251902 -143.88757) (xy 222.130103 -143.84465)
			(xy 222.011178 -143.794313) (xy 221.895577 -143.736751) (xy 221.783738 -143.672181) (xy 221.676087 -143.600849)
			(xy 221.573032 -143.523025) (xy 221.474962 -143.439004) (xy 221.382251 -143.349105) (xy 221.295251 -143.25367)
			(xy 221.21429 -143.15306) (xy 221.139676 -143.047657) (xy 221.071693 -142.93786) (xy 221.010598 -142.824086)
			(xy 220.956623 -142.706767) (xy 220.909972 -142.586348) (xy 220.870823 -142.463285) (xy 220.839324 -142.338046)
			(xy 220.815595 -142.211105) (xy 220.799725 -142.082945) (xy 220.791775 -141.95405) (xy 0.509016 -141.95405)
			(xy 0.509016 -141.99997) (xy 0.509522 -142.095303) (xy 0.517614 -142.285798) (xy 0.533784 -142.475778)
			(xy 0.558002 -142.664901) (xy 0.590225 -142.852825) (xy 0.630394 -143.039212) (xy 0.678438 -143.223727)
			(xy 0.73427 -143.406036) (xy 0.797788 -143.585811) (xy 0.86888 -143.762729) (xy 0.947415 -143.93647)
			(xy 1.033254 -144.106721) (xy 1.126242 -144.273176) (xy 1.22621 -144.435534) (xy 1.332978 -144.593504)
			(xy 1.446355 -144.746799) (xy 1.566136 -144.895145) (xy 1.692104 -145.038273) (xy 1.824034 -145.175926)
			(xy 1.961687 -145.307856) (xy 2.104815 -145.433824) (xy 2.253161 -145.553605) (xy 2.406456 -145.666982)
			(xy 2.564426 -145.77375) (xy 2.726784 -145.873718) (xy 2.893239 -145.966706) (xy 3.06349 -146.052545)
			(xy 3.237231 -146.13108) (xy 3.414149 -146.202172) (xy 3.593924 -146.26569) (xy 3.776233 -146.321522)
			(xy 3.960748 -146.369566) (xy 4.147135 -146.409735) (xy 4.335059 -146.441958) (xy 4.524182 -146.466176)
			(xy 4.714162 -146.482346) (xy 4.904657 -146.490438) (xy 4.99999 -146.490944) (xy 266.33297 -146.490944)
			(xy 266.33297 -146.49196) (xy 266.666472 -146.49196)
		)
		(stroke
			(width 0)
			(type solid)
		)
		(fill yes)
		(layer "In6.Cu")
		(net "GND")
	)
	(gr_circle
		(center 9.85012 -76.019914)
		(end 11.22172 -76.019914)
		(stroke
			(width 0.2)
			(type default)
		)
		(fill no)
		(layer "In6.Cu")
	)
	(gr_circle
		(center 9.85012 -74.319892)
		(end 11.22172 -74.319892)
		(stroke
			(width 0.2)
			(type default)
		)
		(fill no)
		(layer "In6.Cu")
	)
	(gr_circle
		(center 9.85012 -70.939914)
		(end 11.22172 -70.939914)
		(stroke
			(width 0.2)
			(type default)
		)
		(fill no)
		(layer "In6.Cu")
	)
	(gr_circle
		(center 9.85012 -69.239892)
		(end 11.22172 -69.239892)
		(stroke
			(width 0.2)
			(type default)
		)
		(fill no)
		(layer "In6.Cu")
	)
	(gr_circle
		(center 11.135868 -70.02272)
		(end 12.507468 -70.02272)
		(stroke
			(width 0.2)
			(type default)
		)
		(fill no)
		(layer "In6.Cu")
	)
	(gr_circle
		(center 11.205464 -75.188572)
		(end 12.577064 -75.188572)
		(stroke
			(width 0.2)
			(type default)
		)
		(fill no)
		(layer "In6.Cu")
	)
	(gr_circle
		(center 12.39012 -76.019914)
		(end 13.76172 -76.019914)
		(stroke
			(width 0.2)
			(type default)
		)
		(fill no)
		(layer "In6.Cu")
	)
	(gr_circle
		(center 12.39012 -74.319892)
		(end 13.76172 -74.319892)
		(stroke
			(width 0.2)
			(type default)
		)
		(fill no)
		(layer "In6.Cu")
	)
	(gr_circle
		(center 12.39012 -70.939914)
		(end 13.76172 -70.939914)
		(stroke
			(width 0.2)
			(type default)
		)
		(fill no)
		(layer "In6.Cu")
	)
	(gr_circle
		(center 12.39012 -69.239892)
		(end 13.76172 -69.239892)
		(stroke
			(width 0.2)
			(type default)
		)
		(fill no)
		(layer "In6.Cu")
	)
	(gr_circle
		(center 27.5844 -66.43624)
		(end 28.4734 -66.43624)
		(stroke
			(width 0.2)
			(type default)
		)
		(fill no)
		(layer "In6.Cu")
	)
	(gr_circle
		(center 27.5844 -65.67424)
		(end 28.4734 -65.67424)
		(stroke
			(width 0.2)
			(type default)
		)
		(fill no)
		(layer "In6.Cu")
	)
	(gr_circle
		(center 27.5844 -64.91224)
		(end 28.4734 -64.91224)
		(stroke
			(width 0.2)
			(type default)
		)
		(fill no)
		(layer "In6.Cu")
	)
	(gr_circle
		(center 28.3464 -66.43624)
		(end 29.2354 -66.43624)
		(stroke
			(width 0.2)
			(type default)
		)
		(fill no)
		(layer "In6.Cu")
	)
	(gr_circle
		(center 28.3464 -65.67424)
		(end 29.2354 -65.67424)
		(stroke
			(width 0.2)
			(type default)
		)
		(fill no)
		(layer "In6.Cu")
	)
	(gr_circle
		(center 28.3464 -64.91224)
		(end 29.2354 -64.91224)
		(stroke
			(width 0.2)
			(type default)
		)
		(fill no)
		(layer "In6.Cu")
	)
	(gr_circle
		(center 29.3878 -108.3818)
		(end 30.2768 -108.3818)
		(stroke
			(width 0.2)
			(type default)
		)
		(fill no)
		(layer "In6.Cu")
	)
	(gr_circle
		(center 29.3878 -107.6198)
		(end 30.2768 -107.6198)
		(stroke
			(width 0.2)
			(type default)
		)
		(fill no)
		(layer "In6.Cu")
	)
	(gr_circle
		(center 29.3878 -106.8324)
		(end 30.2768 -106.8324)
		(stroke
			(width 0.2)
			(type default)
		)
		(fill no)
		(layer "In6.Cu")
	)
	(gr_circle
		(center 29.3878 -106.0704)
		(end 30.2768 -106.0704)
		(stroke
			(width 0.2)
			(type default)
		)
		(fill no)
		(layer "In6.Cu")
	)
	(gr_circle
		(center 29.3878 -105.3084)
		(end 30.2768 -105.3084)
		(stroke
			(width 0.2)
			(type default)
		)
		(fill no)
		(layer "In6.Cu")
	)
	(gr_circle
		(center 29.3878 -104.5464)
		(end 30.2768 -104.5464)
		(stroke
			(width 0.2)
			(type default)
		)
		(fill no)
		(layer "In6.Cu")
	)
	(gr_circle
		(center 29.3878 -103.7844)
		(end 30.2768 -103.7844)
		(stroke
			(width 0.2)
			(type default)
		)
		(fill no)
		(layer "In6.Cu")
	)
	(gr_circle
		(center 30.353 -108.3564)
		(end 31.242 -108.3564)
		(stroke
			(width 0.2)
			(type default)
		)
		(fill no)
		(layer "In6.Cu")
	)
	(gr_circle
		(center 30.353 -107.5944)
		(end 31.242 -107.5944)
		(stroke
			(width 0.2)
			(type default)
		)
		(fill no)
		(layer "In6.Cu")
	)
	(gr_circle
		(center 30.353 -106.807)
		(end 31.242 -106.807)
		(stroke
			(width 0.2)
			(type default)
		)
		(fill no)
		(layer "In6.Cu")
	)
	(gr_circle
		(center 30.353 -106.045)
		(end 31.242 -106.045)
		(stroke
			(width 0.2)
			(type default)
		)
		(fill no)
		(layer "In6.Cu")
	)
	(gr_circle
		(center 30.353 -105.283)
		(end 31.242 -105.283)
		(stroke
			(width 0.2)
			(type default)
		)
		(fill no)
		(layer "In6.Cu")
	)
	(gr_circle
		(center 30.353 -104.521)
		(end 31.242 -104.521)
		(stroke
			(width 0.2)
			(type default)
		)
		(fill no)
		(layer "In6.Cu")
	)
	(gr_circle
		(center 30.353 -103.759)
		(end 31.242 -103.759)
		(stroke
			(width 0.2)
			(type default)
		)
		(fill no)
		(layer "In6.Cu")
	)
	(gr_circle
		(center 31.242 -108.3564)
		(end 32.131 -108.3564)
		(stroke
			(width 0.2)
			(type default)
		)
		(fill no)
		(layer "In6.Cu")
	)
	(gr_circle
		(center 31.242 -107.5944)
		(end 32.131 -107.5944)
		(stroke
			(width 0.2)
			(type default)
		)
		(fill no)
		(layer "In6.Cu")
	)
	(gr_circle
		(center 31.242 -106.807)
		(end 32.131 -106.807)
		(stroke
			(width 0.2)
			(type default)
		)
		(fill no)
		(layer "In6.Cu")
	)
	(gr_circle
		(center 31.242 -106.045)
		(end 32.131 -106.045)
		(stroke
			(width 0.2)
			(type default)
		)
		(fill no)
		(layer "In6.Cu")
	)
	(gr_circle
		(center 31.242 -105.283)
		(end 32.131 -105.283)
		(stroke
			(width 0.2)
			(type default)
		)
		(fill no)
		(layer "In6.Cu")
	)
	(gr_circle
		(center 31.242 -104.521)
		(end 32.131 -104.521)
		(stroke
			(width 0.2)
			(type default)
		)
		(fill no)
		(layer "In6.Cu")
	)
	(gr_circle
		(center 31.242 -103.759)
		(end 32.131 -103.759)
		(stroke
			(width 0.2)
			(type default)
		)
		(fill no)
		(layer "In6.Cu")
	)
	(gr_circle
		(center 38.261036 -55.642002)
		(end 39.150036 -55.642002)
		(stroke
			(width 0.2)
			(type default)
		)
		(fill no)
		(layer "In6.Cu")
	)
	(gr_circle
		(center 38.692836 -58.436002)
		(end 39.581836 -58.436002)
		(stroke
			(width 0.2)
			(type default)
		)
		(fill no)
		(layer "In6.Cu")
	)
	(gr_circle
		(center 38.692836 -57.547002)
		(end 39.581836 -57.547002)
		(stroke
			(width 0.2)
			(type default)
		)
		(fill no)
		(layer "In6.Cu")
	)
	(gr_circle
		(center 38.692836 -56.658002)
		(end 39.581836 -56.658002)
		(stroke
			(width 0.2)
			(type default)
		)
		(fill no)
		(layer "In6.Cu")
	)
	(gr_circle
		(center 39.378636 -58.817002)
		(end 40.267636 -58.817002)
		(stroke
			(width 0.2)
			(type default)
		)
		(fill no)
		(layer "In6.Cu")
	)
	(gr_circle
		(center 39.378636 -57.928002)
		(end 40.267636 -57.928002)
		(stroke
			(width 0.2)
			(type default)
		)
		(fill no)
		(layer "In6.Cu")
	)
	(gr_circle
		(center 39.378636 -57.039002)
		(end 40.267636 -57.039002)
		(stroke
			(width 0.2)
			(type default)
		)
		(fill no)
		(layer "In6.Cu")
	)
	(gr_circle
		(center 39.8272 -108.3564)
		(end 40.7162 -108.3564)
		(stroke
			(width 0.2)
			(type default)
		)
		(fill no)
		(layer "In6.Cu")
	)
	(gr_circle
		(center 39.8272 -107.5944)
		(end 40.7162 -107.5944)
		(stroke
			(width 0.2)
			(type default)
		)
		(fill no)
		(layer "In6.Cu")
	)
	(gr_circle
		(center 39.878 -106.807)
		(end 40.767 -106.807)
		(stroke
			(width 0.2)
			(type default)
		)
		(fill no)
		(layer "In6.Cu")
	)
	(gr_circle
		(center 39.878 -106.045)
		(end 40.767 -106.045)
		(stroke
			(width 0.2)
			(type default)
		)
		(fill no)
		(layer "In6.Cu")
	)
	(gr_circle
		(center 39.878 -105.283)
		(end 40.767 -105.283)
		(stroke
			(width 0.2)
			(type default)
		)
		(fill no)
		(layer "In6.Cu")
	)
	(gr_circle
		(center 39.878 -104.521)
		(end 40.767 -104.521)
		(stroke
			(width 0.2)
			(type default)
		)
		(fill no)
		(layer "In6.Cu")
	)
	(gr_circle
		(center 39.878 -103.759)
		(end 40.767 -103.759)
		(stroke
			(width 0.2)
			(type default)
		)
		(fill no)
		(layer "In6.Cu")
	)
	(gr_circle
		(center 40.7162 -108.3564)
		(end 41.6052 -108.3564)
		(stroke
			(width 0.2)
			(type default)
		)
		(fill no)
		(layer "In6.Cu")
	)
	(gr_circle
		(center 40.7162 -107.5944)
		(end 41.6052 -107.5944)
		(stroke
			(width 0.2)
			(type default)
		)
		(fill no)
		(layer "In6.Cu")
	)
	(gr_circle
		(center 40.767 -106.807)
		(end 41.656 -106.807)
		(stroke
			(width 0.2)
			(type default)
		)
		(fill no)
		(layer "In6.Cu")
	)
	(gr_circle
		(center 40.767 -106.045)
		(end 41.656 -106.045)
		(stroke
			(width 0.2)
			(type default)
		)
		(fill no)
		(layer "In6.Cu")
	)
	(gr_circle
		(center 40.767 -105.283)
		(end 41.656 -105.283)
		(stroke
			(width 0.2)
			(type default)
		)
		(fill no)
		(layer "In6.Cu")
	)
	(gr_circle
		(center 40.767 -104.521)
		(end 41.656 -104.521)
		(stroke
			(width 0.2)
			(type default)
		)
		(fill no)
		(layer "In6.Cu")
	)
	(gr_circle
		(center 40.767 -103.759)
		(end 41.656 -103.759)
		(stroke
			(width 0.2)
			(type default)
		)
		(fill no)
		(layer "In6.Cu")
	)
	(gr_circle
		(center 41.3639 -58.604912)
		(end 42.2529 -58.604912)
		(stroke
			(width 0.2)
			(type default)
		)
		(fill no)
		(layer "In6.Cu")
	)
	(gr_circle
		(center 41.3639 -57.70499)
		(end 42.2529 -57.70499)
		(stroke
			(width 0.2)
			(type default)
		)
		(fill no)
		(layer "In6.Cu")
	)
	(gr_circle
		(center 41.3639 -56.805068)
		(end 42.2529 -56.805068)
		(stroke
			(width 0.2)
			(type default)
		)
		(fill no)
		(layer "In6.Cu")
	)
	(gr_circle
		(center 41.3639 -55.904892)
		(end 42.2529 -55.904892)
		(stroke
			(width 0.2)
			(type default)
		)
		(fill no)
		(layer "In6.Cu")
	)
	(gr_circle
		(center 41.6052 -108.3818)
		(end 42.4942 -108.3818)
		(stroke
			(width 0.2)
			(type default)
		)
		(fill no)
		(layer "In6.Cu")
	)
	(gr_circle
		(center 41.6052 -107.6198)
		(end 42.4942 -107.6198)
		(stroke
			(width 0.2)
			(type default)
		)
		(fill no)
		(layer "In6.Cu")
	)
	(gr_circle
		(center 41.656 -106.8324)
		(end 42.545 -106.8324)
		(stroke
			(width 0.2)
			(type default)
		)
		(fill no)
		(layer "In6.Cu")
	)
	(gr_circle
		(center 41.656 -106.0704)
		(end 42.545 -106.0704)
		(stroke
			(width 0.2)
			(type default)
		)
		(fill no)
		(layer "In6.Cu")
	)
	(gr_circle
		(center 41.656 -105.3084)
		(end 42.545 -105.3084)
		(stroke
			(width 0.2)
			(type default)
		)
		(fill no)
		(layer "In6.Cu")
	)
	(gr_circle
		(center 41.656 -104.5464)
		(end 42.545 -104.5464)
		(stroke
			(width 0.2)
			(type default)
		)
		(fill no)
		(layer "In6.Cu")
	)
	(gr_circle
		(center 41.656 -103.7844)
		(end 42.545 -103.7844)
		(stroke
			(width 0.2)
			(type default)
		)
		(fill no)
		(layer "In6.Cu")
	)
	(gr_circle
		(center 41.84904 -54.1147)
		(end 42.73804 -54.1147)
		(stroke
			(width 0.2)
			(type default)
		)
		(fill no)
		(layer "In6.Cu")
	)
	(gr_circle
		(center 41.84904 -53.3019)
		(end 42.73804 -53.3019)
		(stroke
			(width 0.2)
			(type default)
		)
		(fill no)
		(layer "In6.Cu")
	)
	(gr_circle
		(center 41.9989 -58.604912)
		(end 42.8879 -58.604912)
		(stroke
			(width 0.2)
			(type default)
		)
		(fill no)
		(layer "In6.Cu")
	)
	(gr_circle
		(center 41.9989 -57.70499)
		(end 42.8879 -57.70499)
		(stroke
			(width 0.2)
			(type default)
		)
		(fill no)
		(layer "In6.Cu")
	)
	(gr_circle
		(center 41.9989 -56.805068)
		(end 42.8879 -56.805068)
		(stroke
			(width 0.2)
			(type default)
		)
		(fill no)
		(layer "In6.Cu")
	)
	(gr_circle
		(center 41.9989 -55.904892)
		(end 42.8879 -55.904892)
		(stroke
			(width 0.2)
			(type default)
		)
		(fill no)
		(layer "In6.Cu")
	)
	(gr_circle
		(center 42.046906 -136.906)
		(end 43.469306 -136.906)
		(stroke
			(width 0.2)
			(type default)
		)
		(fill no)
		(layer "In6.Cu")
	)
	(gr_circle
		(center 42.58564 -54.1147)
		(end 43.47464 -54.1147)
		(stroke
			(width 0.2)
			(type default)
		)
		(fill no)
		(layer "In6.Cu")
	)
	(gr_circle
		(center 42.58564 -53.3019)
		(end 43.47464 -53.3019)
		(stroke
			(width 0.2)
			(type default)
		)
		(fill no)
		(layer "In6.Cu")
	)
	(gr_circle
		(center 42.910506 -131.572)
		(end 43.799506 -131.572)
		(stroke
			(width 0.2)
			(type default)
		)
		(fill no)
		(layer "In6.Cu")
	)
	(gr_circle
		(center 42.910506 -126.492)
		(end 43.799506 -126.492)
		(stroke
			(width 0.2)
			(type default)
		)
		(fill no)
		(layer "In6.Cu")
	)
	(gr_circle
		(center 43.672506 -131.572)
		(end 44.561506 -131.572)
		(stroke
			(width 0.2)
			(type default)
		)
		(fill no)
		(layer "In6.Cu")
	)
	(gr_circle
		(center 43.672506 -126.492)
		(end 44.561506 -126.492)
		(stroke
			(width 0.2)
			(type default)
		)
		(fill no)
		(layer "In6.Cu")
	)
	(gr_circle
		(center 44.36364 -52.2859)
		(end 45.25264 -52.2859)
		(stroke
			(width 0.2)
			(type default)
		)
		(fill no)
		(layer "In6.Cu")
	)
	(gr_circle
		(center 44.36364 -51.4731)
		(end 45.25264 -51.4731)
		(stroke
			(width 0.2)
			(type default)
		)
		(fill no)
		(layer "In6.Cu")
	)
	(gr_circle
		(center 44.84624 -50.0507)
		(end 45.73524 -50.0507)
		(stroke
			(width 0.2)
			(type default)
		)
		(fill no)
		(layer "In6.Cu")
	)
	(gr_circle
		(center 45.58284 -50.0507)
		(end 46.47184 -50.0507)
		(stroke
			(width 0.2)
			(type default)
		)
		(fill no)
		(layer "In6.Cu")
	)
	(gr_circle
		(center 46.29404 -50.0507)
		(end 47.18304 -50.0507)
		(stroke
			(width 0.2)
			(type default)
		)
		(fill no)
		(layer "In6.Cu")
	)
	(gr_circle
		(center 47.05604 -52.9209)
		(end 47.94504 -52.9209)
		(stroke
			(width 0.2)
			(type default)
		)
		(fill no)
		(layer "In6.Cu")
	)
	(gr_circle
		(center 47.05604 -52.1589)
		(end 47.94504 -52.1589)
		(stroke
			(width 0.2)
			(type default)
		)
		(fill no)
		(layer "In6.Cu")
	)
	(gr_circle
		(center 49.31664 -52.8828)
		(end 50.20564 -52.8828)
		(stroke
			(width 0.2)
			(type default)
		)
		(fill no)
		(layer "In6.Cu")
	)
	(gr_circle
		(center 49.31664 -52.1208)
		(end 50.20564 -52.1208)
		(stroke
			(width 0.2)
			(type default)
		)
		(fill no)
		(layer "In6.Cu")
	)
	(gr_circle
		(center 50.07864 -52.8828)
		(end 50.96764 -52.8828)
		(stroke
			(width 0.2)
			(type default)
		)
		(fill no)
		(layer "In6.Cu")
	)
	(gr_circle
		(center 50.07864 -52.1208)
		(end 50.96764 -52.1208)
		(stroke
			(width 0.2)
			(type default)
		)
		(fill no)
		(layer "In6.Cu")
	)
	(gr_circle
		(center 50.84064 -52.8828)
		(end 51.72964 -52.8828)
		(stroke
			(width 0.2)
			(type default)
		)
		(fill no)
		(layer "In6.Cu")
	)
	(gr_circle
		(center 50.84064 -52.1208)
		(end 51.72964 -52.1208)
		(stroke
			(width 0.2)
			(type default)
		)
		(fill no)
		(layer "In6.Cu")
	)
	(gr_circle
		(center 54.238906 -136.906)
		(end 55.661306 -136.906)
		(stroke
			(width 0.2)
			(type default)
		)
		(fill no)
		(layer "In6.Cu")
	)
	(gr_circle
		(center 55.102506 -131.572)
		(end 55.991506 -131.572)
		(stroke
			(width 0.2)
			(type default)
		)
		(fill no)
		(layer "In6.Cu")
	)
	(gr_circle
		(center 55.102506 -126.492)
		(end 55.991506 -126.492)
		(stroke
			(width 0.2)
			(type default)
		)
		(fill no)
		(layer "In6.Cu")
	)
	(gr_circle
		(center 55.864506 -131.572)
		(end 56.753506 -131.572)
		(stroke
			(width 0.2)
			(type default)
		)
		(fill no)
		(layer "In6.Cu")
	)
	(gr_circle
		(center 55.864506 -126.492)
		(end 56.753506 -126.492)
		(stroke
			(width 0.2)
			(type default)
		)
		(fill no)
		(layer "In6.Cu")
	)
	(gr_circle
		(center 62.850014 -77.71765)
		(end 63.739014 -77.71765)
		(stroke
			(width 0.2)
			(type default)
		)
		(fill no)
		(layer "In6.Cu")
	)
	(gr_circle
		(center 64.470026 -121.209816)
		(end 66.286126 -121.209816)
		(stroke
			(width 0.2)
			(type default)
		)
		(fill no)
		(layer "In6.Cu")
	)
	(gr_circle
		(center 64.470026 -70.409816)
		(end 66.667126 -70.409816)
		(stroke
			(width 0.2)
			(type default)
		)
		(fill no)
		(layer "In6.Cu")
	)
	(gr_circle
		(center 66.430906 -136.906)
		(end 67.853306 -136.906)
		(stroke
			(width 0.2)
			(type default)
		)
		(fill no)
		(layer "In6.Cu")
	)
	(gr_circle
		(center 67.294506 -131.572)
		(end 68.183506 -131.572)
		(stroke
			(width 0.2)
			(type default)
		)
		(fill no)
		(layer "In6.Cu")
	)
	(gr_circle
		(center 67.294506 -126.492)
		(end 68.183506 -126.492)
		(stroke
			(width 0.2)
			(type default)
		)
		(fill no)
		(layer "In6.Cu")
	)
	(gr_circle
		(center 68.056506 -131.572)
		(end 68.945506 -131.572)
		(stroke
			(width 0.2)
			(type default)
		)
		(fill no)
		(layer "In6.Cu")
	)
	(gr_circle
		(center 68.056506 -126.492)
		(end 68.945506 -126.492)
		(stroke
			(width 0.2)
			(type default)
		)
		(fill no)
		(layer "In6.Cu")
	)
	(gr_circle
		(center 68.072 -60.96)
		(end 69.469 -60.96)
		(stroke
			(width 0.2)
			(type default)
		)
		(fill no)
		(layer "In6.Cu")
	)
	(gr_circle
		(center 68.280026 -70.409816)
		(end 70.477126 -70.409816)
		(stroke
			(width 0.2)
			(type default)
		)
		(fill no)
		(layer "In6.Cu")
	)
	(gr_circle
		(center 70.413626 -71.901812)
		(end 71.302626 -71.901812)
		(stroke
			(width 0.2)
			(type default)
		)
		(fill no)
		(layer "In6.Cu")
	)
	(gr_circle
		(center 70.413626 -70.885812)
		(end 71.302626 -70.885812)
		(stroke
			(width 0.2)
			(type default)
		)
		(fill no)
		(layer "In6.Cu")
	)
	(gr_circle
		(center 70.413626 -69.869812)
		(end 71.302626 -69.869812)
		(stroke
			(width 0.2)
			(type default)
		)
		(fill no)
		(layer "In6.Cu")
	)
	(gr_circle
		(center 70.413626 -68.853812)
		(end 71.302626 -68.853812)
		(stroke
			(width 0.2)
			(type default)
		)
		(fill no)
		(layer "In6.Cu")
	)
	(gr_circle
		(center 71.429626 -71.901812)
		(end 72.318626 -71.901812)
		(stroke
			(width 0.2)
			(type default)
		)
		(fill no)
		(layer "In6.Cu")
	)
	(gr_circle
		(center 71.429626 -70.885812)
		(end 72.318626 -70.885812)
		(stroke
			(width 0.2)
			(type default)
		)
		(fill no)
		(layer "In6.Cu")
	)
	(gr_circle
		(center 71.429626 -69.869812)
		(end 72.318626 -69.869812)
		(stroke
			(width 0.2)
			(type default)
		)
		(fill no)
		(layer "In6.Cu")
	)
	(gr_circle
		(center 71.429626 -68.853812)
		(end 72.318626 -68.853812)
		(stroke
			(width 0.2)
			(type default)
		)
		(fill no)
		(layer "In6.Cu")
	)
	(gr_circle
		(center 71.882 -52.324)
		(end 72.771 -52.324)
		(stroke
			(width 0.2)
			(type default)
		)
		(fill no)
		(layer "In6.Cu")
	)
	(gr_circle
		(center 71.882 -51.689)
		(end 72.771 -51.689)
		(stroke
			(width 0.2)
			(type default)
		)
		(fill no)
		(layer "In6.Cu")
	)
	(gr_circle
		(center 71.882 -50.419)
		(end 72.771 -50.419)
		(stroke
			(width 0.2)
			(type default)
		)
		(fill no)
		(layer "In6.Cu")
	)
	(gr_circle
		(center 71.882 -49.784)
		(end 72.771 -49.784)
		(stroke
			(width 0.2)
			(type default)
		)
		(fill no)
		(layer "In6.Cu")
	)
	(gr_circle
		(center 72.445626 -71.901812)
		(end 73.334626 -71.901812)
		(stroke
			(width 0.2)
			(type default)
		)
		(fill no)
		(layer "In6.Cu")
	)
	(gr_circle
		(center 72.445626 -70.885812)
		(end 73.334626 -70.885812)
		(stroke
			(width 0.2)
			(type default)
		)
		(fill no)
		(layer "In6.Cu")
	)
	(gr_circle
		(center 72.445626 -69.869812)
		(end 73.334626 -69.869812)
		(stroke
			(width 0.2)
			(type default)
		)
		(fill no)
		(layer "In6.Cu")
	)
	(gr_circle
		(center 72.445626 -68.853812)
		(end 73.334626 -68.853812)
		(stroke
			(width 0.2)
			(type default)
		)
		(fill no)
		(layer "In6.Cu")
	)
	(gr_circle
		(center 77.343 -52.324)
		(end 78.232 -52.324)
		(stroke
			(width 0.2)
			(type default)
		)
		(fill no)
		(layer "In6.Cu")
	)
	(gr_circle
		(center 77.343 -51.689)
		(end 78.232 -51.689)
		(stroke
			(width 0.2)
			(type default)
		)
		(fill no)
		(layer "In6.Cu")
	)
	(gr_circle
		(center 77.343 -50.419)
		(end 78.232 -50.419)
		(stroke
			(width 0.2)
			(type default)
		)
		(fill no)
		(layer "In6.Cu")
	)
	(gr_circle
		(center 77.343 -49.784)
		(end 78.232 -49.784)
		(stroke
			(width 0.2)
			(type default)
		)
		(fill no)
		(layer "In6.Cu")
	)
	(gr_circle
		(center 79.375 -60.96)
		(end 80.772 -60.96)
		(stroke
			(width 0.2)
			(type default)
		)
		(fill no)
		(layer "In6.Cu")
	)
	(gr_circle
		(center 82.046826 -136.906)
		(end 83.469226 -136.906)
		(stroke
			(width 0.2)
			(type default)
		)
		(fill no)
		(layer "In6.Cu")
	)
	(gr_circle
		(center 82.804 -52.324)
		(end 83.693 -52.324)
		(stroke
			(width 0.2)
			(type default)
		)
		(fill no)
		(layer "In6.Cu")
	)
	(gr_circle
		(center 82.804 -51.689)
		(end 83.693 -51.689)
		(stroke
			(width 0.2)
			(type default)
		)
		(fill no)
		(layer "In6.Cu")
	)
	(gr_circle
		(center 82.804 -50.419)
		(end 83.693 -50.419)
		(stroke
			(width 0.2)
			(type default)
		)
		(fill no)
		(layer "In6.Cu")
	)
	(gr_circle
		(center 82.804 -49.784)
		(end 83.693 -49.784)
		(stroke
			(width 0.2)
			(type default)
		)
		(fill no)
		(layer "In6.Cu")
	)
	(gr_circle
		(center 82.910426 -131.572)
		(end 83.799426 -131.572)
		(stroke
			(width 0.2)
			(type default)
		)
		(fill no)
		(layer "In6.Cu")
	)
	(gr_circle
		(center 82.910426 -126.492)
		(end 83.799426 -126.492)
		(stroke
			(width 0.2)
			(type default)
		)
		(fill no)
		(layer "In6.Cu")
	)
	(gr_circle
		(center 83.672426 -131.572)
		(end 84.561426 -131.572)
		(stroke
			(width 0.2)
			(type default)
		)
		(fill no)
		(layer "In6.Cu")
	)
	(gr_circle
		(center 83.672426 -126.492)
		(end 84.561426 -126.492)
		(stroke
			(width 0.2)
			(type default)
		)
		(fill no)
		(layer "In6.Cu")
	)
	(gr_circle
		(center 88.265 -52.324)
		(end 89.154 -52.324)
		(stroke
			(width 0.2)
			(type default)
		)
		(fill no)
		(layer "In6.Cu")
	)
	(gr_circle
		(center 88.265 -51.689)
		(end 89.154 -51.689)
		(stroke
			(width 0.2)
			(type default)
		)
		(fill no)
		(layer "In6.Cu")
	)
	(gr_circle
		(center 88.265 -50.419)
		(end 89.154 -50.419)
		(stroke
			(width 0.2)
			(type default)
		)
		(fill no)
		(layer "In6.Cu")
	)
	(gr_circle
		(center 88.265 -49.784)
		(end 89.154 -49.784)
		(stroke
			(width 0.2)
			(type default)
		)
		(fill no)
		(layer "In6.Cu")
	)
	(gr_circle
		(center 90.678 -60.96)
		(end 92.075 -60.96)
		(stroke
			(width 0.2)
			(type default)
		)
		(fill no)
		(layer "In6.Cu")
	)
	(gr_circle
		(center 93.726 -52.324)
		(end 94.615 -52.324)
		(stroke
			(width 0.2)
			(type default)
		)
		(fill no)
		(layer "In6.Cu")
	)
	(gr_circle
		(center 93.726 -51.689)
		(end 94.615 -51.689)
		(stroke
			(width 0.2)
			(type default)
		)
		(fill no)
		(layer "In6.Cu")
	)
	(gr_circle
		(center 93.726 -50.419)
		(end 94.615 -50.419)
		(stroke
			(width 0.2)
			(type default)
		)
		(fill no)
		(layer "In6.Cu")
	)
	(gr_circle
		(center 93.726 -49.784)
		(end 94.615 -49.784)
		(stroke
			(width 0.2)
			(type default)
		)
		(fill no)
		(layer "In6.Cu")
	)
	(gr_circle
		(center 94.238826 -136.906)
		(end 95.661226 -136.906)
		(stroke
			(width 0.2)
			(type default)
		)
		(fill no)
		(layer "In6.Cu")
	)
	(gr_circle
		(center 95.102426 -131.572)
		(end 95.991426 -131.572)
		(stroke
			(width 0.2)
			(type default)
		)
		(fill no)
		(layer "In6.Cu")
	)
	(gr_circle
		(center 95.102426 -126.492)
		(end 95.991426 -126.492)
		(stroke
			(width 0.2)
			(type default)
		)
		(fill no)
		(layer "In6.Cu")
	)
	(gr_circle
		(center 95.864426 -131.572)
		(end 96.753426 -131.572)
		(stroke
			(width 0.2)
			(type default)
		)
		(fill no)
		(layer "In6.Cu")
	)
	(gr_circle
		(center 95.864426 -126.492)
		(end 96.753426 -126.492)
		(stroke
			(width 0.2)
			(type default)
		)
		(fill no)
		(layer "In6.Cu")
	)
	(gr_circle
		(center 99.187 -52.324)
		(end 100.076 -52.324)
		(stroke
			(width 0.2)
			(type default)
		)
		(fill no)
		(layer "In6.Cu")
	)
	(gr_circle
		(center 99.187 -51.689)
		(end 100.076 -51.689)
		(stroke
			(width 0.2)
			(type default)
		)
		(fill no)
		(layer "In6.Cu")
	)
	(gr_circle
		(center 99.187 -50.419)
		(end 100.076 -50.419)
		(stroke
			(width 0.2)
			(type default)
		)
		(fill no)
		(layer "In6.Cu")
	)
	(gr_circle
		(center 99.187 -49.784)
		(end 100.076 -49.784)
		(stroke
			(width 0.2)
			(type default)
		)
		(fill no)
		(layer "In6.Cu")
	)
	(gr_circle
		(center 102.045008 -40.55999)
		(end 103.44404 -40.55999)
		(stroke
			(width 0.2)
			(type default)
		)
		(fill no)
		(layer "In6.Cu")
	)
	(gr_circle
		(center 102.045008 -38.01999)
		(end 103.44404 -38.01999)
		(stroke
			(width 0.2)
			(type default)
		)
		(fill no)
		(layer "In6.Cu")
	)
	(gr_circle
		(center 102.045008 -35.47999)
		(end 103.44404 -35.47999)
		(stroke
			(width 0.2)
			(type default)
		)
		(fill no)
		(layer "In6.Cu")
	)
	(gr_circle
		(center 102.045008 -32.93999)
		(end 103.44404 -32.93999)
		(stroke
			(width 0.2)
			(type default)
		)
		(fill no)
		(layer "In6.Cu")
	)
	(gr_circle
		(center 102.849934 -77.71765)
		(end 103.738934 -77.71765)
		(stroke
			(width 0.2)
			(type default)
		)
		(fill no)
		(layer "In6.Cu")
	)
	(gr_circle
		(center 103.315008 -39.54399)
		(end 104.71404 -39.54399)
		(stroke
			(width 0.2)
			(type default)
		)
		(fill no)
		(layer "In6.Cu")
	)
	(gr_circle
		(center 103.315008 -36.74999)
		(end 104.71404 -36.74999)
		(stroke
			(width 0.2)
			(type default)
		)
		(fill no)
		(layer "In6.Cu")
	)
	(gr_circle
		(center 103.315008 -34.20999)
		(end 104.71404 -34.20999)
		(stroke
			(width 0.2)
			(type default)
		)
		(fill no)
		(layer "In6.Cu")
	)
	(gr_circle
		(center 104.469946 -121.209816)
		(end 106.286046 -121.209816)
		(stroke
			(width 0.2)
			(type default)
		)
		(fill no)
		(layer "In6.Cu")
	)
	(gr_circle
		(center 104.469946 -70.409816)
		(end 106.667046 -70.409816)
		(stroke
			(width 0.2)
			(type default)
		)
		(fill no)
		(layer "In6.Cu")
	)
	(gr_circle
		(center 104.585008 -40.55999)
		(end 105.98404 -40.55999)
		(stroke
			(width 0.2)
			(type default)
		)
		(fill no)
		(layer "In6.Cu")
	)
	(gr_circle
		(center 104.585008 -38.01999)
		(end 105.98404 -38.01999)
		(stroke
			(width 0.2)
			(type default)
		)
		(fill no)
		(layer "In6.Cu")
	)
	(gr_circle
		(center 104.585008 -35.47999)
		(end 105.98404 -35.47999)
		(stroke
			(width 0.2)
			(type default)
		)
		(fill no)
		(layer "In6.Cu")
	)
	(gr_circle
		(center 104.585008 -32.93999)
		(end 105.98404 -32.93999)
		(stroke
			(width 0.2)
			(type default)
		)
		(fill no)
		(layer "In6.Cu")
	)
	(gr_circle
		(center 104.648 -52.324)
		(end 105.537 -52.324)
		(stroke
			(width 0.2)
			(type default)
		)
		(fill no)
		(layer "In6.Cu")
	)
	(gr_circle
		(center 104.648 -51.689)
		(end 105.537 -51.689)
		(stroke
			(width 0.2)
			(type default)
		)
		(fill no)
		(layer "In6.Cu")
	)
	(gr_circle
		(center 104.648 -50.419)
		(end 105.537 -50.419)
		(stroke
			(width 0.2)
			(type default)
		)
		(fill no)
		(layer "In6.Cu")
	)
	(gr_circle
		(center 104.648 -49.784)
		(end 105.537 -49.784)
		(stroke
			(width 0.2)
			(type default)
		)
		(fill no)
		(layer "In6.Cu")
	)
	(gr_circle
		(center 106.430826 -136.906)
		(end 107.853226 -136.906)
		(stroke
			(width 0.2)
			(type default)
		)
		(fill no)
		(layer "In6.Cu")
	)
	(gr_circle
		(center 107.294426 -131.572)
		(end 108.183426 -131.572)
		(stroke
			(width 0.2)
			(type default)
		)
		(fill no)
		(layer "In6.Cu")
	)
	(gr_circle
		(center 107.294426 -126.492)
		(end 108.183426 -126.492)
		(stroke
			(width 0.2)
			(type default)
		)
		(fill no)
		(layer "In6.Cu")
	)
	(gr_circle
		(center 108.056426 -131.572)
		(end 108.945426 -131.572)
		(stroke
			(width 0.2)
			(type default)
		)
		(fill no)
		(layer "In6.Cu")
	)
	(gr_circle
		(center 108.056426 -126.492)
		(end 108.945426 -126.492)
		(stroke
			(width 0.2)
			(type default)
		)
		(fill no)
		(layer "In6.Cu")
	)
	(gr_circle
		(center 108.279946 -70.409816)
		(end 110.477046 -70.409816)
		(stroke
			(width 0.2)
			(type default)
		)
		(fill no)
		(layer "In6.Cu")
	)
	(gr_circle
		(center 108.839 -60.96)
		(end 110.236 -60.96)
		(stroke
			(width 0.2)
			(type default)
		)
		(fill no)
		(layer "In6.Cu")
	)
	(gr_circle
		(center 110.362746 -71.929244)
		(end 111.251746 -71.929244)
		(stroke
			(width 0.2)
			(type default)
		)
		(fill no)
		(layer "In6.Cu")
	)
	(gr_circle
		(center 110.362746 -70.913244)
		(end 111.251746 -70.913244)
		(stroke
			(width 0.2)
			(type default)
		)
		(fill no)
		(layer "In6.Cu")
	)
	(gr_circle
		(center 110.362746 -69.897244)
		(end 111.251746 -69.897244)
		(stroke
			(width 0.2)
			(type default)
		)
		(fill no)
		(layer "In6.Cu")
	)
	(gr_circle
		(center 110.362746 -68.881244)
		(end 111.251746 -68.881244)
		(stroke
			(width 0.2)
			(type default)
		)
		(fill no)
		(layer "In6.Cu")
	)
	(gr_circle
		(center 110.935008 -40.55999)
		(end 112.33404 -40.55999)
		(stroke
			(width 0.2)
			(type default)
		)
		(fill no)
		(layer "In6.Cu")
	)
	(gr_circle
		(center 110.935008 -38.01999)
		(end 112.33404 -38.01999)
		(stroke
			(width 0.2)
			(type default)
		)
		(fill no)
		(layer "In6.Cu")
	)
	(gr_circle
		(center 110.935008 -35.47999)
		(end 112.33404 -35.47999)
		(stroke
			(width 0.2)
			(type default)
		)
		(fill no)
		(layer "In6.Cu")
	)
	(gr_circle
		(center 110.935008 -32.93999)
		(end 112.33404 -32.93999)
		(stroke
			(width 0.2)
			(type default)
		)
		(fill no)
		(layer "In6.Cu")
	)
	(gr_circle
		(center 111.378746 -71.929244)
		(end 112.267746 -71.929244)
		(stroke
			(width 0.2)
			(type default)
		)
		(fill no)
		(layer "In6.Cu")
	)
	(gr_circle
		(center 111.378746 -70.913244)
		(end 112.267746 -70.913244)
		(stroke
			(width 0.2)
			(type default)
		)
		(fill no)
		(layer "In6.Cu")
	)
	(gr_circle
		(center 111.378746 -69.897244)
		(end 112.267746 -69.897244)
		(stroke
			(width 0.2)
			(type default)
		)
		(fill no)
		(layer "In6.Cu")
	)
	(gr_circle
		(center 111.378746 -68.881244)
		(end 112.267746 -68.881244)
		(stroke
			(width 0.2)
			(type default)
		)
		(fill no)
		(layer "In6.Cu")
	)
	(gr_circle
		(center 112.078008 -39.16299)
		(end 113.47704 -39.16299)
		(stroke
			(width 0.2)
			(type default)
		)
		(fill no)
		(layer "In6.Cu")
	)
	(gr_circle
		(center 112.205008 -36.87699)
		(end 113.60404 -36.87699)
		(stroke
			(width 0.2)
			(type default)
		)
		(fill no)
		(layer "In6.Cu")
	)
	(gr_circle
		(center 112.205008 -34.08299)
		(end 113.60404 -34.08299)
		(stroke
			(width 0.2)
			(type default)
		)
		(fill no)
		(layer "In6.Cu")
	)
	(gr_circle
		(center 112.394746 -71.929244)
		(end 113.283746 -71.929244)
		(stroke
			(width 0.2)
			(type default)
		)
		(fill no)
		(layer "In6.Cu")
	)
	(gr_circle
		(center 112.394746 -70.913244)
		(end 113.283746 -70.913244)
		(stroke
			(width 0.2)
			(type default)
		)
		(fill no)
		(layer "In6.Cu")
	)
	(gr_circle
		(center 112.394746 -69.897244)
		(end 113.283746 -69.897244)
		(stroke
			(width 0.2)
			(type default)
		)
		(fill no)
		(layer "In6.Cu")
	)
	(gr_circle
		(center 112.394746 -68.881244)
		(end 113.283746 -68.881244)
		(stroke
			(width 0.2)
			(type default)
		)
		(fill no)
		(layer "In6.Cu")
	)
	(gr_circle
		(center 113.475008 -40.55999)
		(end 114.87404 -40.55999)
		(stroke
			(width 0.2)
			(type default)
		)
		(fill no)
		(layer "In6.Cu")
	)
	(gr_circle
		(center 113.475008 -38.01999)
		(end 114.87404 -38.01999)
		(stroke
			(width 0.2)
			(type default)
		)
		(fill no)
		(layer "In6.Cu")
	)
	(gr_circle
		(center 113.475008 -35.47999)
		(end 114.87404 -35.47999)
		(stroke
			(width 0.2)
			(type default)
		)
		(fill no)
		(layer "In6.Cu")
	)
	(gr_circle
		(center 113.475008 -32.93999)
		(end 114.87404 -32.93999)
		(stroke
			(width 0.2)
			(type default)
		)
		(fill no)
		(layer "In6.Cu")
	)
	(gr_circle
		(center 119.825008 -40.55999)
		(end 121.22404 -40.55999)
		(stroke
			(width 0.2)
			(type default)
		)
		(fill no)
		(layer "In6.Cu")
	)
	(gr_circle
		(center 119.825008 -38.01999)
		(end 121.22404 -38.01999)
		(stroke
			(width 0.2)
			(type default)
		)
		(fill no)
		(layer "In6.Cu")
	)
	(gr_circle
		(center 119.825008 -35.47999)
		(end 121.22404 -35.47999)
		(stroke
			(width 0.2)
			(type default)
		)
		(fill no)
		(layer "In6.Cu")
	)
	(gr_circle
		(center 119.825008 -32.93999)
		(end 121.22404 -32.93999)
		(stroke
			(width 0.2)
			(type default)
		)
		(fill no)
		(layer "In6.Cu")
	)
	(gr_circle
		(center 120.015 -60.96)
		(end 121.412 -60.96)
		(stroke
			(width 0.2)
			(type default)
		)
		(fill no)
		(layer "In6.Cu")
	)
	(gr_circle
		(center 121.222008 -39.54399)
		(end 122.62104 -39.54399)
		(stroke
			(width 0.2)
			(type default)
		)
		(fill no)
		(layer "In6.Cu")
	)
	(gr_circle
		(center 121.222008 -37.00399)
		(end 122.62104 -37.00399)
		(stroke
			(width 0.2)
			(type default)
		)
		(fill no)
		(layer "In6.Cu")
	)
	(gr_circle
		(center 121.222008 -34.46399)
		(end 122.62104 -34.46399)
		(stroke
			(width 0.2)
			(type default)
		)
		(fill no)
		(layer "In6.Cu")
	)
	(gr_circle
		(center 122.047 -136.906)
		(end 123.4694 -136.906)
		(stroke
			(width 0.2)
			(type default)
		)
		(fill no)
		(layer "In6.Cu")
	)
	(gr_circle
		(center 122.365008 -40.55999)
		(end 123.76404 -40.55999)
		(stroke
			(width 0.2)
			(type default)
		)
		(fill no)
		(layer "In6.Cu")
	)
	(gr_circle
		(center 122.365008 -38.01999)
		(end 123.76404 -38.01999)
		(stroke
			(width 0.2)
			(type default)
		)
		(fill no)
		(layer "In6.Cu")
	)
	(gr_circle
		(center 122.365008 -35.47999)
		(end 123.76404 -35.47999)
		(stroke
			(width 0.2)
			(type default)
		)
		(fill no)
		(layer "In6.Cu")
	)
	(gr_circle
		(center 122.365008 -32.93999)
		(end 123.76404 -32.93999)
		(stroke
			(width 0.2)
			(type default)
		)
		(fill no)
		(layer "In6.Cu")
	)
	(gr_circle
		(center 122.9106 -131.572)
		(end 123.7996 -131.572)
		(stroke
			(width 0.2)
			(type default)
		)
		(fill no)
		(layer "In6.Cu")
	)
	(gr_circle
		(center 122.9106 -126.492)
		(end 123.7996 -126.492)
		(stroke
			(width 0.2)
			(type default)
		)
		(fill no)
		(layer "In6.Cu")
	)
	(gr_circle
		(center 123.6726 -131.572)
		(end 124.5616 -131.572)
		(stroke
			(width 0.2)
			(type default)
		)
		(fill no)
		(layer "In6.Cu")
	)
	(gr_circle
		(center 123.6726 -126.492)
		(end 124.5616 -126.492)
		(stroke
			(width 0.2)
			(type default)
		)
		(fill no)
		(layer "In6.Cu")
	)
	(gr_circle
		(center 131.191 -60.96)
		(end 132.588 -60.96)
		(stroke
			(width 0.2)
			(type default)
		)
		(fill no)
		(layer "In6.Cu")
	)
	(gr_circle
		(center 134.239 -136.906)
		(end 135.6614 -136.906)
		(stroke
			(width 0.2)
			(type default)
		)
		(fill no)
		(layer "In6.Cu")
	)
	(gr_circle
		(center 135.1026 -131.572)
		(end 135.9916 -131.572)
		(stroke
			(width 0.2)
			(type default)
		)
		(fill no)
		(layer "In6.Cu")
	)
	(gr_circle
		(center 135.1026 -126.492)
		(end 135.9916 -126.492)
		(stroke
			(width 0.2)
			(type default)
		)
		(fill no)
		(layer "In6.Cu")
	)
	(gr_circle
		(center 135.8646 -131.572)
		(end 136.7536 -131.572)
		(stroke
			(width 0.2)
			(type default)
		)
		(fill no)
		(layer "In6.Cu")
	)
	(gr_circle
		(center 135.8646 -126.492)
		(end 136.7536 -126.492)
		(stroke
			(width 0.2)
			(type default)
		)
		(fill no)
		(layer "In6.Cu")
	)
	(gr_circle
		(center 142.748 -112.268)
		(end 143.637 -112.268)
		(stroke
			(width 0.2)
			(type default)
		)
		(fill no)
		(layer "In6.Cu")
	)
	(gr_circle
		(center 142.850108 -77.71765)
		(end 143.739108 -77.71765)
		(stroke
			(width 0.2)
			(type default)
		)
		(fill no)
		(layer "In6.Cu")
	)
	(gr_circle
		(center 143.383 -112.268)
		(end 144.272 -112.268)
		(stroke
			(width 0.2)
			(type default)
		)
		(fill no)
		(layer "In6.Cu")
	)
	(gr_circle
		(center 144.47012 -121.209816)
		(end 146.28622 -121.209816)
		(stroke
			(width 0.2)
			(type default)
		)
		(fill no)
		(layer "In6.Cu")
	)
	(gr_circle
		(center 144.47012 -70.409816)
		(end 146.66722 -70.409816)
		(stroke
			(width 0.2)
			(type default)
		)
		(fill no)
		(layer "In6.Cu")
	)
	(gr_circle
		(center 146.431 -136.906)
		(end 147.8534 -136.906)
		(stroke
			(width 0.2)
			(type default)
		)
		(fill no)
		(layer "In6.Cu")
	)
	(gr_circle
		(center 146.939 -60.96)
		(end 148.336 -60.96)
		(stroke
			(width 0.2)
			(type default)
		)
		(fill no)
		(layer "In6.Cu")
	)
	(gr_circle
		(center 147.2946 -131.572)
		(end 148.1836 -131.572)
		(stroke
			(width 0.2)
			(type default)
		)
		(fill no)
		(layer "In6.Cu")
	)
	(gr_circle
		(center 147.2946 -126.492)
		(end 148.1836 -126.492)
		(stroke
			(width 0.2)
			(type default)
		)
		(fill no)
		(layer "In6.Cu")
	)
	(gr_circle
		(center 148.0566 -131.572)
		(end 148.9456 -131.572)
		(stroke
			(width 0.2)
			(type default)
		)
		(fill no)
		(layer "In6.Cu")
	)
	(gr_circle
		(center 148.0566 -126.492)
		(end 148.9456 -126.492)
		(stroke
			(width 0.2)
			(type default)
		)
		(fill no)
		(layer "In6.Cu")
	)
	(gr_circle
		(center 148.28012 -70.409816)
		(end 150.47722 -70.409816)
		(stroke
			(width 0.2)
			(type default)
		)
		(fill no)
		(layer "In6.Cu")
	)
	(gr_circle
		(center 149.987 -52.197)
		(end 150.876 -52.197)
		(stroke
			(width 0.2)
			(type default)
		)
		(fill no)
		(layer "In6.Cu")
	)
	(gr_circle
		(center 149.987 -51.562)
		(end 150.876 -51.562)
		(stroke
			(width 0.2)
			(type default)
		)
		(fill no)
		(layer "In6.Cu")
	)
	(gr_circle
		(center 149.987 -50.292)
		(end 150.876 -50.292)
		(stroke
			(width 0.2)
			(type default)
		)
		(fill no)
		(layer "In6.Cu")
	)
	(gr_circle
		(center 149.987 -49.657)
		(end 150.876 -49.657)
		(stroke
			(width 0.2)
			(type default)
		)
		(fill no)
		(layer "In6.Cu")
	)
	(gr_circle
		(center 155.448 -52.197)
		(end 156.337 -52.197)
		(stroke
			(width 0.2)
			(type default)
		)
		(fill no)
		(layer "In6.Cu")
	)
	(gr_circle
		(center 155.448 -51.562)
		(end 156.337 -51.562)
		(stroke
			(width 0.2)
			(type default)
		)
		(fill no)
		(layer "In6.Cu")
	)
	(gr_circle
		(center 155.448 -50.292)
		(end 156.337 -50.292)
		(stroke
			(width 0.2)
			(type default)
		)
		(fill no)
		(layer "In6.Cu")
	)
	(gr_circle
		(center 155.448 -49.657)
		(end 156.337 -49.657)
		(stroke
			(width 0.2)
			(type default)
		)
		(fill no)
		(layer "In6.Cu")
	)
	(gr_circle
		(center 158.115 -60.96)
		(end 159.512 -60.96)
		(stroke
			(width 0.2)
			(type default)
		)
		(fill no)
		(layer "In6.Cu")
	)
	(gr_circle
		(center 160.909 -52.197)
		(end 161.798 -52.197)
		(stroke
			(width 0.2)
			(type default)
		)
		(fill no)
		(layer "In6.Cu")
	)
	(gr_circle
		(center 160.909 -51.562)
		(end 161.798 -51.562)
		(stroke
			(width 0.2)
			(type default)
		)
		(fill no)
		(layer "In6.Cu")
	)
	(gr_circle
		(center 160.909 -50.292)
		(end 161.798 -50.292)
		(stroke
			(width 0.2)
			(type default)
		)
		(fill no)
		(layer "In6.Cu")
	)
	(gr_circle
		(center 160.909 -49.657)
		(end 161.798 -49.657)
		(stroke
			(width 0.2)
			(type default)
		)
		(fill no)
		(layer "In6.Cu")
	)
	(gr_circle
		(center 162.047174 -136.906)
		(end 163.469574 -136.906)
		(stroke
			(width 0.2)
			(type default)
		)
		(fill no)
		(layer "In6.Cu")
	)
	(gr_circle
		(center 162.1028 -11.811)
		(end 162.9918 -11.811)
		(stroke
			(width 0.2)
			(type default)
		)
		(fill no)
		(layer "In6.Cu")
	)
	(gr_circle
		(center 162.1028 -11.176)
		(end 162.9918 -11.176)
		(stroke
			(width 0.2)
			(type default)
		)
		(fill no)
		(layer "In6.Cu")
	)
	(gr_circle
		(center 162.7886 -10.7442)
		(end 163.6776 -10.7442)
		(stroke
			(width 0.2)
			(type default)
		)
		(fill no)
		(layer "In6.Cu")
	)
	(gr_circle
		(center 162.8394 -12.2174)
		(end 163.7284 -12.2174)
		(stroke
			(width 0.2)
			(type default)
		)
		(fill no)
		(layer "In6.Cu")
	)
	(gr_circle
		(center 162.910774 -131.572)
		(end 163.799774 -131.572)
		(stroke
			(width 0.2)
			(type default)
		)
		(fill no)
		(layer "In6.Cu")
	)
	(gr_circle
		(center 162.910774 -126.492)
		(end 163.799774 -126.492)
		(stroke
			(width 0.2)
			(type default)
		)
		(fill no)
		(layer "In6.Cu")
	)
	(gr_circle
		(center 163.672774 -131.572)
		(end 164.561774 -131.572)
		(stroke
			(width 0.2)
			(type default)
		)
		(fill no)
		(layer "In6.Cu")
	)
	(gr_circle
		(center 163.672774 -126.492)
		(end 164.561774 -126.492)
		(stroke
			(width 0.2)
			(type default)
		)
		(fill no)
		(layer "In6.Cu")
	)
	(gr_circle
		(center 166.37 -52.197)
		(end 167.259 -52.197)
		(stroke
			(width 0.2)
			(type default)
		)
		(fill no)
		(layer "In6.Cu")
	)
	(gr_circle
		(center 166.37 -51.562)
		(end 167.259 -51.562)
		(stroke
			(width 0.2)
			(type default)
		)
		(fill no)
		(layer "In6.Cu")
	)
	(gr_circle
		(center 166.37 -50.292)
		(end 167.259 -50.292)
		(stroke
			(width 0.2)
			(type default)
		)
		(fill no)
		(layer "In6.Cu")
	)
	(gr_circle
		(center 166.37 -49.657)
		(end 167.259 -49.657)
		(stroke
			(width 0.2)
			(type default)
		)
		(fill no)
		(layer "In6.Cu")
	)
	(gr_circle
		(center 169.291 -60.96)
		(end 170.688 -60.96)
		(stroke
			(width 0.2)
			(type default)
		)
		(fill no)
		(layer "In6.Cu")
	)
	(gr_circle
		(center 171.831 -52.197)
		(end 172.72 -52.197)
		(stroke
			(width 0.2)
			(type default)
		)
		(fill no)
		(layer "In6.Cu")
	)
	(gr_circle
		(center 171.831 -51.562)
		(end 172.72 -51.562)
		(stroke
			(width 0.2)
			(type default)
		)
		(fill no)
		(layer "In6.Cu")
	)
	(gr_circle
		(center 171.831 -50.292)
		(end 172.72 -50.292)
		(stroke
			(width 0.2)
			(type default)
		)
		(fill no)
		(layer "In6.Cu")
	)
	(gr_circle
		(center 171.831 -49.657)
		(end 172.72 -49.657)
		(stroke
			(width 0.2)
			(type default)
		)
		(fill no)
		(layer "In6.Cu")
	)
	(gr_circle
		(center 174.239174 -136.906)
		(end 175.661574 -136.906)
		(stroke
			(width 0.2)
			(type default)
		)
		(fill no)
		(layer "In6.Cu")
	)
	(gr_circle
		(center 175.102774 -131.572)
		(end 175.991774 -131.572)
		(stroke
			(width 0.2)
			(type default)
		)
		(fill no)
		(layer "In6.Cu")
	)
	(gr_circle
		(center 175.102774 -126.492)
		(end 175.991774 -126.492)
		(stroke
			(width 0.2)
			(type default)
		)
		(fill no)
		(layer "In6.Cu")
	)
	(gr_circle
		(center 175.864774 -131.572)
		(end 176.753774 -131.572)
		(stroke
			(width 0.2)
			(type default)
		)
		(fill no)
		(layer "In6.Cu")
	)
	(gr_circle
		(center 175.864774 -126.492)
		(end 176.753774 -126.492)
		(stroke
			(width 0.2)
			(type default)
		)
		(fill no)
		(layer "In6.Cu")
	)
	(gr_circle
		(center 177.28946 -52.197)
		(end 178.17846 -52.197)
		(stroke
			(width 0.2)
			(type default)
		)
		(fill no)
		(layer "In6.Cu")
	)
	(gr_circle
		(center 177.28946 -51.562)
		(end 178.17846 -51.562)
		(stroke
			(width 0.2)
			(type default)
		)
		(fill no)
		(layer "In6.Cu")
	)
	(gr_circle
		(center 177.28946 -50.292)
		(end 178.17846 -50.292)
		(stroke
			(width 0.2)
			(type default)
		)
		(fill no)
		(layer "In6.Cu")
	)
	(gr_circle
		(center 177.28946 -49.657)
		(end 178.17846 -49.657)
		(stroke
			(width 0.2)
			(type default)
		)
		(fill no)
		(layer "In6.Cu")
	)
	(gr_circle
		(center 180.989986 -37.949632)
		(end 182.389018 -37.949632)
		(stroke
			(width 0.2)
			(type default)
		)
		(fill no)
		(layer "In6.Cu")
	)
	(gr_circle
		(center 180.989986 -35.409632)
		(end 182.389018 -35.409632)
		(stroke
			(width 0.2)
			(type default)
		)
		(fill no)
		(layer "In6.Cu")
	)
	(gr_circle
		(center 180.989986 -32.869632)
		(end 182.389018 -32.869632)
		(stroke
			(width 0.2)
			(type default)
		)
		(fill no)
		(layer "In6.Cu")
	)
	(gr_circle
		(center 180.989986 -30.329632)
		(end 182.389018 -30.329632)
		(stroke
			(width 0.2)
			(type default)
		)
		(fill no)
		(layer "In6.Cu")
	)
	(gr_circle
		(center 182.182008 -33.95599)
		(end 183.58104 -33.95599)
		(stroke
			(width 0.2)
			(type default)
		)
		(fill no)
		(layer "In6.Cu")
	)
	(gr_circle
		(center 182.182008 -31.16199)
		(end 183.58104 -31.16199)
		(stroke
			(width 0.2)
			(type default)
		)
		(fill no)
		(layer "In6.Cu")
	)
	(gr_circle
		(center 182.309008 -36.74999)
		(end 183.70804 -36.74999)
		(stroke
			(width 0.2)
			(type default)
		)
		(fill no)
		(layer "In6.Cu")
	)
	(gr_circle
		(center 182.75046 -52.197)
		(end 183.63946 -52.197)
		(stroke
			(width 0.2)
			(type default)
		)
		(fill no)
		(layer "In6.Cu")
	)
	(gr_circle
		(center 182.75046 -51.562)
		(end 183.63946 -51.562)
		(stroke
			(width 0.2)
			(type default)
		)
		(fill no)
		(layer "In6.Cu")
	)
	(gr_circle
		(center 182.75046 -50.292)
		(end 183.63946 -50.292)
		(stroke
			(width 0.2)
			(type default)
		)
		(fill no)
		(layer "In6.Cu")
	)
	(gr_circle
		(center 182.75046 -49.657)
		(end 183.63946 -49.657)
		(stroke
			(width 0.2)
			(type default)
		)
		(fill no)
		(layer "In6.Cu")
	)
	(gr_circle
		(center 182.850282 -77.71765)
		(end 183.739282 -77.71765)
		(stroke
			(width 0.2)
			(type default)
		)
		(fill no)
		(layer "In6.Cu")
	)
	(gr_circle
		(center 183.529986 -37.949632)
		(end 184.929018 -37.949632)
		(stroke
			(width 0.2)
			(type default)
		)
		(fill no)
		(layer "In6.Cu")
	)
	(gr_circle
		(center 183.529986 -35.409632)
		(end 184.929018 -35.409632)
		(stroke
			(width 0.2)
			(type default)
		)
		(fill no)
		(layer "In6.Cu")
	)
	(gr_circle
		(center 183.529986 -32.869632)
		(end 184.929018 -32.869632)
		(stroke
			(width 0.2)
			(type default)
		)
		(fill no)
		(layer "In6.Cu")
	)
	(gr_circle
		(center 183.529986 -30.329632)
		(end 184.929018 -30.329632)
		(stroke
			(width 0.2)
			(type default)
		)
		(fill no)
		(layer "In6.Cu")
	)
	(gr_circle
		(center 184.470294 -121.209816)
		(end 186.286394 -121.209816)
		(stroke
			(width 0.2)
			(type default)
		)
		(fill no)
		(layer "In6.Cu")
	)
	(gr_circle
		(center 184.470294 -70.409816)
		(end 186.667394 -70.409816)
		(stroke
			(width 0.2)
			(type default)
		)
		(fill no)
		(layer "In6.Cu")
	)
	(gr_circle
		(center 186.431174 -136.906)
		(end 187.853574 -136.906)
		(stroke
			(width 0.2)
			(type default)
		)
		(fill no)
		(layer "In6.Cu")
	)
	(gr_circle
		(center 186.939174 -60.96)
		(end 188.336174 -60.96)
		(stroke
			(width 0.2)
			(type default)
		)
		(fill no)
		(layer "In6.Cu")
	)
	(gr_circle
		(center 187.294774 -131.572)
		(end 188.183774 -131.572)
		(stroke
			(width 0.2)
			(type default)
		)
		(fill no)
		(layer "In6.Cu")
	)
	(gr_circle
		(center 187.294774 -126.492)
		(end 188.183774 -126.492)
		(stroke
			(width 0.2)
			(type default)
		)
		(fill no)
		(layer "In6.Cu")
	)
	(gr_circle
		(center 188.056774 -131.572)
		(end 188.945774 -131.572)
		(stroke
			(width 0.2)
			(type default)
		)
		(fill no)
		(layer "In6.Cu")
	)
	(gr_circle
		(center 188.056774 -126.492)
		(end 188.945774 -126.492)
		(stroke
			(width 0.2)
			(type default)
		)
		(fill no)
		(layer "In6.Cu")
	)
	(gr_circle
		(center 188.280294 -70.409816)
		(end 190.477394 -70.409816)
		(stroke
			(width 0.2)
			(type default)
		)
		(fill no)
		(layer "In6.Cu")
	)
	(gr_circle
		(center 189.879986 -37.949632)
		(end 191.279018 -37.949632)
		(stroke
			(width 0.2)
			(type default)
		)
		(fill no)
		(layer "In6.Cu")
	)
	(gr_circle
		(center 189.879986 -35.409632)
		(end 191.279018 -35.409632)
		(stroke
			(width 0.2)
			(type default)
		)
		(fill no)
		(layer "In6.Cu")
	)
	(gr_circle
		(center 189.879986 -32.869632)
		(end 191.279018 -32.869632)
		(stroke
			(width 0.2)
			(type default)
		)
		(fill no)
		(layer "In6.Cu")
	)
	(gr_circle
		(center 189.879986 -30.329632)
		(end 191.279018 -30.329632)
		(stroke
			(width 0.2)
			(type default)
		)
		(fill no)
		(layer "In6.Cu")
	)
	(gr_circle
		(center 190.945008 -36.49599)
		(end 192.34404 -36.49599)
		(stroke
			(width 0.2)
			(type default)
		)
		(fill no)
		(layer "In6.Cu")
	)
	(gr_circle
		(center 191.199008 -34.59099)
		(end 192.59804 -34.59099)
		(stroke
			(width 0.2)
			(type default)
		)
		(fill no)
		(layer "In6.Cu")
	)
	(gr_circle
		(center 191.326008 -32.17799)
		(end 192.72504 -32.17799)
		(stroke
			(width 0.2)
			(type default)
		)
		(fill no)
		(layer "In6.Cu")
	)
	(gr_circle
		(center 192.419986 -37.949632)
		(end 193.819018 -37.949632)
		(stroke
			(width 0.2)
			(type default)
		)
		(fill no)
		(layer "In6.Cu")
	)
	(gr_circle
		(center 192.419986 -35.409632)
		(end 193.819018 -35.409632)
		(stroke
			(width 0.2)
			(type default)
		)
		(fill no)
		(layer "In6.Cu")
	)
	(gr_circle
		(center 192.419986 -32.869632)
		(end 193.819018 -32.869632)
		(stroke
			(width 0.2)
			(type default)
		)
		(fill no)
		(layer "In6.Cu")
	)
	(gr_circle
		(center 192.419986 -30.329632)
		(end 193.819018 -30.329632)
		(stroke
			(width 0.2)
			(type default)
		)
		(fill no)
		(layer "In6.Cu")
	)
	(gr_circle
		(center 198.115174 -60.96)
		(end 199.512174 -60.96)
		(stroke
			(width 0.2)
			(type default)
		)
		(fill no)
		(layer "In6.Cu")
	)
	(gr_circle
		(center 198.769986 -37.949632)
		(end 200.169018 -37.949632)
		(stroke
			(width 0.2)
			(type default)
		)
		(fill no)
		(layer "In6.Cu")
	)
	(gr_circle
		(center 198.769986 -35.409632)
		(end 200.169018 -35.409632)
		(stroke
			(width 0.2)
			(type default)
		)
		(fill no)
		(layer "In6.Cu")
	)
	(gr_circle
		(center 198.769986 -32.869632)
		(end 200.169018 -32.869632)
		(stroke
			(width 0.2)
			(type default)
		)
		(fill no)
		(layer "In6.Cu")
	)
	(gr_circle
		(center 198.769986 -30.329632)
		(end 200.169018 -30.329632)
		(stroke
			(width 0.2)
			(type default)
		)
		(fill no)
		(layer "In6.Cu")
	)
	(gr_circle
		(center 199.962008 -36.74999)
		(end 201.36104 -36.74999)
		(stroke
			(width 0.2)
			(type default)
		)
		(fill no)
		(layer "In6.Cu")
	)
	(gr_circle
		(center 199.962008 -34.59099)
		(end 201.36104 -34.59099)
		(stroke
			(width 0.2)
			(type default)
		)
		(fill no)
		(layer "In6.Cu")
	)
	(gr_circle
		(center 200.089008 -31.79699)
		(end 201.48804 -31.79699)
		(stroke
			(width 0.2)
			(type default)
		)
		(fill no)
		(layer "In6.Cu")
	)
	(gr_circle
		(center 201.309986 -37.949632)
		(end 202.709018 -37.949632)
		(stroke
			(width 0.2)
			(type default)
		)
		(fill no)
		(layer "In6.Cu")
	)
	(gr_circle
		(center 201.309986 -35.409632)
		(end 202.709018 -35.409632)
		(stroke
			(width 0.2)
			(type default)
		)
		(fill no)
		(layer "In6.Cu")
	)
	(gr_circle
		(center 201.309986 -32.869632)
		(end 202.709018 -32.869632)
		(stroke
			(width 0.2)
			(type default)
		)
		(fill no)
		(layer "In6.Cu")
	)
	(gr_circle
		(center 201.309986 -30.329632)
		(end 202.709018 -30.329632)
		(stroke
			(width 0.2)
			(type default)
		)
		(fill no)
		(layer "In6.Cu")
	)
	(gr_circle
		(center 202.3364 -105.883202)
		(end 203.2254 -105.883202)
		(stroke
			(width 0.2)
			(type default)
		)
		(fill no)
		(layer "In6.Cu")
	)
	(gr_circle
		(center 202.3364 -105.121202)
		(end 203.2254 -105.121202)
		(stroke
			(width 0.2)
			(type default)
		)
		(fill no)
		(layer "In6.Cu")
	)
	(gr_circle
		(center 202.3364 -104.418638)
		(end 203.2254 -104.418638)
		(stroke
			(width 0.2)
			(type default)
		)
		(fill no)
		(layer "In6.Cu")
	)
	(gr_circle
		(center 202.3364 -103.656638)
		(end 203.2254 -103.656638)
		(stroke
			(width 0.2)
			(type default)
		)
		(fill no)
		(layer "In6.Cu")
	)
	(gr_circle
		(center 202.3364 -102.894638)
		(end 203.2254 -102.894638)
		(stroke
			(width 0.2)
			(type default)
		)
		(fill no)
		(layer "In6.Cu")
	)
	(gr_circle
		(center 202.35037 -122.809762)
		(end 203.23937 -122.809762)
		(stroke
			(width 0.2)
			(type default)
		)
		(fill no)
		(layer "In6.Cu")
	)
	(gr_circle
		(center 202.35037 -122.047762)
		(end 203.23937 -122.047762)
		(stroke
			(width 0.2)
			(type default)
		)
		(fill no)
		(layer "In6.Cu")
	)
	(gr_circle
		(center 202.35037 -121.331736)
		(end 203.23937 -121.331736)
		(stroke
			(width 0.2)
			(type default)
		)
		(fill no)
		(layer "In6.Cu")
	)
	(gr_circle
		(center 202.35037 -120.569736)
		(end 203.23937 -120.569736)
		(stroke
			(width 0.2)
			(type default)
		)
		(fill no)
		(layer "In6.Cu")
	)
	(gr_circle
		(center 202.364086 -123.528328)
		(end 203.253086 -123.528328)
		(stroke
			(width 0.2)
			(type default)
		)
		(fill no)
		(layer "In6.Cu")
	)
	(gr_circle
		(center 203.028042 -105.896664)
		(end 203.917042 -105.896664)
		(stroke
			(width 0.2)
			(type default)
		)
		(fill no)
		(layer "In6.Cu")
	)
	(gr_circle
		(center 203.028042 -105.134664)
		(end 203.917042 -105.134664)
		(stroke
			(width 0.2)
			(type default)
		)
		(fill no)
		(layer "In6.Cu")
	)
	(gr_circle
		(center 203.028042 -104.4321)
		(end 203.917042 -104.4321)
		(stroke
			(width 0.2)
			(type default)
		)
		(fill no)
		(layer "In6.Cu")
	)
	(gr_circle
		(center 203.028042 -103.6701)
		(end 203.917042 -103.6701)
		(stroke
			(width 0.2)
			(type default)
		)
		(fill no)
		(layer "In6.Cu")
	)
	(gr_circle
		(center 203.028042 -102.9081)
		(end 203.917042 -102.9081)
		(stroke
			(width 0.2)
			(type default)
		)
		(fill no)
		(layer "In6.Cu")
	)
	(gr_circle
		(center 203.11237 -122.809762)
		(end 204.00137 -122.809762)
		(stroke
			(width 0.2)
			(type default)
		)
		(fill no)
		(layer "In6.Cu")
	)
	(gr_circle
		(center 203.11237 -122.047762)
		(end 204.00137 -122.047762)
		(stroke
			(width 0.2)
			(type default)
		)
		(fill no)
		(layer "In6.Cu")
	)
	(gr_circle
		(center 203.11237 -121.331736)
		(end 204.00137 -121.331736)
		(stroke
			(width 0.2)
			(type default)
		)
		(fill no)
		(layer "In6.Cu")
	)
	(gr_circle
		(center 203.11237 -120.569736)
		(end 204.00137 -120.569736)
		(stroke
			(width 0.2)
			(type default)
		)
		(fill no)
		(layer "In6.Cu")
	)
	(gr_circle
		(center 203.126086 -123.528328)
		(end 204.015086 -123.528328)
		(stroke
			(width 0.2)
			(type default)
		)
		(fill no)
		(layer "In6.Cu")
	)
	(gr_circle
		(center 203.790042 -105.896664)
		(end 204.679042 -105.896664)
		(stroke
			(width 0.2)
			(type default)
		)
		(fill no)
		(layer "In6.Cu")
	)
	(gr_circle
		(center 203.790042 -105.134664)
		(end 204.679042 -105.134664)
		(stroke
			(width 0.2)
			(type default)
		)
		(fill no)
		(layer "In6.Cu")
	)
	(gr_circle
		(center 203.790042 -104.4321)
		(end 204.679042 -104.4321)
		(stroke
			(width 0.2)
			(type default)
		)
		(fill no)
		(layer "In6.Cu")
	)
	(gr_circle
		(center 203.790042 -103.6701)
		(end 204.679042 -103.6701)
		(stroke
			(width 0.2)
			(type default)
		)
		(fill no)
		(layer "In6.Cu")
	)
	(gr_circle
		(center 203.790042 -102.9081)
		(end 204.679042 -102.9081)
		(stroke
			(width 0.2)
			(type default)
		)
		(fill no)
		(layer "In6.Cu")
	)
	(gr_circle
		(center 203.87437 -122.809762)
		(end 204.76337 -122.809762)
		(stroke
			(width 0.2)
			(type default)
		)
		(fill no)
		(layer "In6.Cu")
	)
	(gr_circle
		(center 203.87437 -122.047762)
		(end 204.76337 -122.047762)
		(stroke
			(width 0.2)
			(type default)
		)
		(fill no)
		(layer "In6.Cu")
	)
	(gr_circle
		(center 203.87437 -121.331736)
		(end 204.76337 -121.331736)
		(stroke
			(width 0.2)
			(type default)
		)
		(fill no)
		(layer "In6.Cu")
	)
	(gr_circle
		(center 203.87437 -120.569736)
		(end 204.76337 -120.569736)
		(stroke
			(width 0.2)
			(type default)
		)
		(fill no)
		(layer "In6.Cu")
	)
	(gr_circle
		(center 203.888086 -123.528328)
		(end 204.777086 -123.528328)
		(stroke
			(width 0.2)
			(type default)
		)
		(fill no)
		(layer "In6.Cu")
	)
	(gr_circle
		(center 204.552042 -105.896664)
		(end 205.441042 -105.896664)
		(stroke
			(width 0.2)
			(type default)
		)
		(fill no)
		(layer "In6.Cu")
	)
	(gr_circle
		(center 204.552042 -105.134664)
		(end 205.441042 -105.134664)
		(stroke
			(width 0.2)
			(type default)
		)
		(fill no)
		(layer "In6.Cu")
	)
	(gr_circle
		(center 204.552042 -104.4321)
		(end 205.441042 -104.4321)
		(stroke
			(width 0.2)
			(type default)
		)
		(fill no)
		(layer "In6.Cu")
	)
	(gr_circle
		(center 204.552042 -103.6701)
		(end 205.441042 -103.6701)
		(stroke
			(width 0.2)
			(type default)
		)
		(fill no)
		(layer "In6.Cu")
	)
	(gr_circle
		(center 204.552042 -102.9081)
		(end 205.441042 -102.9081)
		(stroke
			(width 0.2)
			(type default)
		)
		(fill no)
		(layer "In6.Cu")
	)
	(gr_circle
		(center 204.63637 -122.809762)
		(end 205.52537 -122.809762)
		(stroke
			(width 0.2)
			(type default)
		)
		(fill no)
		(layer "In6.Cu")
	)
	(gr_circle
		(center 204.63637 -122.047762)
		(end 205.52537 -122.047762)
		(stroke
			(width 0.2)
			(type default)
		)
		(fill no)
		(layer "In6.Cu")
	)
	(gr_circle
		(center 204.63637 -121.331736)
		(end 205.52537 -121.331736)
		(stroke
			(width 0.2)
			(type default)
		)
		(fill no)
		(layer "In6.Cu")
	)
	(gr_circle
		(center 204.63637 -120.569736)
		(end 205.52537 -120.569736)
		(stroke
			(width 0.2)
			(type default)
		)
		(fill no)
		(layer "In6.Cu")
	)
	(gr_circle
		(center 204.650086 -123.528328)
		(end 205.539086 -123.528328)
		(stroke
			(width 0.2)
			(type default)
		)
		(fill no)
		(layer "In6.Cu")
	)
	(gr_circle
		(center 205.314042 -105.896664)
		(end 206.203042 -105.896664)
		(stroke
			(width 0.2)
			(type default)
		)
		(fill no)
		(layer "In6.Cu")
	)
	(gr_circle
		(center 205.314042 -105.134664)
		(end 206.203042 -105.134664)
		(stroke
			(width 0.2)
			(type default)
		)
		(fill no)
		(layer "In6.Cu")
	)
	(gr_circle
		(center 205.314042 -104.4321)
		(end 206.203042 -104.4321)
		(stroke
			(width 0.2)
			(type default)
		)
		(fill no)
		(layer "In6.Cu")
	)
	(gr_circle
		(center 205.314042 -103.6701)
		(end 206.203042 -103.6701)
		(stroke
			(width 0.2)
			(type default)
		)
		(fill no)
		(layer "In6.Cu")
	)
	(gr_circle
		(center 205.314042 -102.9081)
		(end 206.203042 -102.9081)
		(stroke
			(width 0.2)
			(type default)
		)
		(fill no)
		(layer "In6.Cu")
	)
	(gr_circle
		(center 205.39837 -122.809762)
		(end 206.28737 -122.809762)
		(stroke
			(width 0.2)
			(type default)
		)
		(fill no)
		(layer "In6.Cu")
	)
	(gr_circle
		(center 205.39837 -122.047762)
		(end 206.28737 -122.047762)
		(stroke
			(width 0.2)
			(type default)
		)
		(fill no)
		(layer "In6.Cu")
	)
	(gr_circle
		(center 205.39837 -121.331736)
		(end 206.28737 -121.331736)
		(stroke
			(width 0.2)
			(type default)
		)
		(fill no)
		(layer "In6.Cu")
	)
	(gr_circle
		(center 205.39837 -120.569736)
		(end 206.28737 -120.569736)
		(stroke
			(width 0.2)
			(type default)
		)
		(fill no)
		(layer "In6.Cu")
	)
	(gr_circle
		(center 205.412086 -123.528328)
		(end 206.301086 -123.528328)
		(stroke
			(width 0.2)
			(type default)
		)
		(fill no)
		(layer "In6.Cu")
	)
	(gr_circle
		(center 206.076042 -105.896664)
		(end 206.965042 -105.896664)
		(stroke
			(width 0.2)
			(type default)
		)
		(fill no)
		(layer "In6.Cu")
	)
	(gr_circle
		(center 206.076042 -105.134664)
		(end 206.965042 -105.134664)
		(stroke
			(width 0.2)
			(type default)
		)
		(fill no)
		(layer "In6.Cu")
	)
	(gr_circle
		(center 206.076042 -104.4321)
		(end 206.965042 -104.4321)
		(stroke
			(width 0.2)
			(type default)
		)
		(fill no)
		(layer "In6.Cu")
	)
	(gr_circle
		(center 206.076042 -103.6701)
		(end 206.965042 -103.6701)
		(stroke
			(width 0.2)
			(type default)
		)
		(fill no)
		(layer "In6.Cu")
	)
	(gr_circle
		(center 206.076042 -102.9081)
		(end 206.965042 -102.9081)
		(stroke
			(width 0.2)
			(type default)
		)
		(fill no)
		(layer "In6.Cu")
	)
	(gr_circle
		(center 206.16037 -122.809762)
		(end 207.04937 -122.809762)
		(stroke
			(width 0.2)
			(type default)
		)
		(fill no)
		(layer "In6.Cu")
	)
	(gr_circle
		(center 206.16037 -122.047762)
		(end 207.04937 -122.047762)
		(stroke
			(width 0.2)
			(type default)
		)
		(fill no)
		(layer "In6.Cu")
	)
	(gr_circle
		(center 206.16037 -121.331736)
		(end 207.04937 -121.331736)
		(stroke
			(width 0.2)
			(type default)
		)
		(fill no)
		(layer "In6.Cu")
	)
	(gr_circle
		(center 206.16037 -120.569736)
		(end 207.04937 -120.569736)
		(stroke
			(width 0.2)
			(type default)
		)
		(fill no)
		(layer "In6.Cu")
	)
	(gr_circle
		(center 206.174086 -123.528328)
		(end 207.063086 -123.528328)
		(stroke
			(width 0.2)
			(type default)
		)
		(fill no)
		(layer "In6.Cu")
	)
	(gr_circle
		(center 206.838042 -105.896664)
		(end 207.727042 -105.896664)
		(stroke
			(width 0.2)
			(type default)
		)
		(fill no)
		(layer "In6.Cu")
	)
	(gr_circle
		(center 206.838042 -105.134664)
		(end 207.727042 -105.134664)
		(stroke
			(width 0.2)
			(type default)
		)
		(fill no)
		(layer "In6.Cu")
	)
	(gr_circle
		(center 206.838042 -104.4321)
		(end 207.727042 -104.4321)
		(stroke
			(width 0.2)
			(type default)
		)
		(fill no)
		(layer "In6.Cu")
	)
	(gr_circle
		(center 206.838042 -103.6701)
		(end 207.727042 -103.6701)
		(stroke
			(width 0.2)
			(type default)
		)
		(fill no)
		(layer "In6.Cu")
	)
	(gr_circle
		(center 206.838042 -102.9081)
		(end 207.727042 -102.9081)
		(stroke
			(width 0.2)
			(type default)
		)
		(fill no)
		(layer "In6.Cu")
	)
	(gr_circle
		(center 206.92237 -122.809762)
		(end 207.81137 -122.809762)
		(stroke
			(width 0.2)
			(type default)
		)
		(fill no)
		(layer "In6.Cu")
	)
	(gr_circle
		(center 206.92237 -122.047762)
		(end 207.81137 -122.047762)
		(stroke
			(width 0.2)
			(type default)
		)
		(fill no)
		(layer "In6.Cu")
	)
	(gr_circle
		(center 206.92237 -121.331736)
		(end 207.81137 -121.331736)
		(stroke
			(width 0.2)
			(type default)
		)
		(fill no)
		(layer "In6.Cu")
	)
	(gr_circle
		(center 206.92237 -120.569736)
		(end 207.81137 -120.569736)
		(stroke
			(width 0.2)
			(type default)
		)
		(fill no)
		(layer "In6.Cu")
	)
	(gr_circle
		(center 206.936086 -123.528328)
		(end 207.825086 -123.528328)
		(stroke
			(width 0.2)
			(type default)
		)
		(fill no)
		(layer "In6.Cu")
	)
	(gr_circle
		(center 207.556862 -105.882948)
		(end 208.445862 -105.882948)
		(stroke
			(width 0.2)
			(type default)
		)
		(fill no)
		(layer "In6.Cu")
	)
	(gr_circle
		(center 207.556862 -105.120948)
		(end 208.445862 -105.120948)
		(stroke
			(width 0.2)
			(type default)
		)
		(fill no)
		(layer "In6.Cu")
	)
	(gr_circle
		(center 207.556862 -104.418384)
		(end 208.445862 -104.418384)
		(stroke
			(width 0.2)
			(type default)
		)
		(fill no)
		(layer "In6.Cu")
	)
	(gr_circle
		(center 207.556862 -103.656384)
		(end 208.445862 -103.656384)
		(stroke
			(width 0.2)
			(type default)
		)
		(fill no)
		(layer "In6.Cu")
	)
	(gr_circle
		(center 207.556862 -102.894384)
		(end 208.445862 -102.894384)
		(stroke
			(width 0.2)
			(type default)
		)
		(fill no)
		(layer "In6.Cu")
	)
	(gr_circle
		(center 207.68437 -122.809762)
		(end 208.57337 -122.809762)
		(stroke
			(width 0.2)
			(type default)
		)
		(fill no)
		(layer "In6.Cu")
	)
	(gr_circle
		(center 207.68437 -122.047762)
		(end 208.57337 -122.047762)
		(stroke
			(width 0.2)
			(type default)
		)
		(fill no)
		(layer "In6.Cu")
	)
	(gr_circle
		(center 207.68437 -121.331736)
		(end 208.57337 -121.331736)
		(stroke
			(width 0.2)
			(type default)
		)
		(fill no)
		(layer "In6.Cu")
	)
	(gr_circle
		(center 207.68437 -120.569736)
		(end 208.57337 -120.569736)
		(stroke
			(width 0.2)
			(type default)
		)
		(fill no)
		(layer "In6.Cu")
	)
	(gr_circle
		(center 207.698086 -123.528328)
		(end 208.587086 -123.528328)
		(stroke
			(width 0.2)
			(type default)
		)
		(fill no)
		(layer "In6.Cu")
	)
	(gr_circle
		(center 209.291174 -60.96)
		(end 210.688174 -60.96)
		(stroke
			(width 0.2)
			(type default)
		)
		(fill no)
		(layer "In6.Cu")
	)
	(gr_circle
		(center 213.978236 -132.959856)
		(end 214.867236 -132.959856)
		(stroke
			(width 0.2)
			(type default)
		)
		(fill no)
		(layer "In6.Cu")
	)
	(gr_circle
		(center 213.978236 -132.197856)
		(end 214.867236 -132.197856)
		(stroke
			(width 0.2)
			(type default)
		)
		(fill no)
		(layer "In6.Cu")
	)
	(gr_circle
		(center 213.978236 -131.435856)
		(end 214.867236 -131.435856)
		(stroke
			(width 0.2)
			(type default)
		)
		(fill no)
		(layer "In6.Cu")
	)
	(gr_circle
		(center 213.978236 -130.673856)
		(end 214.867236 -130.673856)
		(stroke
			(width 0.2)
			(type default)
		)
		(fill no)
		(layer "In6.Cu")
	)
	(gr_circle
		(center 213.978236 -129.911856)
		(end 214.867236 -129.911856)
		(stroke
			(width 0.2)
			(type default)
		)
		(fill no)
		(layer "In6.Cu")
	)
	(gr_circle
		(center 213.978236 -129.149856)
		(end 214.867236 -129.149856)
		(stroke
			(width 0.2)
			(type default)
		)
		(fill no)
		(layer "In6.Cu")
	)
	(gr_circle
		(center 213.978236 -128.387856)
		(end 214.867236 -128.387856)
		(stroke
			(width 0.2)
			(type default)
		)
		(fill no)
		(layer "In6.Cu")
	)
	(gr_circle
		(center 213.978236 -127.625856)
		(end 214.867236 -127.625856)
		(stroke
			(width 0.2)
			(type default)
		)
		(fill no)
		(layer "In6.Cu")
	)
	(gr_circle
		(center 214.696802 -132.94614)
		(end 215.585802 -132.94614)
		(stroke
			(width 0.2)
			(type default)
		)
		(fill no)
		(layer "In6.Cu")
	)
	(gr_circle
		(center 214.696802 -132.18414)
		(end 215.585802 -132.18414)
		(stroke
			(width 0.2)
			(type default)
		)
		(fill no)
		(layer "In6.Cu")
	)
	(gr_circle
		(center 214.696802 -131.42214)
		(end 215.585802 -131.42214)
		(stroke
			(width 0.2)
			(type default)
		)
		(fill no)
		(layer "In6.Cu")
	)
	(gr_circle
		(center 214.696802 -130.66014)
		(end 215.585802 -130.66014)
		(stroke
			(width 0.2)
			(type default)
		)
		(fill no)
		(layer "In6.Cu")
	)
	(gr_circle
		(center 214.696802 -129.89814)
		(end 215.585802 -129.89814)
		(stroke
			(width 0.2)
			(type default)
		)
		(fill no)
		(layer "In6.Cu")
	)
	(gr_circle
		(center 214.696802 -129.13614)
		(end 215.585802 -129.13614)
		(stroke
			(width 0.2)
			(type default)
		)
		(fill no)
		(layer "In6.Cu")
	)
	(gr_circle
		(center 214.696802 -128.37414)
		(end 215.585802 -128.37414)
		(stroke
			(width 0.2)
			(type default)
		)
		(fill no)
		(layer "In6.Cu")
	)
	(gr_circle
		(center 214.696802 -127.61214)
		(end 215.585802 -127.61214)
		(stroke
			(width 0.2)
			(type default)
		)
		(fill no)
		(layer "In6.Cu")
	)
	(gr_circle
		(center 215.23706 -98.013012)
		(end 216.12606 -98.013012)
		(stroke
			(width 0.2)
			(type default)
		)
		(fill no)
		(layer "In6.Cu")
	)
	(gr_circle
		(center 215.458802 -132.94614)
		(end 216.347802 -132.94614)
		(stroke
			(width 0.2)
			(type default)
		)
		(fill no)
		(layer "In6.Cu")
	)
	(gr_circle
		(center 215.458802 -132.18414)
		(end 216.347802 -132.18414)
		(stroke
			(width 0.2)
			(type default)
		)
		(fill no)
		(layer "In6.Cu")
	)
	(gr_circle
		(center 215.458802 -131.42214)
		(end 216.347802 -131.42214)
		(stroke
			(width 0.2)
			(type default)
		)
		(fill no)
		(layer "In6.Cu")
	)
	(gr_circle
		(center 215.458802 -130.66014)
		(end 216.347802 -130.66014)
		(stroke
			(width 0.2)
			(type default)
		)
		(fill no)
		(layer "In6.Cu")
	)
	(gr_circle
		(center 215.458802 -129.89814)
		(end 216.347802 -129.89814)
		(stroke
			(width 0.2)
			(type default)
		)
		(fill no)
		(layer "In6.Cu")
	)
	(gr_circle
		(center 215.458802 -129.13614)
		(end 216.347802 -129.13614)
		(stroke
			(width 0.2)
			(type default)
		)
		(fill no)
		(layer "In6.Cu")
	)
	(gr_circle
		(center 215.458802 -128.37414)
		(end 216.347802 -128.37414)
		(stroke
			(width 0.2)
			(type default)
		)
		(fill no)
		(layer "In6.Cu")
	)
	(gr_circle
		(center 215.458802 -127.61214)
		(end 216.347802 -127.61214)
		(stroke
			(width 0.2)
			(type default)
		)
		(fill no)
		(layer "In6.Cu")
	)
	(gr_circle
		(center 215.646 -101.346)
		(end 216.535 -101.346)
		(stroke
			(width 0.2)
			(type default)
		)
		(fill no)
		(layer "In6.Cu")
	)
	(gr_circle
		(center 215.99906 -98.013012)
		(end 216.88806 -98.013012)
		(stroke
			(width 0.2)
			(type default)
		)
		(fill no)
		(layer "In6.Cu")
	)
	(gr_circle
		(center 216.174828 -132.94614)
		(end 217.063828 -132.94614)
		(stroke
			(width 0.2)
			(type default)
		)
		(fill no)
		(layer "In6.Cu")
	)
	(gr_circle
		(center 216.174828 -132.18414)
		(end 217.063828 -132.18414)
		(stroke
			(width 0.2)
			(type default)
		)
		(fill no)
		(layer "In6.Cu")
	)
	(gr_circle
		(center 216.174828 -131.42214)
		(end 217.063828 -131.42214)
		(stroke
			(width 0.2)
			(type default)
		)
		(fill no)
		(layer "In6.Cu")
	)
	(gr_circle
		(center 216.174828 -130.66014)
		(end 217.063828 -130.66014)
		(stroke
			(width 0.2)
			(type default)
		)
		(fill no)
		(layer "In6.Cu")
	)
	(gr_circle
		(center 216.174828 -129.89814)
		(end 217.063828 -129.89814)
		(stroke
			(width 0.2)
			(type default)
		)
		(fill no)
		(layer "In6.Cu")
	)
	(gr_circle
		(center 216.174828 -129.13614)
		(end 217.063828 -129.13614)
		(stroke
			(width 0.2)
			(type default)
		)
		(fill no)
		(layer "In6.Cu")
	)
	(gr_circle
		(center 216.174828 -128.37414)
		(end 217.063828 -128.37414)
		(stroke
			(width 0.2)
			(type default)
		)
		(fill no)
		(layer "In6.Cu")
	)
	(gr_circle
		(center 216.174828 -127.61214)
		(end 217.063828 -127.61214)
		(stroke
			(width 0.2)
			(type default)
		)
		(fill no)
		(layer "In6.Cu")
	)
	(gr_circle
		(center 216.727278 -122.809762)
		(end 217.616278 -122.809762)
		(stroke
			(width 0.2)
			(type default)
		)
		(fill no)
		(layer "In6.Cu")
	)
	(gr_circle
		(center 216.727278 -122.047762)
		(end 217.616278 -122.047762)
		(stroke
			(width 0.2)
			(type default)
		)
		(fill no)
		(layer "In6.Cu")
	)
	(gr_circle
		(center 216.727278 -121.331736)
		(end 217.616278 -121.331736)
		(stroke
			(width 0.2)
			(type default)
		)
		(fill no)
		(layer "In6.Cu")
	)
	(gr_circle
		(center 216.727278 -120.569736)
		(end 217.616278 -120.569736)
		(stroke
			(width 0.2)
			(type default)
		)
		(fill no)
		(layer "In6.Cu")
	)
	(gr_circle
		(center 216.740994 -123.528328)
		(end 217.629994 -123.528328)
		(stroke
			(width 0.2)
			(type default)
		)
		(fill no)
		(layer "In6.Cu")
	)
	(gr_circle
		(center 216.819226 -105.883202)
		(end 217.708226 -105.883202)
		(stroke
			(width 0.2)
			(type default)
		)
		(fill no)
		(layer "In6.Cu")
	)
	(gr_circle
		(center 216.819226 -105.121202)
		(end 217.708226 -105.121202)
		(stroke
			(width 0.2)
			(type default)
		)
		(fill no)
		(layer "In6.Cu")
	)
	(gr_circle
		(center 216.819226 -104.418638)
		(end 217.708226 -104.418638)
		(stroke
			(width 0.2)
			(type default)
		)
		(fill no)
		(layer "In6.Cu")
	)
	(gr_circle
		(center 216.819226 -103.656638)
		(end 217.708226 -103.656638)
		(stroke
			(width 0.2)
			(type default)
		)
		(fill no)
		(layer "In6.Cu")
	)
	(gr_circle
		(center 216.819226 -102.894638)
		(end 217.708226 -102.894638)
		(stroke
			(width 0.2)
			(type default)
		)
		(fill no)
		(layer "In6.Cu")
	)
	(gr_circle
		(center 216.936828 -132.94614)
		(end 217.825828 -132.94614)
		(stroke
			(width 0.2)
			(type default)
		)
		(fill no)
		(layer "In6.Cu")
	)
	(gr_circle
		(center 216.936828 -132.18414)
		(end 217.825828 -132.18414)
		(stroke
			(width 0.2)
			(type default)
		)
		(fill no)
		(layer "In6.Cu")
	)
	(gr_circle
		(center 216.936828 -131.42214)
		(end 217.825828 -131.42214)
		(stroke
			(width 0.2)
			(type default)
		)
		(fill no)
		(layer "In6.Cu")
	)
	(gr_circle
		(center 216.936828 -130.66014)
		(end 217.825828 -130.66014)
		(stroke
			(width 0.2)
			(type default)
		)
		(fill no)
		(layer "In6.Cu")
	)
	(gr_circle
		(center 216.936828 -129.89814)
		(end 217.825828 -129.89814)
		(stroke
			(width 0.2)
			(type default)
		)
		(fill no)
		(layer "In6.Cu")
	)
	(gr_circle
		(center 216.936828 -129.13614)
		(end 217.825828 -129.13614)
		(stroke
			(width 0.2)
			(type default)
		)
		(fill no)
		(layer "In6.Cu")
	)
	(gr_circle
		(center 216.936828 -128.37414)
		(end 217.825828 -128.37414)
		(stroke
			(width 0.2)
			(type default)
		)
		(fill no)
		(layer "In6.Cu")
	)
	(gr_circle
		(center 216.936828 -127.61214)
		(end 217.825828 -127.61214)
		(stroke
			(width 0.2)
			(type default)
		)
		(fill no)
		(layer "In6.Cu")
	)
	(gr_circle
		(center 217.488262 -98.013012)
		(end 218.377262 -98.013012)
		(stroke
			(width 0.2)
			(type default)
		)
		(fill no)
		(layer "In6.Cu")
	)
	(gr_circle
		(center 217.489278 -122.809762)
		(end 218.378278 -122.809762)
		(stroke
			(width 0.2)
			(type default)
		)
		(fill no)
		(layer "In6.Cu")
	)
	(gr_circle
		(center 217.489278 -122.047762)
		(end 218.378278 -122.047762)
		(stroke
			(width 0.2)
			(type default)
		)
		(fill no)
		(layer "In6.Cu")
	)
	(gr_circle
		(center 217.489278 -121.331736)
		(end 218.378278 -121.331736)
		(stroke
			(width 0.2)
			(type default)
		)
		(fill no)
		(layer "In6.Cu")
	)
	(gr_circle
		(center 217.489278 -120.569736)
		(end 218.378278 -120.569736)
		(stroke
			(width 0.2)
			(type default)
		)
		(fill no)
		(layer "In6.Cu")
	)
	(gr_circle
		(center 217.502994 -123.528328)
		(end 218.391994 -123.528328)
		(stroke
			(width 0.2)
			(type default)
		)
		(fill no)
		(layer "In6.Cu")
	)
	(gr_circle
		(center 217.510868 -105.896664)
		(end 218.399868 -105.896664)
		(stroke
			(width 0.2)
			(type default)
		)
		(fill no)
		(layer "In6.Cu")
	)
	(gr_circle
		(center 217.510868 -105.134664)
		(end 218.399868 -105.134664)
		(stroke
			(width 0.2)
			(type default)
		)
		(fill no)
		(layer "In6.Cu")
	)
	(gr_circle
		(center 217.510868 -104.4321)
		(end 218.399868 -104.4321)
		(stroke
			(width 0.2)
			(type default)
		)
		(fill no)
		(layer "In6.Cu")
	)
	(gr_circle
		(center 217.510868 -103.6701)
		(end 218.399868 -103.6701)
		(stroke
			(width 0.2)
			(type default)
		)
		(fill no)
		(layer "In6.Cu")
	)
	(gr_circle
		(center 217.510868 -102.9081)
		(end 218.399868 -102.9081)
		(stroke
			(width 0.2)
			(type default)
		)
		(fill no)
		(layer "In6.Cu")
	)
	(gr_circle
		(center 218.250262 -98.013012)
		(end 219.139262 -98.013012)
		(stroke
			(width 0.2)
			(type default)
		)
		(fill no)
		(layer "In6.Cu")
	)
	(gr_circle
		(center 218.251278 -122.809762)
		(end 219.140278 -122.809762)
		(stroke
			(width 0.2)
			(type default)
		)
		(fill no)
		(layer "In6.Cu")
	)
	(gr_circle
		(center 218.251278 -122.047762)
		(end 219.140278 -122.047762)
		(stroke
			(width 0.2)
			(type default)
		)
		(fill no)
		(layer "In6.Cu")
	)
	(gr_circle
		(center 218.251278 -121.331736)
		(end 219.140278 -121.331736)
		(stroke
			(width 0.2)
			(type default)
		)
		(fill no)
		(layer "In6.Cu")
	)
	(gr_circle
		(center 218.251278 -120.569736)
		(end 219.140278 -120.569736)
		(stroke
			(width 0.2)
			(type default)
		)
		(fill no)
		(layer "In6.Cu")
	)
	(gr_circle
		(center 218.264994 -123.528328)
		(end 219.153994 -123.528328)
		(stroke
			(width 0.2)
			(type default)
		)
		(fill no)
		(layer "In6.Cu")
	)
	(gr_circle
		(center 218.272868 -105.896664)
		(end 219.161868 -105.896664)
		(stroke
			(width 0.2)
			(type default)
		)
		(fill no)
		(layer "In6.Cu")
	)
	(gr_circle
		(center 218.272868 -105.134664)
		(end 219.161868 -105.134664)
		(stroke
			(width 0.2)
			(type default)
		)
		(fill no)
		(layer "In6.Cu")
	)
	(gr_circle
		(center 218.272868 -104.4321)
		(end 219.161868 -104.4321)
		(stroke
			(width 0.2)
			(type default)
		)
		(fill no)
		(layer "In6.Cu")
	)
	(gr_circle
		(center 218.272868 -103.6701)
		(end 219.161868 -103.6701)
		(stroke
			(width 0.2)
			(type default)
		)
		(fill no)
		(layer "In6.Cu")
	)
	(gr_circle
		(center 218.272868 -102.9081)
		(end 219.161868 -102.9081)
		(stroke
			(width 0.2)
			(type default)
		)
		(fill no)
		(layer "In6.Cu")
	)
	(gr_circle
		(center 219.013278 -122.809762)
		(end 219.902278 -122.809762)
		(stroke
			(width 0.2)
			(type default)
		)
		(fill no)
		(layer "In6.Cu")
	)
	(gr_circle
		(center 219.013278 -122.047762)
		(end 219.902278 -122.047762)
		(stroke
			(width 0.2)
			(type default)
		)
		(fill no)
		(layer "In6.Cu")
	)
	(gr_circle
		(center 219.013278 -121.331736)
		(end 219.902278 -121.331736)
		(stroke
			(width 0.2)
			(type default)
		)
		(fill no)
		(layer "In6.Cu")
	)
	(gr_circle
		(center 219.013278 -120.569736)
		(end 219.902278 -120.569736)
		(stroke
			(width 0.2)
			(type default)
		)
		(fill no)
		(layer "In6.Cu")
	)
	(gr_circle
		(center 219.026994 -123.528328)
		(end 219.915994 -123.528328)
		(stroke
			(width 0.2)
			(type default)
		)
		(fill no)
		(layer "In6.Cu")
	)
	(gr_circle
		(center 219.034868 -105.896664)
		(end 219.923868 -105.896664)
		(stroke
			(width 0.2)
			(type default)
		)
		(fill no)
		(layer "In6.Cu")
	)
	(gr_circle
		(center 219.034868 -105.134664)
		(end 219.923868 -105.134664)
		(stroke
			(width 0.2)
			(type default)
		)
		(fill no)
		(layer "In6.Cu")
	)
	(gr_circle
		(center 219.034868 -104.4321)
		(end 219.923868 -104.4321)
		(stroke
			(width 0.2)
			(type default)
		)
		(fill no)
		(layer "In6.Cu")
	)
	(gr_circle
		(center 219.034868 -103.6701)
		(end 219.923868 -103.6701)
		(stroke
			(width 0.2)
			(type default)
		)
		(fill no)
		(layer "In6.Cu")
	)
	(gr_circle
		(center 219.034868 -102.9081)
		(end 219.923868 -102.9081)
		(stroke
			(width 0.2)
			(type default)
		)
		(fill no)
		(layer "In6.Cu")
	)
	(gr_circle
		(center 219.775278 -122.809762)
		(end 220.664278 -122.809762)
		(stroke
			(width 0.2)
			(type default)
		)
		(fill no)
		(layer "In6.Cu")
	)
	(gr_circle
		(center 219.775278 -122.047762)
		(end 220.664278 -122.047762)
		(stroke
			(width 0.2)
			(type default)
		)
		(fill no)
		(layer "In6.Cu")
	)
	(gr_circle
		(center 219.775278 -121.331736)
		(end 220.664278 -121.331736)
		(stroke
			(width 0.2)
			(type default)
		)
		(fill no)
		(layer "In6.Cu")
	)
	(gr_circle
		(center 219.775278 -120.569736)
		(end 220.664278 -120.569736)
		(stroke
			(width 0.2)
			(type default)
		)
		(fill no)
		(layer "In6.Cu")
	)
	(gr_circle
		(center 219.788994 -123.528328)
		(end 220.677994 -123.528328)
		(stroke
			(width 0.2)
			(type default)
		)
		(fill no)
		(layer "In6.Cu")
	)
	(gr_circle
		(center 219.796868 -105.896664)
		(end 220.685868 -105.896664)
		(stroke
			(width 0.2)
			(type default)
		)
		(fill no)
		(layer "In6.Cu")
	)
	(gr_circle
		(center 219.796868 -105.134664)
		(end 220.685868 -105.134664)
		(stroke
			(width 0.2)
			(type default)
		)
		(fill no)
		(layer "In6.Cu")
	)
	(gr_circle
		(center 219.796868 -104.4321)
		(end 220.685868 -104.4321)
		(stroke
			(width 0.2)
			(type default)
		)
		(fill no)
		(layer "In6.Cu")
	)
	(gr_circle
		(center 219.796868 -103.6701)
		(end 220.685868 -103.6701)
		(stroke
			(width 0.2)
			(type default)
		)
		(fill no)
		(layer "In6.Cu")
	)
	(gr_circle
		(center 219.796868 -102.9081)
		(end 220.685868 -102.9081)
		(stroke
			(width 0.2)
			(type default)
		)
		(fill no)
		(layer "In6.Cu")
	)
	(gr_circle
		(center 219.847668 -97.985834)
		(end 220.736668 -97.985834)
		(stroke
			(width 0.2)
			(type default)
		)
		(fill no)
		(layer "In6.Cu")
	)
	(gr_circle
		(center 220.537278 -122.809762)
		(end 221.426278 -122.809762)
		(stroke
			(width 0.2)
			(type default)
		)
		(fill no)
		(layer "In6.Cu")
	)
	(gr_circle
		(center 220.537278 -122.047762)
		(end 221.426278 -122.047762)
		(stroke
			(width 0.2)
			(type default)
		)
		(fill no)
		(layer "In6.Cu")
	)
	(gr_circle
		(center 220.537278 -121.331736)
		(end 221.426278 -121.331736)
		(stroke
			(width 0.2)
			(type default)
		)
		(fill no)
		(layer "In6.Cu")
	)
	(gr_circle
		(center 220.537278 -120.569736)
		(end 221.426278 -120.569736)
		(stroke
			(width 0.2)
			(type default)
		)
		(fill no)
		(layer "In6.Cu")
	)
	(gr_circle
		(center 220.550994 -123.528328)
		(end 221.439994 -123.528328)
		(stroke
			(width 0.2)
			(type default)
		)
		(fill no)
		(layer "In6.Cu")
	)
	(gr_circle
		(center 220.558868 -105.896664)
		(end 221.447868 -105.896664)
		(stroke
			(width 0.2)
			(type default)
		)
		(fill no)
		(layer "In6.Cu")
	)
	(gr_circle
		(center 220.558868 -105.134664)
		(end 221.447868 -105.134664)
		(stroke
			(width 0.2)
			(type default)
		)
		(fill no)
		(layer "In6.Cu")
	)
	(gr_circle
		(center 220.558868 -104.4321)
		(end 221.447868 -104.4321)
		(stroke
			(width 0.2)
			(type default)
		)
		(fill no)
		(layer "In6.Cu")
	)
	(gr_circle
		(center 220.558868 -103.6701)
		(end 221.447868 -103.6701)
		(stroke
			(width 0.2)
			(type default)
		)
		(fill no)
		(layer "In6.Cu")
	)
	(gr_circle
		(center 220.558868 -102.9081)
		(end 221.447868 -102.9081)
		(stroke
			(width 0.2)
			(type default)
		)
		(fill no)
		(layer "In6.Cu")
	)
	(gr_circle
		(center 220.609668 -97.985834)
		(end 221.498668 -97.985834)
		(stroke
			(width 0.2)
			(type default)
		)
		(fill no)
		(layer "In6.Cu")
	)
	(gr_circle
		(center 221.299278 -122.809762)
		(end 222.188278 -122.809762)
		(stroke
			(width 0.2)
			(type default)
		)
		(fill no)
		(layer "In6.Cu")
	)
	(gr_circle
		(center 221.299278 -122.047762)
		(end 222.188278 -122.047762)
		(stroke
			(width 0.2)
			(type default)
		)
		(fill no)
		(layer "In6.Cu")
	)
	(gr_circle
		(center 221.299278 -121.331736)
		(end 222.188278 -121.331736)
		(stroke
			(width 0.2)
			(type default)
		)
		(fill no)
		(layer "In6.Cu")
	)
	(gr_circle
		(center 221.299278 -120.569736)
		(end 222.188278 -120.569736)
		(stroke
			(width 0.2)
			(type default)
		)
		(fill no)
		(layer "In6.Cu")
	)
	(gr_circle
		(center 221.312994 -123.528328)
		(end 222.201994 -123.528328)
		(stroke
			(width 0.2)
			(type default)
		)
		(fill no)
		(layer "In6.Cu")
	)
	(gr_circle
		(center 221.320868 -105.896664)
		(end 222.209868 -105.896664)
		(stroke
			(width 0.2)
			(type default)
		)
		(fill no)
		(layer "In6.Cu")
	)
	(gr_circle
		(center 221.320868 -105.134664)
		(end 222.209868 -105.134664)
		(stroke
			(width 0.2)
			(type default)
		)
		(fill no)
		(layer "In6.Cu")
	)
	(gr_circle
		(center 221.320868 -104.4321)
		(end 222.209868 -104.4321)
		(stroke
			(width 0.2)
			(type default)
		)
		(fill no)
		(layer "In6.Cu")
	)
	(gr_circle
		(center 221.320868 -103.6701)
		(end 222.209868 -103.6701)
		(stroke
			(width 0.2)
			(type default)
		)
		(fill no)
		(layer "In6.Cu")
	)
	(gr_circle
		(center 221.320868 -102.9081)
		(end 222.209868 -102.9081)
		(stroke
			(width 0.2)
			(type default)
		)
		(fill no)
		(layer "In6.Cu")
	)
	(gr_circle
		(center 222.039688 -105.882948)
		(end 222.928688 -105.882948)
		(stroke
			(width 0.2)
			(type default)
		)
		(fill no)
		(layer "In6.Cu")
	)
	(gr_circle
		(center 222.039688 -105.120948)
		(end 222.928688 -105.120948)
		(stroke
			(width 0.2)
			(type default)
		)
		(fill no)
		(layer "In6.Cu")
	)
	(gr_circle
		(center 222.039688 -104.418384)
		(end 222.928688 -104.418384)
		(stroke
			(width 0.2)
			(type default)
		)
		(fill no)
		(layer "In6.Cu")
	)
	(gr_circle
		(center 222.039688 -103.656384)
		(end 222.928688 -103.656384)
		(stroke
			(width 0.2)
			(type default)
		)
		(fill no)
		(layer "In6.Cu")
	)
	(gr_circle
		(center 222.039688 -102.894384)
		(end 222.928688 -102.894384)
		(stroke
			(width 0.2)
			(type default)
		)
		(fill no)
		(layer "In6.Cu")
	)
	(gr_circle
		(center 222.061278 -122.809762)
		(end 222.950278 -122.809762)
		(stroke
			(width 0.2)
			(type default)
		)
		(fill no)
		(layer "In6.Cu")
	)
	(gr_circle
		(center 222.061278 -122.047762)
		(end 222.950278 -122.047762)
		(stroke
			(width 0.2)
			(type default)
		)
		(fill no)
		(layer "In6.Cu")
	)
	(gr_circle
		(center 222.061278 -121.331736)
		(end 222.950278 -121.331736)
		(stroke
			(width 0.2)
			(type default)
		)
		(fill no)
		(layer "In6.Cu")
	)
	(gr_circle
		(center 222.061278 -120.569736)
		(end 222.950278 -120.569736)
		(stroke
			(width 0.2)
			(type default)
		)
		(fill no)
		(layer "In6.Cu")
	)
	(gr_circle
		(center 222.074994 -123.528328)
		(end 222.963994 -123.528328)
		(stroke
			(width 0.2)
			(type default)
		)
		(fill no)
		(layer "In6.Cu")
	)
	(gr_circle
		(center 222.09887 -97.985834)
		(end 222.98787 -97.985834)
		(stroke
			(width 0.2)
			(type default)
		)
		(fill no)
		(layer "In6.Cu")
	)
	(gr_circle
		(center 222.86087 -97.985834)
		(end 223.74987 -97.985834)
		(stroke
			(width 0.2)
			(type default)
		)
		(fill no)
		(layer "In6.Cu")
	)
	(gr_circle
		(center 224.593912 -97.985834)
		(end 225.482912 -97.985834)
		(stroke
			(width 0.2)
			(type default)
		)
		(fill no)
		(layer "In6.Cu")
	)
	(gr_circle
		(center 225.355912 -97.985834)
		(end 226.244912 -97.985834)
		(stroke
			(width 0.2)
			(type default)
		)
		(fill no)
		(layer "In6.Cu")
	)
	(gr_circle
		(center 226.845114 -97.985834)
		(end 227.734114 -97.985834)
		(stroke
			(width 0.2)
			(type default)
		)
		(fill no)
		(layer "In6.Cu")
	)
	(gr_circle
		(center 227.607114 -97.985834)
		(end 228.496114 -97.985834)
		(stroke
			(width 0.2)
			(type default)
		)
		(fill no)
		(layer "In6.Cu")
	)
	(gr_circle
		(center 229.530148 -98.012758)
		(end 230.419148 -98.012758)
		(stroke
			(width 0.2)
			(type default)
		)
		(fill no)
		(layer "In6.Cu")
	)
	(gr_circle
		(center 230.292148 -98.012758)
		(end 231.181148 -98.012758)
		(stroke
			(width 0.2)
			(type default)
		)
		(fill no)
		(layer "In6.Cu")
	)
	(gr_circle
		(center 231.591104 -131.110736)
		(end 232.480104 -131.110736)
		(stroke
			(width 0.2)
			(type default)
		)
		(fill no)
		(layer "In6.Cu")
	)
	(gr_circle
		(center 231.591104 -130.348736)
		(end 232.480104 -130.348736)
		(stroke
			(width 0.2)
			(type default)
		)
		(fill no)
		(layer "In6.Cu")
	)
	(gr_circle
		(center 231.591104 -129.586736)
		(end 232.480104 -129.586736)
		(stroke
			(width 0.2)
			(type default)
		)
		(fill no)
		(layer "In6.Cu")
	)
	(gr_circle
		(center 231.591104 -128.824736)
		(end 232.480104 -128.824736)
		(stroke
			(width 0.2)
			(type default)
		)
		(fill no)
		(layer "In6.Cu")
	)
	(gr_circle
		(center 231.591104 -128.062736)
		(end 232.480104 -128.062736)
		(stroke
			(width 0.2)
			(type default)
		)
		(fill no)
		(layer "In6.Cu")
	)
	(gr_circle
		(center 231.591104 -127.300736)
		(end 232.480104 -127.300736)
		(stroke
			(width 0.2)
			(type default)
		)
		(fill no)
		(layer "In6.Cu")
	)
	(gr_circle
		(center 231.604566 -126.609094)
		(end 232.493566 -126.609094)
		(stroke
			(width 0.2)
			(type default)
		)
		(fill no)
		(layer "In6.Cu")
	)
	(gr_circle
		(center 231.60482 -131.829556)
		(end 232.49382 -131.829556)
		(stroke
			(width 0.2)
			(type default)
		)
		(fill no)
		(layer "In6.Cu")
	)
	(gr_circle
		(center 231.78135 -98.012758)
		(end 232.67035 -98.012758)
		(stroke
			(width 0.2)
			(type default)
		)
		(fill no)
		(layer "In6.Cu")
	)
	(gr_circle
		(center 232.353104 -131.110736)
		(end 233.242104 -131.110736)
		(stroke
			(width 0.2)
			(type default)
		)
		(fill no)
		(layer "In6.Cu")
	)
	(gr_circle
		(center 232.353104 -130.348736)
		(end 233.242104 -130.348736)
		(stroke
			(width 0.2)
			(type default)
		)
		(fill no)
		(layer "In6.Cu")
	)
	(gr_circle
		(center 232.353104 -129.586736)
		(end 233.242104 -129.586736)
		(stroke
			(width 0.2)
			(type default)
		)
		(fill no)
		(layer "In6.Cu")
	)
	(gr_circle
		(center 232.353104 -128.824736)
		(end 233.242104 -128.824736)
		(stroke
			(width 0.2)
			(type default)
		)
		(fill no)
		(layer "In6.Cu")
	)
	(gr_circle
		(center 232.353104 -128.062736)
		(end 233.242104 -128.062736)
		(stroke
			(width 0.2)
			(type default)
		)
		(fill no)
		(layer "In6.Cu")
	)
	(gr_circle
		(center 232.353104 -127.300736)
		(end 233.242104 -127.300736)
		(stroke
			(width 0.2)
			(type default)
		)
		(fill no)
		(layer "In6.Cu")
	)
	(gr_circle
		(center 232.366566 -126.609094)
		(end 233.255566 -126.609094)
		(stroke
			(width 0.2)
			(type default)
		)
		(fill no)
		(layer "In6.Cu")
	)
	(gr_circle
		(center 232.36682 -131.829556)
		(end 233.25582 -131.829556)
		(stroke
			(width 0.2)
			(type default)
		)
		(fill no)
		(layer "In6.Cu")
	)
	(gr_circle
		(center 232.54335 -98.012758)
		(end 233.43235 -98.012758)
		(stroke
			(width 0.2)
			(type default)
		)
		(fill no)
		(layer "In6.Cu")
	)
	(gr_circle
		(center 233.055668 -131.110736)
		(end 233.944668 -131.110736)
		(stroke
			(width 0.2)
			(type default)
		)
		(fill no)
		(layer "In6.Cu")
	)
	(gr_circle
		(center 233.055668 -130.348736)
		(end 233.944668 -130.348736)
		(stroke
			(width 0.2)
			(type default)
		)
		(fill no)
		(layer "In6.Cu")
	)
	(gr_circle
		(center 233.055668 -129.586736)
		(end 233.944668 -129.586736)
		(stroke
			(width 0.2)
			(type default)
		)
		(fill no)
		(layer "In6.Cu")
	)
	(gr_circle
		(center 233.055668 -128.824736)
		(end 233.944668 -128.824736)
		(stroke
			(width 0.2)
			(type default)
		)
		(fill no)
		(layer "In6.Cu")
	)
	(gr_circle
		(center 233.055668 -128.062736)
		(end 233.944668 -128.062736)
		(stroke
			(width 0.2)
			(type default)
		)
		(fill no)
		(layer "In6.Cu")
	)
	(gr_circle
		(center 233.055668 -127.300736)
		(end 233.944668 -127.300736)
		(stroke
			(width 0.2)
			(type default)
		)
		(fill no)
		(layer "In6.Cu")
	)
	(gr_circle
		(center 233.06913 -126.609094)
		(end 233.95813 -126.609094)
		(stroke
			(width 0.2)
			(type default)
		)
		(fill no)
		(layer "In6.Cu")
	)
	(gr_circle
		(center 233.069384 -131.829556)
		(end 233.958384 -131.829556)
		(stroke
			(width 0.2)
			(type default)
		)
		(fill no)
		(layer "In6.Cu")
	)
	(gr_circle
		(center 233.817668 -131.110736)
		(end 234.706668 -131.110736)
		(stroke
			(width 0.2)
			(type default)
		)
		(fill no)
		(layer "In6.Cu")
	)
	(gr_circle
		(center 233.817668 -130.348736)
		(end 234.706668 -130.348736)
		(stroke
			(width 0.2)
			(type default)
		)
		(fill no)
		(layer "In6.Cu")
	)
	(gr_circle
		(center 233.817668 -129.586736)
		(end 234.706668 -129.586736)
		(stroke
			(width 0.2)
			(type default)
		)
		(fill no)
		(layer "In6.Cu")
	)
	(gr_circle
		(center 233.817668 -128.824736)
		(end 234.706668 -128.824736)
		(stroke
			(width 0.2)
			(type default)
		)
		(fill no)
		(layer "In6.Cu")
	)
	(gr_circle
		(center 233.817668 -128.062736)
		(end 234.706668 -128.062736)
		(stroke
			(width 0.2)
			(type default)
		)
		(fill no)
		(layer "In6.Cu")
	)
	(gr_circle
		(center 233.817668 -127.300736)
		(end 234.706668 -127.300736)
		(stroke
			(width 0.2)
			(type default)
		)
		(fill no)
		(layer "In6.Cu")
	)
	(gr_circle
		(center 233.83113 -126.609094)
		(end 234.72013 -126.609094)
		(stroke
			(width 0.2)
			(type default)
		)
		(fill no)
		(layer "In6.Cu")
	)
	(gr_circle
		(center 233.831384 -131.829556)
		(end 234.720384 -131.829556)
		(stroke
			(width 0.2)
			(type default)
		)
		(fill no)
		(layer "In6.Cu")
	)
	(gr_circle
		(center 234.303316 -97.985834)
		(end 235.192316 -97.985834)
		(stroke
			(width 0.2)
			(type default)
		)
		(fill no)
		(layer "In6.Cu")
	)
	(gr_circle
		(center 234.579668 -131.110736)
		(end 235.468668 -131.110736)
		(stroke
			(width 0.2)
			(type default)
		)
		(fill no)
		(layer "In6.Cu")
	)
	(gr_circle
		(center 234.579668 -130.348736)
		(end 235.468668 -130.348736)
		(stroke
			(width 0.2)
			(type default)
		)
		(fill no)
		(layer "In6.Cu")
	)
	(gr_circle
		(center 234.579668 -129.586736)
		(end 235.468668 -129.586736)
		(stroke
			(width 0.2)
			(type default)
		)
		(fill no)
		(layer "In6.Cu")
	)
	(gr_circle
		(center 234.579668 -128.824736)
		(end 235.468668 -128.824736)
		(stroke
			(width 0.2)
			(type default)
		)
		(fill no)
		(layer "In6.Cu")
	)
	(gr_circle
		(center 234.579668 -128.062736)
		(end 235.468668 -128.062736)
		(stroke
			(width 0.2)
			(type default)
		)
		(fill no)
		(layer "In6.Cu")
	)
	(gr_circle
		(center 234.579668 -127.300736)
		(end 235.468668 -127.300736)
		(stroke
			(width 0.2)
			(type default)
		)
		(fill no)
		(layer "In6.Cu")
	)
	(gr_circle
		(center 234.59313 -126.609094)
		(end 235.48213 -126.609094)
		(stroke
			(width 0.2)
			(type default)
		)
		(fill no)
		(layer "In6.Cu")
	)
	(gr_circle
		(center 234.593384 -131.829556)
		(end 235.482384 -131.829556)
		(stroke
			(width 0.2)
			(type default)
		)
		(fill no)
		(layer "In6.Cu")
	)
	(gr_circle
		(center 235.065316 -97.985834)
		(end 235.954316 -97.985834)
		(stroke
			(width 0.2)
			(type default)
		)
		(fill no)
		(layer "In6.Cu")
	)
	(gr_circle
		(center 236.554518 -97.985834)
		(end 237.443518 -97.985834)
		(stroke
			(width 0.2)
			(type default)
		)
		(fill no)
		(layer "In6.Cu")
	)
	(gr_circle
		(center 237.316518 -97.985834)
		(end 238.205518 -97.985834)
		(stroke
			(width 0.2)
			(type default)
		)
		(fill no)
		(layer "In6.Cu")
	)
	(gr_circle
		(center 239.076738 -98.012758)
		(end 239.965738 -98.012758)
		(stroke
			(width 0.2)
			(type default)
		)
		(fill no)
		(layer "In6.Cu")
	)
	(gr_circle
		(center 239.838738 -98.012758)
		(end 240.727738 -98.012758)
		(stroke
			(width 0.2)
			(type default)
		)
		(fill no)
		(layer "In6.Cu")
	)
	(gr_circle
		(center 241.32794 -98.012758)
		(end 242.21694 -98.012758)
		(stroke
			(width 0.2)
			(type default)
		)
		(fill no)
		(layer "In6.Cu")
	)
	(gr_circle
		(center 242.08994 -98.012758)
		(end 242.97894 -98.012758)
		(stroke
			(width 0.2)
			(type default)
		)
		(fill no)
		(layer "In6.Cu")
	)
	(gr_circle
		(center 258.219956 -50.232818)
		(end 259.108956 -50.232818)
		(stroke
			(width 0.2)
			(type default)
		)
		(fill no)
		(layer "In6.Cu")
	)
	(gr_circle
		(center 258.219956 -48.327818)
		(end 259.108956 -48.327818)
		(stroke
			(width 0.2)
			(type default)
		)
		(fill no)
		(layer "In6.Cu")
	)
	(gr_circle
		(center 258.219956 -47.565818)
		(end 259.108956 -47.565818)
		(stroke
			(width 0.2)
			(type default)
		)
		(fill no)
		(layer "In6.Cu")
	)
	(gr_circle
		(center 258.530598 -39.18712)
		(end 259.419598 -39.18712)
		(stroke
			(width 0.2)
			(type default)
		)
		(fill no)
		(layer "In6.Cu")
	)
	(gr_circle
		(center 258.548886 -38.461696)
		(end 259.437886 -38.461696)
		(stroke
			(width 0.2)
			(type default)
		)
		(fill no)
		(layer "In6.Cu")
	)
	(gr_circle
		(center 258.83362 -40.72382)
		(end 259.72262 -40.72382)
		(stroke
			(width 0.2)
			(type default)
		)
		(fill no)
		(layer "In6.Cu")
	)
	(gr_circle
		(center 258.83616 -39.95674)
		(end 259.72516 -39.95674)
		(stroke
			(width 0.2)
			(type default)
		)
		(fill no)
		(layer "In6.Cu")
	)
	(gr_circle
		(center 259.0038 -42.3164)
		(end 259.8928 -42.3164)
		(stroke
			(width 0.2)
			(type default)
		)
		(fill no)
		(layer "In6.Cu")
	)
	(gr_circle
		(center 259.588 -43.4848)
		(end 260.477 -43.4848)
		(stroke
			(width 0.2)
			(type default)
		)
		(fill no)
		(layer "In6.Cu")
	)
	(gr_circle
		(center 259.630672 -41.092882)
		(end 260.519672 -41.092882)
		(stroke
			(width 0.2)
			(type default)
		)
		(fill no)
		(layer "In6.Cu")
	)
	(gr_circle
		(center 259.630672 -39.592758)
		(end 260.519672 -39.592758)
		(stroke
			(width 0.2)
			(type default)
		)
		(fill no)
		(layer "In6.Cu")
	)
	(gr_circle
		(center 260.182106 -37.2364)
		(end 261.071106 -37.2364)
		(stroke
			(width 0.2)
			(type default)
		)
		(fill no)
		(layer "In6.Cu")
	)
	(gr_circle
		(center 269.24 -125.857)
		(end 270.129 -125.857)
		(stroke
			(width 0.2)
			(type default)
		)
		(fill no)
		(layer "In6.Cu")
	)
	(gr_circle
		(center 269.24 -125.095)
		(end 270.129 -125.095)
		(stroke
			(width 0.2)
			(type default)
		)
		(fill no)
		(layer "In6.Cu")
	)
	(gr_circle
		(center 269.24 -124.333)
		(end 270.129 -124.333)
		(stroke
			(width 0.2)
			(type default)
		)
		(fill no)
		(layer "In6.Cu")
	)
	(gr_circle
		(center 269.24 -123.571)
		(end 270.129 -123.571)
		(stroke
			(width 0.2)
			(type default)
		)
		(fill no)
		(layer "In6.Cu")
	)
	(gr_circle
		(center 269.24 -122.809)
		(end 270.129 -122.809)
		(stroke
			(width 0.2)
			(type default)
		)
		(fill no)
		(layer "In6.Cu")
	)
	(gr_circle
		(center 269.24 -122.047)
		(end 270.129 -122.047)
		(stroke
			(width 0.2)
			(type default)
		)
		(fill no)
		(layer "In6.Cu")
	)
	(gr_circle
		(center 269.24 -113.792)
		(end 270.129 -113.792)
		(stroke
			(width 0.2)
			(type default)
		)
		(fill no)
		(layer "In6.Cu")
	)
	(gr_circle
		(center 269.24 -113.03)
		(end 270.129 -113.03)
		(stroke
			(width 0.2)
			(type default)
		)
		(fill no)
		(layer "In6.Cu")
	)
	(gr_circle
		(center 269.24 -112.268)
		(end 270.129 -112.268)
		(stroke
			(width 0.2)
			(type default)
		)
		(fill no)
		(layer "In6.Cu")
	)
	(gr_circle
		(center 269.24 -111.506)
		(end 270.129 -111.506)
		(stroke
			(width 0.2)
			(type default)
		)
		(fill no)
		(layer "In6.Cu")
	)
	(gr_circle
		(center 269.24 -110.744)
		(end 270.129 -110.744)
		(stroke
			(width 0.2)
			(type default)
		)
		(fill no)
		(layer "In6.Cu")
	)
	(gr_circle
		(center 269.24 -109.982)
		(end 270.129 -109.982)
		(stroke
			(width 0.2)
			(type default)
		)
		(fill no)
		(layer "In6.Cu")
	)
	(gr_circle
		(center 269.24 -101.727)
		(end 270.129 -101.727)
		(stroke
			(width 0.2)
			(type default)
		)
		(fill no)
		(layer "In6.Cu")
	)
	(gr_circle
		(center 269.24 -100.965)
		(end 270.129 -100.965)
		(stroke
			(width 0.2)
			(type default)
		)
		(fill no)
		(layer "In6.Cu")
	)
	(gr_circle
		(center 269.24 -100.203)
		(end 270.129 -100.203)
		(stroke
			(width 0.2)
			(type default)
		)
		(fill no)
		(layer "In6.Cu")
	)
	(gr_circle
		(center 269.24 -99.441)
		(end 270.129 -99.441)
		(stroke
			(width 0.2)
			(type default)
		)
		(fill no)
		(layer "In6.Cu")
	)
	(gr_circle
		(center 269.24 -98.679)
		(end 270.129 -98.679)
		(stroke
			(width 0.2)
			(type default)
		)
		(fill no)
		(layer "In6.Cu")
	)
	(gr_circle
		(center 269.24 -97.917)
		(end 270.129 -97.917)
		(stroke
			(width 0.2)
			(type default)
		)
		(fill no)
		(layer "In6.Cu")
	)
	(gr_circle
		(center 269.24 -89.662)
		(end 270.129 -89.662)
		(stroke
			(width 0.2)
			(type default)
		)
		(fill no)
		(layer "In6.Cu")
	)
	(gr_circle
		(center 269.24 -88.9)
		(end 270.129 -88.9)
		(stroke
			(width 0.2)
			(type default)
		)
		(fill no)
		(layer "In6.Cu")
	)
	(gr_circle
		(center 269.24 -88.138)
		(end 270.129 -88.138)
		(stroke
			(width 0.2)
			(type default)
		)
		(fill no)
		(layer "In6.Cu")
	)
	(gr_circle
		(center 269.24 -87.376)
		(end 270.129 -87.376)
		(stroke
			(width 0.2)
			(type default)
		)
		(fill no)
		(layer "In6.Cu")
	)
	(gr_circle
		(center 269.24 -86.614)
		(end 270.129 -86.614)
		(stroke
			(width 0.2)
			(type default)
		)
		(fill no)
		(layer "In6.Cu")
	)
	(gr_circle
		(center 269.24 -85.852)
		(end 270.129 -85.852)
		(stroke
			(width 0.2)
			(type default)
		)
		(fill no)
		(layer "In6.Cu")
	)
	(gr_circle
		(center 269.24 -77.597)
		(end 270.129 -77.597)
		(stroke
			(width 0.2)
			(type default)
		)
		(fill no)
		(layer "In6.Cu")
	)
	(gr_circle
		(center 269.24 -76.835)
		(end 270.129 -76.835)
		(stroke
			(width 0.2)
			(type default)
		)
		(fill no)
		(layer "In6.Cu")
	)
	(gr_circle
		(center 269.24 -76.073)
		(end 270.129 -76.073)
		(stroke
			(width 0.2)
			(type default)
		)
		(fill no)
		(layer "In6.Cu")
	)
	(gr_circle
		(center 269.24 -75.311)
		(end 270.129 -75.311)
		(stroke
			(width 0.2)
			(type default)
		)
		(fill no)
		(layer "In6.Cu")
	)
	(gr_circle
		(center 269.24 -74.549)
		(end 270.129 -74.549)
		(stroke
			(width 0.2)
			(type default)
		)
		(fill no)
		(layer "In6.Cu")
	)
	(gr_circle
		(center 269.24 -73.787)
		(end 270.129 -73.787)
		(stroke
			(width 0.2)
			(type default)
		)
		(fill no)
		(layer "In6.Cu")
	)
	(gr_circle
		(center 269.24 -65.532)
		(end 270.129 -65.532)
		(stroke
			(width 0.2)
			(type default)
		)
		(fill no)
		(layer "In6.Cu")
	)
	(gr_circle
		(center 269.24 -64.77)
		(end 270.129 -64.77)
		(stroke
			(width 0.2)
			(type default)
		)
		(fill no)
		(layer "In6.Cu")
	)
	(gr_circle
		(center 269.24 -64.008)
		(end 270.129 -64.008)
		(stroke
			(width 0.2)
			(type default)
		)
		(fill no)
		(layer "In6.Cu")
	)
	(gr_circle
		(center 269.24 -63.246)
		(end 270.129 -63.246)
		(stroke
			(width 0.2)
			(type default)
		)
		(fill no)
		(layer "In6.Cu")
	)
	(gr_circle
		(center 269.24 -62.484)
		(end 270.129 -62.484)
		(stroke
			(width 0.2)
			(type default)
		)
		(fill no)
		(layer "In6.Cu")
	)
	(gr_circle
		(center 269.24 -61.722)
		(end 270.129 -61.722)
		(stroke
			(width 0.2)
			(type default)
		)
		(fill no)
		(layer "In6.Cu")
	)
	(gr_circle
		(center 270.002 -125.857)
		(end 270.891 -125.857)
		(stroke
			(width 0.2)
			(type default)
		)
		(fill no)
		(layer "In6.Cu")
	)
	(gr_circle
		(center 270.002 -125.095)
		(end 270.891 -125.095)
		(stroke
			(width 0.2)
			(type default)
		)
		(fill no)
		(layer "In6.Cu")
	)
	(gr_circle
		(center 270.002 -124.333)
		(end 270.891 -124.333)
		(stroke
			(width 0.2)
			(type default)
		)
		(fill no)
		(layer "In6.Cu")
	)
	(gr_circle
		(center 270.002 -123.571)
		(end 270.891 -123.571)
		(stroke
			(width 0.2)
			(type default)
		)
		(fill no)
		(layer "In6.Cu")
	)
	(gr_circle
		(center 270.002 -122.809)
		(end 270.891 -122.809)
		(stroke
			(width 0.2)
			(type default)
		)
		(fill no)
		(layer "In6.Cu")
	)
	(gr_circle
		(center 270.002 -122.047)
		(end 270.891 -122.047)
		(stroke
			(width 0.2)
			(type default)
		)
		(fill no)
		(layer "In6.Cu")
	)
	(gr_circle
		(center 270.002 -113.792)
		(end 270.891 -113.792)
		(stroke
			(width 0.2)
			(type default)
		)
		(fill no)
		(layer "In6.Cu")
	)
	(gr_circle
		(center 270.002 -113.03)
		(end 270.891 -113.03)
		(stroke
			(width 0.2)
			(type default)
		)
		(fill no)
		(layer "In6.Cu")
	)
	(gr_circle
		(center 270.002 -112.268)
		(end 270.891 -112.268)
		(stroke
			(width 0.2)
			(type default)
		)
		(fill no)
		(layer "In6.Cu")
	)
	(gr_circle
		(center 270.002 -111.506)
		(end 270.891 -111.506)
		(stroke
			(width 0.2)
			(type default)
		)
		(fill no)
		(layer "In6.Cu")
	)
	(gr_circle
		(center 270.002 -110.744)
		(end 270.891 -110.744)
		(stroke
			(width 0.2)
			(type default)
		)
		(fill no)
		(layer "In6.Cu")
	)
	(gr_circle
		(center 270.002 -109.982)
		(end 270.891 -109.982)
		(stroke
			(width 0.2)
			(type default)
		)
		(fill no)
		(layer "In6.Cu")
	)
	(gr_circle
		(center 270.002 -101.727)
		(end 270.891 -101.727)
		(stroke
			(width 0.2)
			(type default)
		)
		(fill no)
		(layer "In6.Cu")
	)
	(gr_circle
		(center 270.002 -100.965)
		(end 270.891 -100.965)
		(stroke
			(width 0.2)
			(type default)
		)
		(fill no)
		(layer "In6.Cu")
	)
	(gr_circle
		(center 270.002 -100.203)
		(end 270.891 -100.203)
		(stroke
			(width 0.2)
			(type default)
		)
		(fill no)
		(layer "In6.Cu")
	)
	(gr_circle
		(center 270.002 -99.441)
		(end 270.891 -99.441)
		(stroke
			(width 0.2)
			(type default)
		)
		(fill no)
		(layer "In6.Cu")
	)
	(gr_circle
		(center 270.002 -98.679)
		(end 270.891 -98.679)
		(stroke
			(width 0.2)
			(type default)
		)
		(fill no)
		(layer "In6.Cu")
	)
	(gr_circle
		(center 270.002 -97.917)
		(end 270.891 -97.917)
		(stroke
			(width 0.2)
			(type default)
		)
		(fill no)
		(layer "In6.Cu")
	)
	(gr_circle
		(center 270.002 -89.662)
		(end 270.891 -89.662)
		(stroke
			(width 0.2)
			(type default)
		)
		(fill no)
		(layer "In6.Cu")
	)
	(gr_circle
		(center 270.002 -88.9)
		(end 270.891 -88.9)
		(stroke
			(width 0.2)
			(type default)
		)
		(fill no)
		(layer "In6.Cu")
	)
	(gr_circle
		(center 270.002 -88.138)
		(end 270.891 -88.138)
		(stroke
			(width 0.2)
			(type default)
		)
		(fill no)
		(layer "In6.Cu")
	)
	(gr_circle
		(center 270.002 -87.376)
		(end 270.891 -87.376)
		(stroke
			(width 0.2)
			(type default)
		)
		(fill no)
		(layer "In6.Cu")
	)
	(gr_circle
		(center 270.002 -86.614)
		(end 270.891 -86.614)
		(stroke
			(width 0.2)
			(type default)
		)
		(fill no)
		(layer "In6.Cu")
	)
	(gr_circle
		(center 270.002 -85.852)
		(end 270.891 -85.852)
		(stroke
			(width 0.2)
			(type default)
		)
		(fill no)
		(layer "In6.Cu")
	)
	(gr_circle
		(center 270.002 -77.597)
		(end 270.891 -77.597)
		(stroke
			(width 0.2)
			(type default)
		)
		(fill no)
		(layer "In6.Cu")
	)
	(gr_circle
		(center 270.002 -76.835)
		(end 270.891 -76.835)
		(stroke
			(width 0.2)
			(type default)
		)
		(fill no)
		(layer "In6.Cu")
	)
	(gr_circle
		(center 270.002 -76.073)
		(end 270.891 -76.073)
		(stroke
			(width 0.2)
			(type default)
		)
		(fill no)
		(layer "In6.Cu")
	)
	(gr_circle
		(center 270.002 -75.311)
		(end 270.891 -75.311)
		(stroke
			(width 0.2)
			(type default)
		)
		(fill no)
		(layer "In6.Cu")
	)
	(gr_circle
		(center 270.002 -74.549)
		(end 270.891 -74.549)
		(stroke
			(width 0.2)
			(type default)
		)
		(fill no)
		(layer "In6.Cu")
	)
	(gr_circle
		(center 270.002 -73.787)
		(end 270.891 -73.787)
		(stroke
			(width 0.2)
			(type default)
		)
		(fill no)
		(layer "In6.Cu")
	)
	(gr_circle
		(center 270.002 -65.532)
		(end 270.891 -65.532)
		(stroke
			(width 0.2)
			(type default)
		)
		(fill no)
		(layer "In6.Cu")
	)
	(gr_circle
		(center 270.002 -64.77)
		(end 270.891 -64.77)
		(stroke
			(width 0.2)
			(type default)
		)
		(fill no)
		(layer "In6.Cu")
	)
	(gr_circle
		(center 270.002 -64.008)
		(end 270.891 -64.008)
		(stroke
			(width 0.2)
			(type default)
		)
		(fill no)
		(layer "In6.Cu")
	)
	(gr_circle
		(center 270.002 -63.246)
		(end 270.891 -63.246)
		(stroke
			(width 0.2)
			(type default)
		)
		(fill no)
		(layer "In6.Cu")
	)
	(gr_circle
		(center 270.002 -62.484)
		(end 270.891 -62.484)
		(stroke
			(width 0.2)
			(type default)
		)
		(fill no)
		(layer "In6.Cu")
	)
	(gr_circle
		(center 270.002 -61.722)
		(end 270.891 -61.722)
		(stroke
			(width 0.2)
			(type default)
		)
		(fill no)
		(layer "In6.Cu")
	)
	(gr_circle
		(center 270.764 -125.857)
		(end 271.653 -125.857)
		(stroke
			(width 0.2)
			(type default)
		)
		(fill no)
		(layer "In6.Cu")
	)
	(gr_circle
		(center 270.764 -125.095)
		(end 271.653 -125.095)
		(stroke
			(width 0.2)
			(type default)
		)
		(fill no)
		(layer "In6.Cu")
	)
	(gr_circle
		(center 270.764 -124.333)
		(end 271.653 -124.333)
		(stroke
			(width 0.2)
			(type default)
		)
		(fill no)
		(layer "In6.Cu")
	)
	(gr_circle
		(center 270.764 -123.571)
		(end 271.653 -123.571)
		(stroke
			(width 0.2)
			(type default)
		)
		(fill no)
		(layer "In6.Cu")
	)
	(gr_circle
		(center 270.764 -122.809)
		(end 271.653 -122.809)
		(stroke
			(width 0.2)
			(type default)
		)
		(fill no)
		(layer "In6.Cu")
	)
	(gr_circle
		(center 270.764 -122.047)
		(end 271.653 -122.047)
		(stroke
			(width 0.2)
			(type default)
		)
		(fill no)
		(layer "In6.Cu")
	)
	(gr_circle
		(center 270.764 -113.792)
		(end 271.653 -113.792)
		(stroke
			(width 0.2)
			(type default)
		)
		(fill no)
		(layer "In6.Cu")
	)
	(gr_circle
		(center 270.764 -113.03)
		(end 271.653 -113.03)
		(stroke
			(width 0.2)
			(type default)
		)
		(fill no)
		(layer "In6.Cu")
	)
	(gr_circle
		(center 270.764 -112.268)
		(end 271.653 -112.268)
		(stroke
			(width 0.2)
			(type default)
		)
		(fill no)
		(layer "In6.Cu")
	)
	(gr_circle
		(center 270.764 -111.506)
		(end 271.653 -111.506)
		(stroke
			(width 0.2)
			(type default)
		)
		(fill no)
		(layer "In6.Cu")
	)
	(gr_circle
		(center 270.764 -110.744)
		(end 271.653 -110.744)
		(stroke
			(width 0.2)
			(type default)
		)
		(fill no)
		(layer "In6.Cu")
	)
	(gr_circle
		(center 270.764 -109.982)
		(end 271.653 -109.982)
		(stroke
			(width 0.2)
			(type default)
		)
		(fill no)
		(layer "In6.Cu")
	)
	(gr_circle
		(center 270.764 -101.727)
		(end 271.653 -101.727)
		(stroke
			(width 0.2)
			(type default)
		)
		(fill no)
		(layer "In6.Cu")
	)
	(gr_circle
		(center 270.764 -100.965)
		(end 271.653 -100.965)
		(stroke
			(width 0.2)
			(type default)
		)
		(fill no)
		(layer "In6.Cu")
	)
	(gr_circle
		(center 270.764 -100.203)
		(end 271.653 -100.203)
		(stroke
			(width 0.2)
			(type default)
		)
		(fill no)
		(layer "In6.Cu")
	)
	(gr_circle
		(center 270.764 -99.441)
		(end 271.653 -99.441)
		(stroke
			(width 0.2)
			(type default)
		)
		(fill no)
		(layer "In6.Cu")
	)
	(gr_circle
		(center 270.764 -98.679)
		(end 271.653 -98.679)
		(stroke
			(width 0.2)
			(type default)
		)
		(fill no)
		(layer "In6.Cu")
	)
	(gr_circle
		(center 270.764 -97.917)
		(end 271.653 -97.917)
		(stroke
			(width 0.2)
			(type default)
		)
		(fill no)
		(layer "In6.Cu")
	)
	(gr_circle
		(center 270.764 -89.662)
		(end 271.653 -89.662)
		(stroke
			(width 0.2)
			(type default)
		)
		(fill no)
		(layer "In6.Cu")
	)
	(gr_circle
		(center 270.764 -88.9)
		(end 271.653 -88.9)
		(stroke
			(width 0.2)
			(type default)
		)
		(fill no)
		(layer "In6.Cu")
	)
	(gr_circle
		(center 270.764 -88.138)
		(end 271.653 -88.138)
		(stroke
			(width 0.2)
			(type default)
		)
		(fill no)
		(layer "In6.Cu")
	)
	(gr_circle
		(center 270.764 -87.376)
		(end 271.653 -87.376)
		(stroke
			(width 0.2)
			(type default)
		)
		(fill no)
		(layer "In6.Cu")
	)
	(gr_circle
		(center 270.764 -86.614)
		(end 271.653 -86.614)
		(stroke
			(width 0.2)
			(type default)
		)
		(fill no)
		(layer "In6.Cu")
	)
	(gr_circle
		(center 270.764 -85.852)
		(end 271.653 -85.852)
		(stroke
			(width 0.2)
			(type default)
		)
		(fill no)
		(layer "In6.Cu")
	)
	(gr_circle
		(center 270.764 -77.597)
		(end 271.653 -77.597)
		(stroke
			(width 0.2)
			(type default)
		)
		(fill no)
		(layer "In6.Cu")
	)
	(gr_circle
		(center 270.764 -76.835)
		(end 271.653 -76.835)
		(stroke
			(width 0.2)
			(type default)
		)
		(fill no)
		(layer "In6.Cu")
	)
	(gr_circle
		(center 270.764 -76.073)
		(end 271.653 -76.073)
		(stroke
			(width 0.2)
			(type default)
		)
		(fill no)
		(layer "In6.Cu")
	)
	(gr_circle
		(center 270.764 -75.311)
		(end 271.653 -75.311)
		(stroke
			(width 0.2)
			(type default)
		)
		(fill no)
		(layer "In6.Cu")
	)
	(gr_circle
		(center 270.764 -74.549)
		(end 271.653 -74.549)
		(stroke
			(width 0.2)
			(type default)
		)
		(fill no)
		(layer "In6.Cu")
	)
	(gr_circle
		(center 270.764 -73.787)
		(end 271.653 -73.787)
		(stroke
			(width 0.2)
			(type default)
		)
		(fill no)
		(layer "In6.Cu")
	)
	(gr_circle
		(center 270.764 -65.532)
		(end 271.653 -65.532)
		(stroke
			(width 0.2)
			(type default)
		)
		(fill no)
		(layer "In6.Cu")
	)
	(gr_circle
		(center 270.764 -64.77)
		(end 271.653 -64.77)
		(stroke
			(width 0.2)
			(type default)
		)
		(fill no)
		(layer "In6.Cu")
	)
	(gr_circle
		(center 270.764 -64.008)
		(end 271.653 -64.008)
		(stroke
			(width 0.2)
			(type default)
		)
		(fill no)
		(layer "In6.Cu")
	)
	(gr_circle
		(center 270.764 -63.246)
		(end 271.653 -63.246)
		(stroke
			(width 0.2)
			(type default)
		)
		(fill no)
		(layer "In6.Cu")
	)
	(gr_circle
		(center 270.764 -62.484)
		(end 271.653 -62.484)
		(stroke
			(width 0.2)
			(type default)
		)
		(fill no)
		(layer "In6.Cu")
	)
	(gr_circle
		(center 270.764 -61.722)
		(end 271.653 -61.722)
		(stroke
			(width 0.2)
			(type default)
		)
		(fill no)
		(layer "In6.Cu")
	)
	(gr_circle
		(center 270.891 -140.462)
		(end 271.78 -140.462)
		(stroke
			(width 0.2)
			(type default)
		)
		(fill no)
		(layer "In6.Cu")
	)
	(gr_circle
		(center 270.891 -139.7)
		(end 271.78 -139.7)
		(stroke
			(width 0.2)
			(type default)
		)
		(fill no)
		(layer "In6.Cu")
	)
	(gr_circle
		(center 270.891 -138.938)
		(end 271.78 -138.938)
		(stroke
			(width 0.2)
			(type default)
		)
		(fill no)
		(layer "In6.Cu")
	)
	(gr_circle
		(center 270.891 -138.176)
		(end 271.78 -138.176)
		(stroke
			(width 0.2)
			(type default)
		)
		(fill no)
		(layer "In6.Cu")
	)
	(gr_circle
		(center 270.891 -137.414)
		(end 271.78 -137.414)
		(stroke
			(width 0.2)
			(type default)
		)
		(fill no)
		(layer "In6.Cu")
	)
	(gr_circle
		(center 270.891 -136.652)
		(end 271.78 -136.652)
		(stroke
			(width 0.2)
			(type default)
		)
		(fill no)
		(layer "In6.Cu")
	)
	(gr_circle
		(center 271.526 -125.857)
		(end 272.415 -125.857)
		(stroke
			(width 0.2)
			(type default)
		)
		(fill no)
		(layer "In6.Cu")
	)
	(gr_circle
		(center 271.526 -125.095)
		(end 272.415 -125.095)
		(stroke
			(width 0.2)
			(type default)
		)
		(fill no)
		(layer "In6.Cu")
	)
	(gr_circle
		(center 271.526 -122.809)
		(end 272.415 -122.809)
		(stroke
			(width 0.2)
			(type default)
		)
		(fill no)
		(layer "In6.Cu")
	)
	(gr_circle
		(center 271.526 -122.047)
		(end 272.415 -122.047)
		(stroke
			(width 0.2)
			(type default)
		)
		(fill no)
		(layer "In6.Cu")
	)
	(gr_circle
		(center 271.526 -113.792)
		(end 272.415 -113.792)
		(stroke
			(width 0.2)
			(type default)
		)
		(fill no)
		(layer "In6.Cu")
	)
	(gr_circle
		(center 271.526 -113.03)
		(end 272.415 -113.03)
		(stroke
			(width 0.2)
			(type default)
		)
		(fill no)
		(layer "In6.Cu")
	)
	(gr_circle
		(center 271.526 -110.744)
		(end 272.415 -110.744)
		(stroke
			(width 0.2)
			(type default)
		)
		(fill no)
		(layer "In6.Cu")
	)
	(gr_circle
		(center 271.526 -109.982)
		(end 272.415 -109.982)
		(stroke
			(width 0.2)
			(type default)
		)
		(fill no)
		(layer "In6.Cu")
	)
	(gr_circle
		(center 271.526 -101.727)
		(end 272.415 -101.727)
		(stroke
			(width 0.2)
			(type default)
		)
		(fill no)
		(layer "In6.Cu")
	)
	(gr_circle
		(center 271.526 -100.965)
		(end 272.415 -100.965)
		(stroke
			(width 0.2)
			(type default)
		)
		(fill no)
		(layer "In6.Cu")
	)
	(gr_circle
		(center 271.526 -98.679)
		(end 272.415 -98.679)
		(stroke
			(width 0.2)
			(type default)
		)
		(fill no)
		(layer "In6.Cu")
	)
	(gr_circle
		(center 271.526 -97.917)
		(end 272.415 -97.917)
		(stroke
			(width 0.2)
			(type default)
		)
		(fill no)
		(layer "In6.Cu")
	)
	(gr_circle
		(center 271.526 -89.662)
		(end 272.415 -89.662)
		(stroke
			(width 0.2)
			(type default)
		)
		(fill no)
		(layer "In6.Cu")
	)
	(gr_circle
		(center 271.526 -88.9)
		(end 272.415 -88.9)
		(stroke
			(width 0.2)
			(type default)
		)
		(fill no)
		(layer "In6.Cu")
	)
	(gr_circle
		(center 271.526 -86.614)
		(end 272.415 -86.614)
		(stroke
			(width 0.2)
			(type default)
		)
		(fill no)
		(layer "In6.Cu")
	)
	(gr_circle
		(center 271.526 -85.852)
		(end 272.415 -85.852)
		(stroke
			(width 0.2)
			(type default)
		)
		(fill no)
		(layer "In6.Cu")
	)
	(gr_circle
		(center 271.526 -77.597)
		(end 272.415 -77.597)
		(stroke
			(width 0.2)
			(type default)
		)
		(fill no)
		(layer "In6.Cu")
	)
	(gr_circle
		(center 271.526 -76.835)
		(end 272.415 -76.835)
		(stroke
			(width 0.2)
			(type default)
		)
		(fill no)
		(layer "In6.Cu")
	)
	(gr_circle
		(center 271.526 -74.549)
		(end 272.415 -74.549)
		(stroke
			(width 0.2)
			(type default)
		)
		(fill no)
		(layer "In6.Cu")
	)
	(gr_circle
		(center 271.526 -73.787)
		(end 272.415 -73.787)
		(stroke
			(width 0.2)
			(type default)
		)
		(fill no)
		(layer "In6.Cu")
	)
	(gr_circle
		(center 271.526 -65.532)
		(end 272.415 -65.532)
		(stroke
			(width 0.2)
			(type default)
		)
		(fill no)
		(layer "In6.Cu")
	)
	(gr_circle
		(center 271.526 -64.77)
		(end 272.415 -64.77)
		(stroke
			(width 0.2)
			(type default)
		)
		(fill no)
		(layer "In6.Cu")
	)
	(gr_circle
		(center 271.526 -62.484)
		(end 272.415 -62.484)
		(stroke
			(width 0.2)
			(type default)
		)
		(fill no)
		(layer "In6.Cu")
	)
	(gr_circle
		(center 271.526 -61.722)
		(end 272.415 -61.722)
		(stroke
			(width 0.2)
			(type default)
		)
		(fill no)
		(layer "In6.Cu")
	)
	(gr_circle
		(center 271.653 -140.462)
		(end 272.542 -140.462)
		(stroke
			(width 0.2)
			(type default)
		)
		(fill no)
		(layer "In6.Cu")
	)
	(gr_circle
		(center 271.653 -139.7)
		(end 272.542 -139.7)
		(stroke
			(width 0.2)
			(type default)
		)
		(fill no)
		(layer "In6.Cu")
	)
	(gr_circle
		(center 271.653 -138.938)
		(end 272.542 -138.938)
		(stroke
			(width 0.2)
			(type default)
		)
		(fill no)
		(layer "In6.Cu")
	)
	(gr_circle
		(center 271.653 -138.176)
		(end 272.542 -138.176)
		(stroke
			(width 0.2)
			(type default)
		)
		(fill no)
		(layer "In6.Cu")
	)
	(gr_circle
		(center 271.653 -137.414)
		(end 272.542 -137.414)
		(stroke
			(width 0.2)
			(type default)
		)
		(fill no)
		(layer "In6.Cu")
	)
	(gr_circle
		(center 271.653 -136.652)
		(end 272.542 -136.652)
		(stroke
			(width 0.2)
			(type default)
		)
		(fill no)
		(layer "In6.Cu")
	)
	(gr_circle
		(center 272.288 -125.857)
		(end 273.177 -125.857)
		(stroke
			(width 0.2)
			(type default)
		)
		(fill no)
		(layer "In6.Cu")
	)
	(gr_circle
		(center 272.288 -125.095)
		(end 273.177 -125.095)
		(stroke
			(width 0.2)
			(type default)
		)
		(fill no)
		(layer "In6.Cu")
	)
	(gr_circle
		(center 272.288 -122.809)
		(end 273.177 -122.809)
		(stroke
			(width 0.2)
			(type default)
		)
		(fill no)
		(layer "In6.Cu")
	)
	(gr_circle
		(center 272.288 -122.047)
		(end 273.177 -122.047)
		(stroke
			(width 0.2)
			(type default)
		)
		(fill no)
		(layer "In6.Cu")
	)
	(gr_circle
		(center 272.288 -113.792)
		(end 273.177 -113.792)
		(stroke
			(width 0.2)
			(type default)
		)
		(fill no)
		(layer "In6.Cu")
	)
	(gr_circle
		(center 272.288 -113.03)
		(end 273.177 -113.03)
		(stroke
			(width 0.2)
			(type default)
		)
		(fill no)
		(layer "In6.Cu")
	)
	(gr_circle
		(center 272.288 -110.744)
		(end 273.177 -110.744)
		(stroke
			(width 0.2)
			(type default)
		)
		(fill no)
		(layer "In6.Cu")
	)
	(gr_circle
		(center 272.288 -109.982)
		(end 273.177 -109.982)
		(stroke
			(width 0.2)
			(type default)
		)
		(fill no)
		(layer "In6.Cu")
	)
	(gr_circle
		(center 272.288 -101.727)
		(end 273.177 -101.727)
		(stroke
			(width 0.2)
			(type default)
		)
		(fill no)
		(layer "In6.Cu")
	)
	(gr_circle
		(center 272.288 -100.965)
		(end 273.177 -100.965)
		(stroke
			(width 0.2)
			(type default)
		)
		(fill no)
		(layer "In6.Cu")
	)
	(gr_circle
		(center 272.288 -98.679)
		(end 273.177 -98.679)
		(stroke
			(width 0.2)
			(type default)
		)
		(fill no)
		(layer "In6.Cu")
	)
	(gr_circle
		(center 272.288 -97.917)
		(end 273.177 -97.917)
		(stroke
			(width 0.2)
			(type default)
		)
		(fill no)
		(layer "In6.Cu")
	)
	(gr_circle
		(center 272.288 -89.662)
		(end 273.177 -89.662)
		(stroke
			(width 0.2)
			(type default)
		)
		(fill no)
		(layer "In6.Cu")
	)
	(gr_circle
		(center 272.288 -88.9)
		(end 273.177 -88.9)
		(stroke
			(width 0.2)
			(type default)
		)
		(fill no)
		(layer "In6.Cu")
	)
	(gr_circle
		(center 272.288 -86.614)
		(end 273.177 -86.614)
		(stroke
			(width 0.2)
			(type default)
		)
		(fill no)
		(layer "In6.Cu")
	)
	(gr_circle
		(center 272.288 -85.852)
		(end 273.177 -85.852)
		(stroke
			(width 0.2)
			(type default)
		)
		(fill no)
		(layer "In6.Cu")
	)
	(gr_circle
		(center 272.288 -77.597)
		(end 273.177 -77.597)
		(stroke
			(width 0.2)
			(type default)
		)
		(fill no)
		(layer "In6.Cu")
	)
	(gr_circle
		(center 272.288 -76.835)
		(end 273.177 -76.835)
		(stroke
			(width 0.2)
			(type default)
		)
		(fill no)
		(layer "In6.Cu")
	)
	(gr_circle
		(center 272.288 -74.549)
		(end 273.177 -74.549)
		(stroke
			(width 0.2)
			(type default)
		)
		(fill no)
		(layer "In6.Cu")
	)
	(gr_circle
		(center 272.288 -73.787)
		(end 273.177 -73.787)
		(stroke
			(width 0.2)
			(type default)
		)
		(fill no)
		(layer "In6.Cu")
	)
	(gr_circle
		(center 272.288 -65.532)
		(end 273.177 -65.532)
		(stroke
			(width 0.2)
			(type default)
		)
		(fill no)
		(layer "In6.Cu")
	)
	(gr_circle
		(center 272.288 -64.77)
		(end 273.177 -64.77)
		(stroke
			(width 0.2)
			(type default)
		)
		(fill no)
		(layer "In6.Cu")
	)
	(gr_circle
		(center 272.288 -62.484)
		(end 273.177 -62.484)
		(stroke
			(width 0.2)
			(type default)
		)
		(fill no)
		(layer "In6.Cu")
	)
	(gr_circle
		(center 272.288 -61.722)
		(end 273.177 -61.722)
		(stroke
			(width 0.2)
			(type default)
		)
		(fill no)
		(layer "In6.Cu")
	)
	(gr_circle
		(center 272.5928 -23.0886)
		(end 273.4818 -23.0886)
		(stroke
			(width 0.2)
			(type default)
		)
		(fill no)
		(layer "In6.Cu")
	)
	(gr_circle
		(center 273.6088 -23.0886)
		(end 274.4978 -23.0886)
		(stroke
			(width 0.2)
			(type default)
		)
		(fill no)
		(layer "In6.Cu")
	)
	(gr_circle
		(center 275.41855 -33.070038)
		(end 276.30755 -33.070038)
		(stroke
			(width 0.2)
			(type default)
		)
		(fill no)
		(layer "In6.Cu")
	)
	(gr_circle
		(center 277.368 -20.955)
		(end 278.257 -20.955)
		(stroke
			(width 0.2)
			(type default)
		)
		(fill no)
		(layer "In6.Cu")
	)
	(gr_line
		(start 278.19985 -131.594352)
		(end 278.19985 -61.165994)
		(stroke
			(width 1.016)
			(type default)
		)
		(layer "In6.Cu")
	)
	(gr_line
		(start 278.19985 -97.85985)
		(end 279.6921 -96.3676)
		(stroke
			(width 1.016)
			(type default)
		)
		(layer "In6.Cu")
	)
	(gr_line
		(start 278.19985 -94.87535)
		(end 279.6921 -96.3676)
		(stroke
			(width 1.016)
			(type default)
		)
		(layer "In6.Cu")
	)
	(gr_line
		(start 279.565862 -132.960364)
		(end 278.19985 -131.594352)
		(stroke
			(width 1.016)
			(type default)
		)
		(layer "In6.Cu")
	)
	(gr_line
		(start 279.648666 -59.717178)
		(end 278.19985 -61.165994)
		(stroke
			(width 1.016)
			(type default)
		)
		(layer "In6.Cu")
	)
	(gr_line
		(start 279.648666 -59.717178)
		(end 291.200078 -59.717178)
		(stroke
			(width 1.016)
			(type default)
		)
		(layer "In6.Cu")
	)
	(gr_circle
		(center 283.413454 -32.1564)
		(end 284.302454 -32.1564)
		(stroke
			(width 0.2)
			(type default)
		)
		(fill no)
		(layer "In6.Cu")
	)
	(gr_circle
		(center 285.242 -30.687264)
		(end 286.131 -30.687264)
		(stroke
			(width 0.2)
			(type default)
		)
		(fill no)
		(layer "In6.Cu")
	)
	(gr_circle
		(center 286.004 -30.687264)
		(end 286.893 -30.687264)
		(stroke
			(width 0.2)
			(type default)
		)
		(fill no)
		(layer "In6.Cu")
	)
	(gr_circle
		(center 287.401 -30.687264)
		(end 288.29 -30.687264)
		(stroke
			(width 0.2)
			(type default)
		)
		(fill no)
		(layer "In6.Cu")
	)
	(gr_circle
		(center 288.163 -30.687264)
		(end 289.052 -30.687264)
		(stroke
			(width 0.2)
			(type default)
		)
		(fill no)
		(layer "In6.Cu")
	)
	(gr_line
		(start 291.200078 -59.717178)
		(end 298.525184 -59.717178)
		(stroke
			(width 1.016)
			(type default)
		)
		(layer "In6.Cu")
	)
	(gr_circle
		(center 294.132 -45.466)
		(end 295.021 -45.466)
		(stroke
			(width 0.2)
			(type default)
		)
		(fill no)
		(layer "In6.Cu")
	)
	(gr_circle
		(center 294.1828 -34.9758)
		(end 295.0718 -34.9758)
		(stroke
			(width 0.2)
			(type default)
		)
		(fill no)
		(layer "In6.Cu")
	)
	(gr_circle
		(center 294.6908 -44.699428)
		(end 295.5798 -44.699428)
		(stroke
			(width 0.2)
			(type default)
		)
		(fill no)
		(layer "In6.Cu")
	)
	(gr_circle
		(center 295.3258 -44.693586)
		(end 296.2148 -44.693586)
		(stroke
			(width 0.2)
			(type default)
		)
		(fill no)
		(layer "In6.Cu")
	)
	(gr_circle
		(center 297.561 -54.356)
		(end 298.45 -54.356)
		(stroke
			(width 0.2)
			(type default)
		)
		(fill no)
		(layer "In6.Cu")
	)
	(gr_circle
		(center 297.561 -53.594)
		(end 298.45 -53.594)
		(stroke
			(width 0.2)
			(type default)
		)
		(fill no)
		(layer "In6.Cu")
	)
	(gr_circle
		(center 297.561 -52.832)
		(end 298.45 -52.832)
		(stroke
			(width 0.2)
			(type default)
		)
		(fill no)
		(layer "In6.Cu")
	)
	(gr_circle
		(center 297.561 -52.07)
		(end 298.45 -52.07)
		(stroke
			(width 0.2)
			(type default)
		)
		(fill no)
		(layer "In6.Cu")
	)
	(gr_line
		(start 298.271184 -96.3676)
		(end 278.19985 -96.3676)
		(stroke
			(width 1.016)
			(type default)
		)
		(layer "In6.Cu")
	)
	(gr_circle
		(center 298.323 -54.356)
		(end 299.212 -54.356)
		(stroke
			(width 0.2)
			(type default)
		)
		(fill no)
		(layer "In6.Cu")
	)
	(gr_circle
		(center 298.323 -53.594)
		(end 299.212 -53.594)
		(stroke
			(width 0.2)
			(type default)
		)
		(fill no)
		(layer "In6.Cu")
	)
	(gr_circle
		(center 298.323 -52.832)
		(end 299.212 -52.832)
		(stroke
			(width 0.2)
			(type default)
		)
		(fill no)
		(layer "In6.Cu")
	)
	(gr_circle
		(center 298.323 -52.07)
		(end 299.212 -52.07)
		(stroke
			(width 0.2)
			(type default)
		)
		(fill no)
		(layer "In6.Cu")
	)
	(gr_line
		(start 298.525184 -59.717178)
		(end 299.763434 -60.955428)
		(stroke
			(width 1.016)
			(type default)
		)
		(layer "In6.Cu")
	)
	(gr_line
		(start 298.533566 -132.960364)
		(end 279.565862 -132.960364)
		(stroke
			(width 1.016)
			(type default)
		)
		(layer "In6.Cu")
	)
	(gr_line
		(start 299.763434 -131.730496)
		(end 298.533566 -132.960364)
		(stroke
			(width 1.016)
			(type default)
		)
		(layer "In6.Cu")
	)
	(gr_line
		(start 299.763434 -127.672338)
		(end 299.763434 -131.730496)
		(stroke
			(width 1.016)
			(type default)
		)
		(layer "In6.Cu")
	)
	(gr_line
		(start 299.763434 -127.672338)
		(end 299.763434 -126.359666)
		(stroke
			(width 1.016)
			(type default)
		)
		(layer "In6.Cu")
	)
	(gr_line
		(start 299.763434 -127.672338)
		(end 299.763434 -126.219966)
		(stroke
			(width 1.016)
			(type default)
		)
		(layer "In6.Cu")
	)
	(gr_line
		(start 299.763434 -126.219966)
		(end 303.6824 -122.301)
		(stroke
			(width 1.016)
			(type default)
		)
		(layer "In6.Cu")
	)
	(gr_line
		(start 299.763434 -125.046994)
		(end 299.763434 -126.359666)
		(stroke
			(width 1.016)
			(type default)
		)
		(layer "In6.Cu")
	)
	(gr_line
		(start 299.763434 -125.046994)
		(end 299.763434 -122.1994)
		(stroke
			(width 1.016)
			(type default)
		)
		(layer "In6.Cu")
	)
	(gr_line
		(start 299.763434 -97.85985)
		(end 298.271184 -96.3676)
		(stroke
			(width 1.016)
			(type default)
		)
		(layer "In6.Cu")
	)
	(gr_line
		(start 299.763434 -96.3676)
		(end 298.271184 -96.3676)
		(stroke
			(width 1.016)
			(type default)
		)
		(layer "In6.Cu")
	)
	(gr_line
		(start 299.763434 -94.87535)
		(end 298.271184 -96.3676)
		(stroke
			(width 1.016)
			(type default)
		)
		(layer "In6.Cu")
	)
	(gr_line
		(start 299.763434 -60.955428)
		(end 299.763434 -122.1994)
		(stroke
			(width 1.016)
			(type default)
		)
		(layer "In6.Cu")
	)
	(gr_line
		(start 300.4185 -73.53935)
		(end 299.806868 -72.927718)
		(stroke
			(width 1.016)
			(type default)
		)
		(layer "In6.Cu")
	)
	(gr_line
		(start 300.61789 -73.554336)
		(end 299.798994 -74.373232)
		(stroke
			(width 1.016)
			(type default)
		)
		(layer "In6.Cu")
	)
	(gr_line
		(start 301.084742 -122.1994)
		(end 299.763434 -123.520708)
		(stroke
			(width 1.016)
			(type default)
		)
		(layer "In6.Cu")
	)
	(gr_line
		(start 301.084742 -122.1994)
		(end 299.763434 -120.878092)
		(stroke
			(width 1.016)
			(type default)
		)
		(layer "In6.Cu")
	)
	(gr_line
		(start 301.447708 -122.503692)
		(end 300.1264 -123.825)
		(stroke
			(width 1.016)
			(type default)
		)
		(layer "In6.Cu")
	)
	(gr_line
		(start 302.509428 -122.301)
		(end 299.763434 -125.046994)
		(stroke
			(width 1.016)
			(type default)
		)
		(layer "In6.Cu")
	)
	(gr_line
		(start 303.6824 -122.301)
		(end 302.509428 -122.301)
		(stroke
			(width 1.016)
			(type default)
		)
		(layer "In6.Cu")
	)
	(gr_line
		(start 304.071782 -73.53935)
		(end 300.4185 -73.53935)
		(stroke
			(width 1.016)
			(type default)
		)
		(layer "In6.Cu")
	)
	(gr_line
		(start 304.365406 -122.1994)
		(end 304.688494 -122.1994)
		(stroke
			(width 1.016)
			(type default)
		)
		(layer "In6.Cu")
	)
	(gr_line
		(start 306.38115 -73.53935)
		(end 304.071782 -73.53935)
		(stroke
			(width 1.016)
			(type default)
		)
		(layer "In6.Cu")
	)
	(gr_line
		(start 306.451 -73.6092)
		(end 306.38115 -73.53935)
		(stroke
			(width 1.016)
			(type default)
		)
		(layer "In6.Cu")
	)
	(gr_line
		(start 306.451 -73.6092)
		(end 308.6608 -75.819)
		(stroke
			(width 1.016)
			(type default)
		)
		(layer "In6.Cu")
	)
	(gr_line
		(start 308.6608 -75.819)
		(end 319.8876 -75.819)
		(stroke
			(width 1.016)
			(type default)
		)
		(layer "In6.Cu")
	)
	(gr_circle
		(center 311.410096 -72.879966)
		(end 312.809128 -72.879966)
		(stroke
			(width 0.2)
			(type default)
		)
		(fill no)
		(layer "In6.Cu")
	)
	(gr_line
		(start 319.6336 -122.1994)
		(end 299.763434 -122.1994)
		(stroke
			(width 1.016)
			(type default)
		)
		(layer "In6.Cu")
	)
	(gr_line
		(start 319.8876 -75.819)
		(end 320.929 -76.8604)
		(stroke
			(width 1.016)
			(type default)
		)
		(layer "In6.Cu")
	)
	(gr_line
		(start 320.929 -120.904)
		(end 319.6336 -122.1994)
		(stroke
			(width 1.016)
			(type default)
		)
		(layer "In6.Cu")
	)
	(gr_line
		(start 320.929 -76.8604)
		(end 320.929 -120.904)
		(stroke
			(width 1.016)
			(type default)
		)
		(layer "In6.Cu")
	)
	(gr_poly
		(pts
			(xy 295.2496 -95.7326) (xy 295.2496 -83.4898) (xy 296.32021 -82.41919) (xy 296.32021 -61.16701) (xy 295.9862 -60.833)
			(xy 279.8318 -60.833) (xy 279.334976 -61.329824) (xy 279.334976 -95.492824) (xy 279.726898 -95.885)
			(xy 295.0972 -95.885)
		)
		(stroke
			(width 0)
			(type solid)
		)
		(fill yes)
		(layer "In7.Cu")
		(net "P52V_HS1_DRAIN_2")
	)
	(gr_poly
		(pts
			(xy 295.402 -131.4704) (xy 295.402 -118.2624) (xy 296.32021 -117.34419) (xy 296.32021 -97.36201)
			(xy 295.9862 -97.028) (xy 279.4 -97.028) (xy 278.99868 -97.42932) (xy 278.99868 -131.351782) (xy 279.726898 -132.08)
			(xy 294.7924 -132.08)
		)
		(stroke
			(width 0)
			(type solid)
		)
		(fill yes)
		(layer "In7.Cu")
		(net "P52V_HS1_DRAIN_1")
	)
	(gr_poly
		(pts
			(xy 278.638 -90.91168) (xy 278.638 -59.412124) (xy 276.388576 -57.1627) (xy 265.177524 -57.1627)
			(xy 259.9182 -51.903376) (xy 259.9182 -43.3832) (xy 259.7404 -43.2054) (xy 259.4356 -43.2054) (xy 259.1562 -43.4848)
			(xy 259.1562 -52.93741) (xy 264.65149 -58.4327) (xy 275.869146 -58.4327) (xy 277.44928 -60.012834)
			(xy 277.44928 -88.08212) (xy 275.717 -89.8144) (xy 275.717 -90.932) (xy 276.352 -91.567) (xy 277.98268 -91.567)
		)
		(stroke
			(width 0)
			(type solid)
		)
		(fill yes)
		(layer "In7.Cu")
		(net "P52V_HS1_4287_GATE2_R")
	)
	(gr_poly
		(pts
			(arc
				(start 62.787276 -70.562724)
				(mid 62.782152 -70.487236)
				(end 62.780418 -70.411594)
			)
			(arc
				(start 62.780418 -70.409816)
				(mid 63.275293 -69.215083)
				(end 64.470026 -68.720208)
			)
			(arc
				(start 64.470026 -68.720208)
				(mid 65.114688 -68.848047)
				(end 65.661794 -69.212206)
			)
			(xy 66.802 -68.072) (xy 66.802 -66.548) (xy 66.294 -66.04) (xy 64.2874 -66.04) (xy 64.0588 -66.2686)
			(xy 64.0588 -67.703446)
			(arc
				(start 63.89243 -67.869816)
				(mid 63.587113 -68.606915)
				(end 62.850014 -68.912232)
			)
			(arc
				(start 62.850014 -68.912232)
				(mid 62.795712 -68.910856)
				(end 62.741556 -68.906644)
			)
			(xy 61.928756 -68.906644) (xy 61.6204 -69.215) (xy 61.6204 -70.4088) (xy 62.0776 -70.866) (xy 62.484 -70.866)
		)
		(stroke
			(width 0)
			(type solid)
		)
		(fill yes)
		(layer "In7.Cu")
		(net "P12V_BRICK")
	)
	(gr_poly
		(pts
			(arc
				(start 102.787196 -70.562724)
				(mid 102.782072 -70.487236)
				(end 102.780338 -70.411594)
			)
			(arc
				(start 102.780338 -70.409816)
				(mid 103.275213 -69.215083)
				(end 104.469946 -68.720208)
			)
			(arc
				(start 104.469946 -68.720208)
				(mid 105.114608 -68.848047)
				(end 105.661714 -69.212206)
			)
			(xy 106.80192 -68.072) (xy 106.80192 -66.548) (xy 106.29392 -66.04) (xy 104.28732 -66.04) (xy 104.05872 -66.2686)
			(xy 104.05872 -67.703446)
			(arc
				(start 103.89235 -67.869816)
				(mid 103.587033 -68.606915)
				(end 102.849934 -68.912232)
			)
			(arc
				(start 102.849934 -68.912232)
				(mid 102.795632 -68.910856)
				(end 102.741476 -68.906644)
			)
			(xy 101.928676 -68.906644) (xy 101.62032 -69.215) (xy 101.62032 -70.4088) (xy 102.07752 -70.866)
			(xy 102.48392 -70.866)
		)
		(stroke
			(width 0)
			(type solid)
		)
		(fill yes)
		(layer "In7.Cu")
		(net "P12V_BRICK")
	)
	(gr_poly
		(pts
			(xy 143.277082 -72.563482) (xy 142.5448 -71.8312) (xy 142.5448 -70.805294)
			(arc
				(start 142.78737 -70.562724)
				(mid 142.782246 -70.487236)
				(end 142.780512 -70.411594)
			)
			(arc
				(start 142.780512 -70.409816)
				(mid 143.275387 -69.215083)
				(end 144.47012 -68.720208)
			)
			(arc
				(start 144.47012 -68.720208)
				(mid 145.114782 -68.848047)
				(end 145.661888 -69.212206)
			)
			(xy 146.802094 -68.072) (xy 146.802094 -66.548) (xy 146.294094 -66.04) (xy 144.287494 -66.04) (xy 144.058894 -66.2686)
			(xy 144.058894 -67.703446)
			(arc
				(start 143.892524 -67.869816)
				(mid 143.587207 -68.606915)
				(end 142.850108 -68.912232)
			)
			(arc
				(start 142.850108 -68.912232)
				(mid 142.795806 -68.910856)
				(end 142.74165 -68.906644)
			)
			(xy 141.92885 -68.906644) (xy 141.620494 -69.215) (xy 141.620494 -70.4088) (xy 141.620494 -72.507094)
			(xy 142.3924 -73.279) (xy 143.277082 -73.279)
		)
		(stroke
			(width 0)
			(type solid)
		)
		(fill yes)
		(layer "In7.Cu")
		(net "P12V_BRICK")
	)
	(gr_poly
		(pts
			(arc
				(start 32.490918 -67.183)
				(mid 32.510441 -67.179099)
				(end 32.526986 -67.168014)
			)
			(xy 34.765742 -64.929258) (xy 34.773362 -64.9097) (xy 34.772854 -64.898778)
			(arc
				(start 34.772092 -64.86144)
				(mid 35.032623 -64.232463)
				(end 35.6616 -63.971932)
			)
			(xy 35.698938 -63.972694) (xy 35.70986 -63.973202) (xy 35.729418 -63.965582) (xy 38.518846 -61.176154)
			(xy 38.526212 -61.153802)
			(arc
				(start 38.524688 -61.141864)
				(mid 38.518217 -61.080292)
				(end 38.516052 -61.01842)
			)
			(arc
				(start 38.516052 -61.01842)
				(mid 38.776583 -60.389443)
				(end 39.40556 -60.128912)
			)
			(arc
				(start 39.40556 -60.128912)
				(mid 39.467432 -60.131084)
				(end 39.529004 -60.137548)
			)
			(xy 39.540942 -60.139072) (xy 39.563294 -60.131706)
			(arc
				(start 39.863014 -59.831986)
				(mid 39.874125 -59.815452)
				(end 39.878 -59.795918)
			)
			(xy 39.878 -59.293252) (xy 39.877492 -59.292744)
			(arc
				(start 39.877492 -56.408574)
				(mid 39.873659 -56.389217)
				(end 39.86276 -56.37276)
			)
			(arc
				(start 38.622986 -55.132986)
				(mid 38.606452 -55.121875)
				(end 38.586918 -55.118)
			)
			(arc
				(start 30.120082 -55.118)
				(mid 30.100559 -55.121901)
				(end 30.084014 -55.132986)
			)
			(arc
				(start 26.938986 -58.278014)
				(mid 26.927875 -58.294548)
				(end 26.924 -58.314082)
			)
			(arc
				(start 26.924 -66.907918)
				(mid 26.927901 -66.927441)
				(end 26.938986 -66.943986)
			)
			(arc
				(start 27.163014 -67.168014)
				(mid 27.179548 -67.179125)
				(end 27.199082 -67.183)
			)
		)
		(stroke
			(width 0)
			(type solid)
		)
		(fill yes)
		(layer "In7.Cu")
		(net "P12V_HPDB")
	)
	(gr_poly
		(pts
			(xy 278.257 -102.616) (xy 278.257 -92.456) (xy 278.003 -92.202) (xy 276.088856 -92.202) (xy 275.082 -91.195144)
			(xy 275.082 -89.551256) (xy 276.81428 -87.818976) (xy 276.81428 -60.275978) (xy 275.606002 -59.0677)
			(xy 263.7917 -59.0677) (xy 257.302 -52.578) (xy 257.302 -44.440856) (xy 259.461 -42.281856) (xy 259.461 -41.91)
			(xy 259.281422 -41.730422) (xy 258.268978 -41.730422) (xy 256.028444 -43.970956) (xy 256.028444 -53.209444)
			(xy 262.7884 -59.9694) (xy 275.1836 -59.9694) (xy 275.91258 -60.69838) (xy 275.91258 -87.40902) (xy 274.1803 -89.1413)
			(xy 274.1803 -91.7067) (xy 275.6662 -93.1926) (xy 275.6662 -95.673361) (xy 276.097742 -95.673361)
			(xy 276.097742 -95.588639) (xy 276.105795 -95.504302) (xy 276.121829 -95.421112) (xy 276.145697 -95.339822)
			(xy 276.177185 -95.26117) (xy 276.216007 -95.185867) (xy 276.26181 -95.114595) (xy 276.314181 -95.047999)
			(xy 276.372646 -94.986684) (xy 276.436674 -94.931203) (xy 276.505686 -94.88206) (xy 276.579056 -94.8397)
			(xy 276.656121 -94.804505) (xy 276.736183 -94.776796) (xy 276.818516 -94.756822) (xy 276.902375 -94.744765)
			(xy 276.987 -94.740734) (xy 277.071625 -94.744765) (xy 277.155484 -94.756822) (xy 277.237817 -94.776796)
			(xy 277.317879 -94.804505) (xy 277.394944 -94.8397) (xy 277.468314 -94.88206) (xy 277.537326 -94.931203)
			(xy 277.601354 -94.986684) (xy 277.659819 -95.047999) (xy 277.71219 -95.114595) (xy 277.757993 -95.185867)
			(xy 277.796815 -95.26117) (xy 277.828303 -95.339822) (xy 277.852171 -95.421112) (xy 277.868205 -95.504302)
			(xy 277.876258 -95.588639) (xy 277.876762 -95.631) (xy 277.876258 -95.673361) (xy 277.868205 -95.757698)
			(xy 277.852171 -95.840888) (xy 277.828303 -95.922178) (xy 277.796815 -96.00083) (xy 277.757993 -96.076133)
			(xy 277.71219 -96.147405) (xy 277.659819 -96.214001) (xy 277.601354 -96.275316) (xy 277.537326 -96.330797)
			(xy 277.468314 -96.37994) (xy 277.394944 -96.4223) (xy 277.317879 -96.457495) (xy 277.237817 -96.485204)
			(xy 277.155484 -96.505178) (xy 277.071625 -96.517235) (xy 276.987 -96.521267) (xy 276.902375 -96.517235)
			(xy 276.818516 -96.505178) (xy 276.736183 -96.485204) (xy 276.656121 -96.457495) (xy 276.579056 -96.4223)
			(xy 276.505686 -96.37994) (xy 276.436674 -96.330797) (xy 276.372646 -96.275316) (xy 276.314181 -96.214001)
			(xy 276.26181 -96.147405) (xy 276.216007 -96.076133) (xy 276.177185 -96.00083) (xy 276.145697 -95.922178)
			(xy 276.121829 -95.840888) (xy 276.105795 -95.757698) (xy 276.097742 -95.673361) (xy 275.6662 -95.673361)
			(xy 275.6662 -102.5652) (xy 275.8694 -102.7684) (xy 278.1046 -102.7684)
		)
		(stroke
			(width 0)
			(type solid)
		)
		(fill yes)
		(layer "In7.Cu")
		(net "P52V_HS1_4287_GATE_R")
	)
	(gr_poly
		(pts
			(xy 267.461746 -37.6936) (xy 267.464032 -37.674296) (xy 267.467777 -37.646803) (xy 267.482189 -37.593221)
			(xy 267.504209 -37.542292) (xy 267.533373 -37.49509) (xy 267.569065 -37.452608) (xy 267.610534 -37.415743)
			(xy 267.656904 -37.385273) (xy 267.707199 -37.36184) (xy 267.760357 -37.345938) (xy 267.815257 -37.337902)
			(xy 267.870743 -37.337902) (xy 267.925643 -37.345938) (xy 267.978801 -37.36184) (xy 268.029096 -37.385273)
			(xy 268.075466 -37.415743) (xy 268.116935 -37.452608) (xy 268.152627 -37.49509) (xy 268.181791 -37.542292)
			(xy 268.203811 -37.593221) (xy 268.218223 -37.646803) (xy 268.221968 -37.674296) (xy 268.224254 -37.6936)
			(xy 268.252702 -37.719) (xy 272.520918 -37.719) (xy 272.530987 -37.718573) (xy 272.549586 -37.710854)
			(xy 272.556986 -37.704014) (xy 272.908014 -37.352986) (xy 272.914868 -37.345591) (xy 272.92261 -37.326992)
			(xy 272.923 -37.316918) (xy 272.923 -34.438082) (xy 272.922573 -34.428013) (xy 272.914854 -34.409414)
			(xy 272.908014 -34.402014) (xy 272.683986 -34.177986) (xy 272.676591 -34.171132) (xy 272.657992 -34.16339)
			(xy 272.647918 -34.163) (xy 268.990318 -34.163) (xy 268.965172 -34.179256) (xy 268.959076 -34.192972)
			(xy 268.947391 -34.217713) (xy 268.917986 -34.263854) (xy 268.882291 -34.305321) (xy 268.841039 -34.341264)
			(xy 268.795074 -34.370945) (xy 268.745342 -34.393756) (xy 268.69286 -34.409228) (xy 268.638707 -34.417044)
			(xy 268.583993 -34.417044) (xy 268.52984 -34.409228) (xy 268.477358 -34.393756) (xy 268.427626 -34.370945)
			(xy 268.381661 -34.341264) (xy 268.340409 -34.305321) (xy 268.304714 -34.263854) (xy 268.275309 -34.217713)
			(xy 268.263624 -34.192972) (xy 268.257528 -34.179256) (xy 268.232382 -34.163) (xy 265.070082 -34.163)
			(xy 265.060013 -34.163427) (xy 265.041414 -34.171146) (xy 265.034014 -34.177986) (xy 264.809986 -34.402014)
			(xy 264.803132 -34.409409) (xy 264.79539 -34.428008) (xy 264.795 -34.438082) (xy 264.795 -35.2044)
			(xy 268.229332 -35.2044) (xy 268.233403 -35.148778) (xy 268.245529 -35.094341) (xy 268.265452 -35.04225)
			(xy 268.292748 -34.993615) (xy 268.326834 -34.949472) (xy 268.366983 -34.910763) (xy 268.412341 -34.878312)
			(xy 268.461941 -34.852811) (xy 268.514725 -34.834804) (xy 268.569568 -34.824674) (xy 268.625302 -34.822637)
			(xy 268.680739 -34.828737) (xy 268.734696 -34.842843) (xy 268.786025 -34.864655) (xy 268.833631 -34.893709)
			(xy 268.876499 -34.929384) (xy 268.913716 -34.970921) (xy 268.944489 -35.017434) (xy 268.968161 -35.067931)
			(xy 268.984229 -35.121338) (xy 268.992349 -35.176514) (xy 268.992858 -35.2044) (xy 268.992349 -35.232286)
			(xy 268.984229 -35.287462) (xy 268.968161 -35.340869) (xy 268.944489 -35.391366) (xy 268.913716 -35.437879)
			(xy 268.876499 -35.479416) (xy 268.833631 -35.515091) (xy 268.786025 -35.544145) (xy 268.734696 -35.565957)
			(xy 268.680739 -35.580063) (xy 268.625302 -35.586163) (xy 268.569568 -35.584126) (xy 268.514725 -35.573996)
			(xy 268.461941 -35.555989) (xy 268.412341 -35.530488) (xy 268.366983 -35.498037) (xy 268.326834 -35.459328)
			(xy 268.292748 -35.415185) (xy 268.265452 -35.36655) (xy 268.245529 -35.314459) (xy 268.233403 -35.260022)
			(xy 268.229332 -35.2044) (xy 264.795 -35.2044) (xy 264.795 -35.964941) (xy 265.597392 -35.964941)
			(xy 265.597393 -35.910441) (xy 265.60515 -35.856496) (xy 265.620506 -35.804204) (xy 265.643147 -35.75463)
			(xy 265.672612 -35.708782) (xy 265.708303 -35.667594) (xy 265.749492 -35.631905) (xy 265.79534 -35.602441)
			(xy 265.844916 -35.579801) (xy 265.897208 -35.564448) (xy 265.951153 -35.556692) (xy 266.005653 -35.556692)
			(xy 266.059598 -35.564449) (xy 266.111891 -35.579804) (xy 266.161465 -35.602444) (xy 266.207314 -35.631909)
			(xy 266.248502 -35.667599) (xy 266.284192 -35.708787) (xy 266.313657 -35.754636) (xy 266.336297 -35.804211)
			(xy 266.351651 -35.856503) (xy 266.359408 -35.910448) (xy 266.359894 -35.937698) (xy 266.3594 -35.965606)
			(xy 266.351238 -36.020822) (xy 266.343638 -36.04768) (xy 266.339801 -36.062199) (xy 266.339833 -36.092214)
			(xy 266.348584 -36.120926) (xy 266.365299 -36.145856) (xy 266.388536 -36.164855) (xy 266.416291 -36.176284)
			(xy 266.446169 -36.179155) (xy 266.460986 -36.176712) (xy 266.479644 -36.173168) (xy 266.517434 -36.169353)
			(xy 266.536424 -36.169092) (xy 266.563673 -36.169604) (xy 266.617616 -36.177363) (xy 266.669906 -36.19272)
			(xy 266.719478 -36.215362) (xy 266.765323 -36.244829) (xy 266.806508 -36.28052) (xy 266.842195 -36.321709)
			(xy 266.871657 -36.367557) (xy 266.894294 -36.417132) (xy 266.909645 -36.469423) (xy 266.917399 -36.523367)
			(xy 266.917397 -36.577865) (xy 266.909639 -36.631808) (xy 266.894283 -36.684098) (xy 266.871641 -36.733671)
			(xy 266.842176 -36.779517) (xy 266.806486 -36.820703) (xy 266.765298 -36.85639) (xy 266.71945 -36.885853)
			(xy 266.669876 -36.908491) (xy 266.617585 -36.923844) (xy 266.563641 -36.931598) (xy 266.509143 -36.931597)
			(xy 266.455199 -36.92384) (xy 266.402909 -36.908485) (xy 266.353336 -36.885845) (xy 266.30749 -36.856381)
			(xy 266.266303 -36.820691) (xy 266.230614 -36.779504) (xy 266.201151 -36.733657) (xy 266.178512 -36.684083)
			(xy 266.163158 -36.631793) (xy 266.155402 -36.577849) (xy 266.154916 -36.5506) (xy 266.155409 -36.522692)
			(xy 266.163572 -36.467476) (xy 266.171172 -36.440618) (xy 266.174999 -36.426097) (xy 266.174967 -36.396084)
			(xy 266.166216 -36.367375) (xy 266.149503 -36.342446) (xy 266.126268 -36.323447) (xy 266.098516 -36.312018)
			(xy 266.06864 -36.309145) (xy 266.053824 -36.311586) (xy 266.035165 -36.315128) (xy 265.997376 -36.318945)
			(xy 265.978386 -36.319206) (xy 265.951136 -36.318707) (xy 265.897191 -36.310949) (xy 265.844899 -36.295593)
			(xy 265.795325 -36.272951) (xy 265.749478 -36.243484) (xy 265.708291 -36.207793) (xy 265.672602 -36.166604)
			(xy 265.643138 -36.120755) (xy 265.6205 -36.071179) (xy 265.605146 -36.018887) (xy 265.597392 -35.964941)
			(xy 264.795 -35.964941) (xy 264.795 -37.211) (xy 271.579592 -37.211) (xy 271.583663 -37.155378) (xy 271.595789 -37.100941)
			(xy 271.615712 -37.04885) (xy 271.643008 -37.000215) (xy 271.677094 -36.956072) (xy 271.717243 -36.917363)
			(xy 271.762601 -36.884912) (xy 271.812201 -36.859411) (xy 271.864985 -36.841404) (xy 271.919828 -36.831274)
			(xy 271.975562 -36.829237) (xy 272.030999 -36.835337) (xy 272.084956 -36.849443) (xy 272.136285 -36.871255)
			(xy 272.183891 -36.900309) (xy 272.226759 -36.935984) (xy 272.263976 -36.977521) (xy 272.294749 -37.024034)
			(xy 272.318421 -37.074531) (xy 272.334489 -37.127938) (xy 272.342609 -37.183114) (xy 272.343118 -37.211)
			(xy 272.342609 -37.238886) (xy 272.334489 -37.294062) (xy 272.318421 -37.347469) (xy 272.294749 -37.397966)
			(xy 272.263976 -37.444479) (xy 272.226759 -37.486016) (xy 272.183891 -37.521691) (xy 272.136285 -37.550745)
			(xy 272.084956 -37.572557) (xy 272.030999 -37.586663) (xy 271.975562 -37.592763) (xy 271.919828 -37.590726)
			(xy 271.864985 -37.580596) (xy 271.812201 -37.562589) (xy 271.762601 -37.537088) (xy 271.717243 -37.504637)
			(xy 271.677094 -37.465928) (xy 271.643008 -37.421785) (xy 271.615712 -37.37315) (xy 271.595789 -37.321059)
			(xy 271.583663 -37.266622) (xy 271.579592 -37.211) (xy 264.795 -37.211) (xy 264.795 -37.443918) (xy 264.795427 -37.453987)
			(xy 264.803146 -37.472586) (xy 264.809986 -37.479986) (xy 265.034014 -37.704014) (xy 265.041409 -37.710868)
			(xy 265.060008 -37.71861) (xy 265.070082 -37.719) (xy 267.433298 -37.719)
		)
		(stroke
			(width 0)
			(type solid)
		)
		(fill yes)
		(layer "In7.Cu")
		(net "P52V_HS1_DVCC")
	)
	(gr_poly
		(pts
			(xy 319.401952 -121.691654) (xy 319.412017 -121.69122) (xy 319.430603 -121.683487) (xy 319.43802 -121.676668)
			(xy 320.406014 -120.708674) (xy 320.412866 -120.701278) (xy 320.420604 -120.682679) (xy 320.421 -120.672606)
			(xy 320.421 -77.110082) (xy 320.420573 -77.100013) (xy 320.412854 -77.081414) (xy 320.406014 -77.074014)
			(xy 319.673986 -76.341986) (xy 319.666591 -76.335132) (xy 319.647992 -76.32739) (xy 319.637918 -76.327)
			(xy 308.463696 -76.327) (xy 308.453626 -76.326576) (xy 308.435023 -76.318861) (xy 308.427628 -76.312014)
			(xy 306.17668 -74.061066) (xy 306.169284 -74.054216) (xy 306.150685 -74.046478) (xy 306.140612 -74.04608)
			(xy 302.583342 -74.04608) (xy 302.573276 -74.046513) (xy 302.554685 -74.05424) (xy 302.547274 -74.061066)
			(xy 302.478186 -74.130154) (xy 302.471339 -74.137551) (xy 302.463611 -74.156151) (xy 302.4632 -74.166222)
			(xy 302.4632 -83.5025) (xy 302.744376 -83.5025) (xy 302.748447 -83.446878) (xy 302.760573 -83.392441)
			(xy 302.780496 -83.34035) (xy 302.807792 -83.291715) (xy 302.841878 -83.247572) (xy 302.882027 -83.208863)
			(xy 302.927385 -83.176412) (xy 302.976985 -83.150911) (xy 303.029769 -83.132904) (xy 303.084612 -83.122774)
			(xy 303.140346 -83.120737) (xy 303.195783 -83.126837) (xy 303.24974 -83.140943) (xy 303.301069 -83.162755)
			(xy 303.348675 -83.191809) (xy 303.391543 -83.227484) (xy 303.42876 -83.269021) (xy 303.459533 -83.315534)
			(xy 303.483205 -83.366031) (xy 303.499273 -83.419438) (xy 303.507393 -83.474614) (xy 303.507902 -83.5025)
			(xy 303.507393 -83.530386) (xy 303.499273 -83.585562) (xy 303.483205 -83.638969) (xy 303.459533 -83.689466)
			(xy 303.42876 -83.735979) (xy 303.391543 -83.777516) (xy 303.348675 -83.813191) (xy 303.301069 -83.842245)
			(xy 303.24974 -83.864057) (xy 303.195783 -83.878163) (xy 303.140346 -83.884263) (xy 303.084612 -83.882226)
			(xy 303.029769 -83.872096) (xy 302.976985 -83.854089) (xy 302.927385 -83.828588) (xy 302.882027 -83.796137)
			(xy 302.841878 -83.757428) (xy 302.807792 -83.713285) (xy 302.780496 -83.66465) (xy 302.760573 -83.612559)
			(xy 302.748447 -83.558122) (xy 302.744376 -83.5025) (xy 302.4632 -83.5025) (xy 302.4632 -94.771718)
			(xy 302.462773 -94.781787) (xy 302.455054 -94.800386) (xy 302.448214 -94.807786) (xy 300.839886 -96.416114)
			(xy 300.833032 -96.423509) (xy 300.82529 -96.442108) (xy 300.8249 -96.452182) (xy 300.8249 -101.454966)
			(xy 306.278033 -101.454966) (xy 306.28204 -101.252216) (xy 306.294053 -101.049782) (xy 306.314054 -100.847981)
			(xy 306.342013 -100.647127) (xy 306.377884 -100.447535) (xy 306.421613 -100.249516) (xy 306.473131 -100.053379)
			(xy 306.532357 -99.859431) (xy 306.599199 -99.667973) (xy 306.673553 -99.479306) (xy 306.755302 -99.293724)
			(xy 306.84432 -99.111516) (xy 306.940466 -98.932967) (xy 307.043591 -98.758356) (xy 307.153534 -98.587956)
			(xy 307.270123 -98.422032) (xy 307.393176 -98.260843) (xy 307.522501 -98.104642) (xy 307.657896 -97.953672)
			(xy 307.799149 -97.808168) (xy 307.946041 -97.668359) (xy 308.098341 -97.534462) (xy 308.255812 -97.406687)
			(xy 308.418209 -97.285232) (xy 308.585276 -97.170288) (xy 308.756755 -97.062034) (xy 308.932376 -96.960639)
			(xy 309.111866 -96.866261) (xy 309.294944 -96.779049) (xy 309.481325 -96.699137) (xy 309.670718 -96.62665)
			(xy 309.862826 -96.561703) (xy 310.05735 -96.504395) (xy 310.253986 -96.454818) (xy 310.452428 -96.413047)
			(xy 310.652365 -96.379149) (xy 310.853484 -96.353177) (xy 311.055473 -96.33517) (xy 311.258016 -96.325157)
			(xy 311.460796 -96.323153) (xy 311.663497 -96.329163) (xy 311.865802 -96.343175) (xy 312.067396 -96.36517)
			(xy 312.267963 -96.395111) (xy 312.467191 -96.432952) (xy 312.664769 -96.478635) (xy 312.860387 -96.532088)
			(xy 313.053741 -96.593227) (xy 313.244529 -96.661958) (xy 313.432452 -96.738172) (xy 313.617218 -96.821751)
			(xy 313.798537 -96.912564) (xy 313.976128 -97.010469) (xy 314.149711 -97.115314) (xy 314.319017 -97.226935)
			(xy 314.483782 -97.345157) (xy 314.643747 -97.469797) (xy 314.798663 -97.600658) (xy 314.948288 -97.737538)
			(xy 315.092388 -97.880222) (xy 315.23074 -98.028488) (xy 315.363125 -98.182104) (xy 315.489339 -98.340829)
			(xy 315.609183 -98.504418) (xy 315.722471 -98.672613) (xy 315.829026 -98.845152) (xy 315.928681 -99.021767)
			(xy 316.021281 -99.20218) (xy 316.106681 -99.386111) (xy 316.184748 -99.573272) (xy 316.25536 -99.763372)
			(xy 316.318406 -99.956112) (xy 316.373789 -100.151193) (xy 316.421421 -100.34831) (xy 316.461229 -100.547154)
			(xy 316.493151 -100.747416) (xy 316.517135 -100.948782) (xy 316.533146 -101.150939) (xy 316.541157 -101.353571)
			(xy 316.541658 -101.454966) (xy 316.541157 -101.556361) (xy 316.533146 -101.758993) (xy 316.517135 -101.96115)
			(xy 316.493151 -102.162516) (xy 316.461229 -102.362778) (xy 316.421421 -102.561622) (xy 316.373789 -102.758739)
			(xy 316.318406 -102.95382) (xy 316.25536 -103.14656) (xy 316.184748 -103.33666) (xy 316.106681 -103.523821)
			(xy 316.021281 -103.707752) (xy 315.928681 -103.888165) (xy 315.829026 -104.06478) (xy 315.722471 -104.237319)
			(xy 315.609183 -104.405514) (xy 315.489339 -104.569103) (xy 315.363125 -104.727828) (xy 315.23074 -104.881444)
			(xy 315.092388 -105.02971) (xy 314.948288 -105.172394) (xy 314.798663 -105.309274) (xy 314.643747 -105.440135)
			(xy 314.483782 -105.564775) (xy 314.319017 -105.682997) (xy 314.149711 -105.794618) (xy 313.976128 -105.899463)
			(xy 313.798537 -105.997368) (xy 313.617218 -106.088181) (xy 313.432452 -106.17176) (xy 313.244529 -106.247974)
			(xy 313.053741 -106.316705) (xy 312.860387 -106.377844) (xy 312.664769 -106.431297) (xy 312.467191 -106.47698)
			(xy 312.267963 -106.514821) (xy 312.067396 -106.544762) (xy 311.865802 -106.566757) (xy 311.663497 -106.580769)
			(xy 311.460796 -106.586779) (xy 311.258016 -106.584775) (xy 311.055473 -106.574762) (xy 310.853484 -106.556755)
			(xy 310.652365 -106.530783) (xy 310.452428 -106.496885) (xy 310.253986 -106.455114) (xy 310.05735 -106.405537)
			(xy 309.862826 -106.348229) (xy 309.670718 -106.283282) (xy 309.481325 -106.210795) (xy 309.294944 -106.130883)
			(xy 309.111866 -106.043671) (xy 308.932376 -105.949293) (xy 308.756755 -105.847898) (xy 308.585276 -105.739644)
			(xy 308.418209 -105.6247) (xy 308.255812 -105.503245) (xy 308.098341 -105.37547) (xy 307.946041 -105.241573)
			(xy 307.799149 -105.101764) (xy 307.657896 -104.95626) (xy 307.522501 -104.80529) (xy 307.393176 -104.649089)
			(xy 307.270123 -104.4879) (xy 307.153534 -104.321976) (xy 307.043591 -104.151576) (xy 306.940466 -103.976965)
			(xy 306.84432 -103.798416) (xy 306.755302 -103.616208) (xy 306.673553 -103.430626) (xy 306.599199 -103.241959)
			(xy 306.532357 -103.050501) (xy 306.473131 -102.856553) (xy 306.421613 -102.660416) (xy 306.377884 -102.462397)
			(xy 306.342013 -102.262805) (xy 306.314054 -102.061951) (xy 306.294053 -101.86015) (xy 306.28204 -101.657716)
			(xy 306.278033 -101.454966) (xy 300.8249 -101.454966) (xy 300.8249 -119.6975) (xy 302.853342 -119.6975)
			(xy 302.857413 -119.641878) (xy 302.869539 -119.587441) (xy 302.889462 -119.53535) (xy 302.916758 -119.486715)
			(xy 302.950844 -119.442572) (xy 302.990993 -119.403863) (xy 303.036351 -119.371412) (xy 303.085951 -119.345911)
			(xy 303.138735 -119.327904) (xy 303.193578 -119.317774) (xy 303.249312 -119.315737) (xy 303.304749 -119.321837)
			(xy 303.358706 -119.335943) (xy 303.410035 -119.357755) (xy 303.457641 -119.386809) (xy 303.500509 -119.422484)
			(xy 303.537726 -119.464021) (xy 303.568499 -119.510534) (xy 303.592171 -119.561031) (xy 303.608239 -119.614438)
			(xy 303.616359 -119.669614) (xy 303.616868 -119.6975) (xy 303.616359 -119.725386) (xy 303.608239 -119.780562)
			(xy 303.592171 -119.833969) (xy 303.568499 -119.884466) (xy 303.537726 -119.930979) (xy 303.500509 -119.972516)
			(xy 303.457641 -120.008191) (xy 303.410035 -120.037245) (xy 303.358706 -120.059057) (xy 303.304749 -120.073163)
			(xy 303.249312 -120.079263) (xy 303.193578 -120.077226) (xy 303.138735 -120.067096) (xy 303.085951 -120.049089)
			(xy 303.036351 -120.023588) (xy 302.990993 -119.991137) (xy 302.950844 -119.952428) (xy 302.916758 -119.908285)
			(xy 302.889462 -119.85965) (xy 302.869539 -119.807559) (xy 302.857413 -119.753122) (xy 302.853342 -119.6975)
			(xy 300.8249 -119.6975) (xy 300.8249 -121.19991) (xy 300.825325 -121.209979) (xy 300.833042 -121.228581)
			(xy 300.839886 -121.235978) (xy 301.280576 -121.676668) (xy 301.287977 -121.683506) (xy 301.306576 -121.691218)
			(xy 301.316644 -121.691654)
		)
		(stroke
			(width 0)
			(type solid)
		)
		(fill yes)
		(layer "In7.Cu")
		(net "P52V_1")
	)
	(gr_poly
		(pts
			(xy 31.63443 -116.228114) (xy 31.644498 -116.227686) (xy 31.663096 -116.219965) (xy 31.670498 -116.213128)
			(xy 34.136838 -116.213128) (xy 34.146906 -116.212699) (xy 34.165503 -116.204978) (xy 34.172906 -116.198142)
			(xy 34.57956 -115.791488) (xy 34.586409 -115.784091) (xy 34.594145 -115.765492) (xy 34.594546 -115.75542)
			(xy 34.594546 -83.775042) (xy 34.594981 -83.764978) (xy 34.602715 -83.746393) (xy 34.609532 -83.738974)
			(xy 35.849052 -82.499454) (xy 35.856451 -82.49261) (xy 35.87505 -82.484886) (xy 35.88512 -82.484468)
			(xy 39.580058 -82.484468) (xy 39.590123 -82.484034) (xy 39.608709 -82.476301) (xy 39.616126 -82.469482)
			(xy 40.108378 -81.97723) (xy 40.11549 -81.963006) (xy 40.11676 -81.954878) (xy 40.124144 -81.911313)
			(xy 40.14643 -81.825805) (xy 40.177091 -81.742929) (xy 40.215825 -81.663505) (xy 40.262248 -81.588317)
			(xy 40.315903 -81.518106) (xy 40.37626 -81.453565) (xy 40.409114 -81.424018) (xy 40.41691 -81.416482)
			(xy 40.425844 -81.396748) (xy 40.426386 -81.385918) (xy 40.426386 -77.317346) (xy 40.425953 -77.30728)
			(xy 40.418223 -77.288692) (xy 40.4114 -77.281278) (xy 37.729668 -74.599546) (xy 37.722823 -74.592148)
			(xy 37.715097 -74.573549) (xy 37.714682 -74.563478) (xy 37.714682 -68.245482) (xy 37.714255 -68.235414)
			(xy 37.706534 -68.216816) (xy 37.699696 -68.209414) (xy 37.424868 -67.934586) (xy 37.417472 -67.927735)
			(xy 37.398873 -67.919999) (xy 37.3888 -67.9196) (xy 8.809482 -67.9196) (xy 8.799413 -67.920027) (xy 8.780814 -67.927746)
			(xy 8.773414 -67.934586) (xy 8.473186 -68.234814) (xy 8.466332 -68.242209) (xy 8.45859 -68.260808)
			(xy 8.4582 -68.270882) (xy 8.4582 -70.939914) (xy 8.859012 -70.939914) (xy 8.859529 -70.895741) (xy 8.867385 -70.807746)
			(xy 8.883045 -70.7208) (xy 8.906383 -70.635593) (xy 8.937216 -70.552803) (xy 8.975297 -70.473086)
			(xy 9.020325 -70.397077) (xy 9.071942 -70.325379) (xy 9.129737 -70.258561) (xy 9.193252 -70.197155)
			(xy 9.227312 -70.169024) (xy 9.236202 -70.161658) (xy 9.246108 -70.141084) (xy 9.246108 -70.038722)
			(xy 9.236202 -70.018148) (xy 9.227312 -70.010782) (xy 9.193255 -69.982647) (xy 9.129742 -69.921238)
			(xy 9.071948 -69.854419) (xy 9.020332 -69.782721) (xy 8.975302 -69.706713) (xy 8.937217 -69.626998)
			(xy 8.90638 -69.544209) (xy 8.883034 -69.459004) (xy 8.867365 -69.372059) (xy 8.859498 -69.284065)
			(xy 8.859012 -69.239892) (xy 8.859511 -69.195404) (xy 8.867487 -69.106785) (xy 8.883374 -69.019239)
			(xy 8.907045 -68.933468) (xy 8.938309 -68.850165) (xy 8.976915 -68.77) (xy 9.022551 -68.693618) (xy 9.07485 -68.621635)
			(xy 9.133391 -68.554629) (xy 9.197703 -68.493141) (xy 9.267268 -68.437665) (xy 9.341525 -68.388648)
			(xy 9.419878 -68.346485) (xy 9.501694 -68.311514) (xy 9.586316 -68.284019) (xy 9.673062 -68.26422)
			(xy 9.761233 -68.252276) (xy 9.85012 -68.248285) (xy 9.939007 -68.252276) (xy 10.027178 -68.26422)
			(xy 10.113924 -68.284019) (xy 10.198546 -68.311514) (xy 10.280362 -68.346485) (xy 10.358715 -68.388648)
			(xy 10.432972 -68.437665) (xy 10.502537 -68.493141) (xy 10.566849 -68.554629) (xy 10.62539 -68.621635)
			(xy 10.677689 -68.693618) (xy 10.723325 -68.77) (xy 10.761931 -68.850165) (xy 10.793195 -68.933468)
			(xy 10.816866 -69.019239) (xy 10.832753 -69.106785) (xy 10.840729 -69.195404) (xy 10.841228 -69.239892)
			(xy 10.840737 -69.284065) (xy 10.83288 -69.372062) (xy 10.817219 -69.45901) (xy 10.793879 -69.544217)
			(xy 10.763044 -69.627009) (xy 10.724959 -69.706725) (xy 10.679928 -69.782734) (xy 10.628308 -69.854431)
			(xy 10.570509 -69.921248) (xy 10.50699 -69.982652) (xy 10.472928 -70.010782) (xy 10.464038 -70.018148)
			(xy 10.454132 -70.038722) (xy 10.454132 -70.141084) (xy 10.464038 -70.161658) (xy 10.472928 -70.169024)
			(xy 10.506988 -70.197155) (xy 10.570501 -70.258565) (xy 10.628294 -70.325384) (xy 10.679911 -70.397083)
			(xy 10.72494 -70.473092) (xy 10.763024 -70.552807) (xy 10.793862 -70.635596) (xy 10.817207 -70.720801)
			(xy 10.832875 -70.807746) (xy 10.840742 -70.895741) (xy 10.841228 -70.939914) (xy 11.399012 -70.939914)
			(xy 11.399529 -70.895741) (xy 11.407385 -70.807746) (xy 11.423045 -70.7208) (xy 11.446383 -70.635593)
			(xy 11.477216 -70.552803) (xy 11.515297 -70.473086) (xy 11.560325 -70.397077) (xy 11.611942 -70.325379)
			(xy 11.669737 -70.258561) (xy 11.733252 -70.197155) (xy 11.767312 -70.169024) (xy 11.776202 -70.161658)
			(xy 11.786108 -70.141084) (xy 11.786108 -70.038722) (xy 11.776202 -70.018148) (xy 11.767312 -70.010782)
			(xy 11.733255 -69.982647) (xy 11.669742 -69.921238) (xy 11.611948 -69.854419) (xy 11.560332 -69.782721)
			(xy 11.515302 -69.706713) (xy 11.477217 -69.626998) (xy 11.44638 -69.544209) (xy 11.423034 -69.459004)
			(xy 11.407365 -69.372059) (xy 11.399498 -69.284065) (xy 11.399012 -69.239892) (xy 11.399511 -69.195404)
			(xy 11.407487 -69.106785) (xy 11.423374 -69.019239) (xy 11.447045 -68.933468) (xy 11.478309 -68.850165)
			(xy 11.516915 -68.77) (xy 11.562551 -68.693618) (xy 11.61485 -68.621635) (xy 11.673391 -68.554629)
			(xy 11.737703 -68.493141) (xy 11.807268 -68.437665) (xy 11.881525 -68.388648) (xy 11.959878 -68.346485)
			(xy 12.041694 -68.311514) (xy 12.126316 -68.284019) (xy 12.213062 -68.26422) (xy 12.301233 -68.252276)
			(xy 12.39012 -68.248285) (xy 12.479007 -68.252276) (xy 12.567178 -68.26422) (xy 12.653924 -68.284019)
			(xy 12.738546 -68.311514) (xy 12.820362 -68.346485) (xy 12.898715 -68.388648) (xy 12.972972 -68.437665)
			(xy 13.042537 -68.493141) (xy 13.106849 -68.554629) (xy 13.16539 -68.621635) (xy 13.217689 -68.693618)
			(xy 13.263325 -68.77) (xy 13.301931 -68.850165) (xy 13.333195 -68.933468) (xy 13.356866 -69.019239)
			(xy 13.372753 -69.106785) (xy 13.380729 -69.195404) (xy 13.381228 -69.239892) (xy 13.380737 -69.284065)
			(xy 13.37288 -69.372062) (xy 13.357219 -69.45901) (xy 13.333879 -69.544217) (xy 13.303044 -69.627009)
			(xy 13.264959 -69.706725) (xy 13.219928 -69.782734) (xy 13.168308 -69.854431) (xy 13.110509 -69.921248)
			(xy 13.04699 -69.982652) (xy 13.012928 -70.010782) (xy 13.004038 -70.018148) (xy 12.994132 -70.038722)
			(xy 12.994132 -70.141084) (xy 13.004038 -70.161658) (xy 13.012928 -70.169024) (xy 13.046988 -70.197155)
			(xy 13.110501 -70.258565) (xy 13.168294 -70.325384) (xy 13.219911 -70.397083) (xy 13.26494 -70.473092)
			(xy 13.303024 -70.552807) (xy 13.333862 -70.635596) (xy 13.357207 -70.720801) (xy 13.372875 -70.807746)
			(xy 13.380742 -70.895741) (xy 13.381228 -70.939914) (xy 13.380729 -70.984402) (xy 13.372753 -71.073021)
			(xy 13.356866 -71.160567) (xy 13.333195 -71.246338) (xy 13.301931 -71.329641) (xy 13.263325 -71.409806)
			(xy 13.217689 -71.486188) (xy 13.16539 -71.558171) (xy 13.106849 -71.625177) (xy 13.042537 -71.686665)
			(xy 12.972972 -71.742141) (xy 12.898715 -71.791158) (xy 12.820362 -71.833321) (xy 12.738546 -71.868292)
			(xy 12.653924 -71.895787) (xy 12.567178 -71.915586) (xy 12.479007 -71.92753) (xy 12.39012 -71.931522)
			(xy 12.301233 -71.92753) (xy 12.213062 -71.915586) (xy 12.126316 -71.895787) (xy 12.041694 -71.868292)
			(xy 11.959878 -71.833321) (xy 11.881525 -71.791158) (xy 11.807268 -71.742141) (xy 11.737703 -71.686665)
			(xy 11.673391 -71.625177) (xy 11.61485 -71.558171) (xy 11.562551 -71.486188) (xy 11.516915 -71.409806)
			(xy 11.478309 -71.329641) (xy 11.447045 -71.246338) (xy 11.423374 -71.160567) (xy 11.407487 -71.073021)
			(xy 11.399511 -70.984402) (xy 11.399012 -70.939914) (xy 10.841228 -70.939914) (xy 10.840729 -70.984402)
			(xy 10.832753 -71.073021) (xy 10.816866 -71.160567) (xy 10.793195 -71.246338) (xy 10.761931 -71.329641)
			(xy 10.723325 -71.409806) (xy 10.677689 -71.486188) (xy 10.62539 -71.558171) (xy 10.566849 -71.625177)
			(xy 10.502537 -71.686665) (xy 10.432972 -71.742141) (xy 10.358715 -71.791158) (xy 10.280362 -71.833321)
			(xy 10.198546 -71.868292) (xy 10.113924 -71.895787) (xy 10.027178 -71.915586) (xy 9.939007 -71.92753)
			(xy 9.85012 -71.931522) (xy 9.761233 -71.92753) (xy 9.673062 -71.915586) (xy 9.586316 -71.895787)
			(xy 9.501694 -71.868292) (xy 9.419878 -71.833321) (xy 9.341525 -71.791158) (xy 9.267268 -71.742141)
			(xy 9.197703 -71.686665) (xy 9.133391 -71.625177) (xy 9.07485 -71.558171) (xy 9.022551 -71.486188)
			(xy 8.976915 -71.409806) (xy 8.938309 -71.329641) (xy 8.907045 -71.246338) (xy 8.883374 -71.160567)
			(xy 8.867487 -71.073021) (xy 8.859511 -70.984402) (xy 8.859012 -70.939914) (xy 8.4582 -70.939914)
			(xy 8.4582 -76.019914) (xy 8.859012 -76.019914) (xy 8.859529 -75.975741) (xy 8.867385 -75.887746)
			(xy 8.883045 -75.8008) (xy 8.906383 -75.715593) (xy 8.937216 -75.632803) (xy 8.975297 -75.553086)
			(xy 9.020325 -75.477077) (xy 9.071942 -75.405379) (xy 9.129737 -75.338561) (xy 9.193252 -75.277155)
			(xy 9.227312 -75.249024) (xy 9.236202 -75.241658) (xy 9.246108 -75.221084) (xy 9.246108 -75.118722)
			(xy 9.236202 -75.098148) (xy 9.227312 -75.090782) (xy 9.193255 -75.062647) (xy 9.129742 -75.001238)
			(xy 9.071948 -74.934419) (xy 9.020332 -74.862721) (xy 8.975302 -74.786713) (xy 8.937217 -74.706998)
			(xy 8.90638 -74.624209) (xy 8.883034 -74.539004) (xy 8.867365 -74.452059) (xy 8.859498 -74.364065)
			(xy 8.859012 -74.319892) (xy 8.859511 -74.275404) (xy 8.867487 -74.186785) (xy 8.883374 -74.099239)
			(xy 8.907045 -74.013468) (xy 8.938309 -73.930165) (xy 8.976915 -73.85) (xy 9.022551 -73.773618) (xy 9.07485 -73.701635)
			(xy 9.133391 -73.634629) (xy 9.197703 -73.573141) (xy 9.267268 -73.517665) (xy 9.341525 -73.468648)
			(xy 9.419878 -73.426485) (xy 9.501694 -73.391514) (xy 9.586316 -73.364019) (xy 9.673062 -73.34422)
			(xy 9.761233 -73.332276) (xy 9.85012 -73.328285) (xy 9.939007 -73.332276) (xy 10.027178 -73.34422)
			(xy 10.113924 -73.364019) (xy 10.198546 -73.391514) (xy 10.280362 -73.426485) (xy 10.358715 -73.468648)
			(xy 10.432972 -73.517665) (xy 10.502537 -73.573141) (xy 10.566849 -73.634629) (xy 10.62539 -73.701635)
			(xy 10.677689 -73.773618) (xy 10.723325 -73.85) (xy 10.761931 -73.930165) (xy 10.793195 -74.013468)
			(xy 10.816866 -74.099239) (xy 10.832753 -74.186785) (xy 10.840729 -74.275404) (xy 10.841228 -74.319892)
			(xy 10.840737 -74.364065) (xy 10.83288 -74.452062) (xy 10.817219 -74.53901) (xy 10.793879 -74.624217)
			(xy 10.763044 -74.707009) (xy 10.724959 -74.786725) (xy 10.679928 -74.862734) (xy 10.628308 -74.934431)
			(xy 10.570509 -75.001248) (xy 10.50699 -75.062652) (xy 10.472928 -75.090782) (xy 10.464038 -75.098148)
			(xy 10.454132 -75.118722) (xy 10.454132 -75.221084) (xy 10.464038 -75.241658) (xy 10.472928 -75.249024)
			(xy 10.506988 -75.277155) (xy 10.570501 -75.338565) (xy 10.628294 -75.405384) (xy 10.679911 -75.477083)
			(xy 10.72494 -75.553092) (xy 10.763024 -75.632807) (xy 10.793862 -75.715596) (xy 10.817207 -75.800801)
			(xy 10.832875 -75.887746) (xy 10.840742 -75.975741) (xy 10.841228 -76.019914) (xy 11.399012 -76.019914)
			(xy 11.399529 -75.975741) (xy 11.407385 -75.887746) (xy 11.423045 -75.8008) (xy 11.446383 -75.715593)
			(xy 11.477216 -75.632803) (xy 11.515297 -75.553086) (xy 11.560325 -75.477077) (xy 11.611942 -75.405379)
			(xy 11.669737 -75.338561) (xy 11.733252 -75.277155) (xy 11.767312 -75.249024) (xy 11.776202 -75.241658)
			(xy 11.786108 -75.221084) (xy 11.786108 -75.118722) (xy 11.776202 -75.098148) (xy 11.767312 -75.090782)
			(xy 11.733255 -75.062647) (xy 11.669742 -75.001238) (xy 11.611948 -74.934419) (xy 11.560332 -74.862721)
			(xy 11.515302 -74.786713) (xy 11.477217 -74.706998) (xy 11.44638 -74.624209) (xy 11.423034 -74.539004)
			(xy 11.407365 -74.452059) (xy 11.399498 -74.364065) (xy 11.399012 -74.319892) (xy 11.399511 -74.275404)
			(xy 11.407487 -74.186785) (xy 11.423374 -74.099239) (xy 11.447045 -74.013468) (xy 11.478309 -73.930165)
			(xy 11.516915 -73.85) (xy 11.562551 -73.773618) (xy 11.61485 -73.701635) (xy 11.673391 -73.634629)
			(xy 11.737703 -73.573141) (xy 11.807268 -73.517665) (xy 11.881525 -73.468648) (xy 11.959878 -73.426485)
			(xy 12.041694 -73.391514) (xy 12.126316 -73.364019) (xy 12.213062 -73.34422) (xy 12.301233 -73.332276)
			(xy 12.39012 -73.328285) (xy 12.479007 -73.332276) (xy 12.567178 -73.34422) (xy 12.653924 -73.364019)
			(xy 12.738546 -73.391514) (xy 12.820362 -73.426485) (xy 12.898715 -73.468648) (xy 12.972972 -73.517665)
			(xy 13.042537 -73.573141) (xy 13.106849 -73.634629) (xy 13.16539 -73.701635) (xy 13.217689 -73.773618)
			(xy 13.263325 -73.85) (xy 13.301931 -73.930165) (xy 13.333195 -74.013468) (xy 13.356866 -74.099239)
			(xy 13.372753 -74.186785) (xy 13.380729 -74.275404) (xy 13.381228 -74.319892) (xy 13.380737 -74.364065)
			(xy 13.37288 -74.452062) (xy 13.357219 -74.53901) (xy 13.333879 -74.624217) (xy 13.303044 -74.707009)
			(xy 13.264959 -74.786725) (xy 13.219928 -74.862734) (xy 13.168308 -74.934431) (xy 13.110509 -75.001248)
			(xy 13.04699 -75.062652) (xy 13.012928 -75.090782) (xy 13.004038 -75.098148) (xy 12.994132 -75.118722)
			(xy 12.994132 -75.221084) (xy 13.004038 -75.241658) (xy 13.012928 -75.249024) (xy 13.046988 -75.277155)
			(xy 13.110501 -75.338565) (xy 13.168294 -75.405384) (xy 13.219911 -75.477083) (xy 13.26494 -75.553092)
			(xy 13.303024 -75.632807) (xy 13.333862 -75.715596) (xy 13.357207 -75.800801) (xy 13.372875 -75.887746)
			(xy 13.380742 -75.975741) (xy 13.381228 -76.019914) (xy 13.380729 -76.064402) (xy 13.372753 -76.153021)
			(xy 13.356866 -76.240567) (xy 13.333195 -76.326338) (xy 13.301931 -76.409641) (xy 13.263325 -76.489806)
			(xy 13.217689 -76.566188) (xy 13.16539 -76.638171) (xy 13.106849 -76.705177) (xy 13.042537 -76.766665)
			(xy 12.972972 -76.822141) (xy 12.898715 -76.871158) (xy 12.820362 -76.913321) (xy 12.738546 -76.948292)
			(xy 12.653924 -76.975787) (xy 12.567178 -76.995586) (xy 12.479007 -77.00753) (xy 12.39012 -77.011522)
			(xy 12.301233 -77.00753) (xy 12.213062 -76.995586) (xy 12.126316 -76.975787) (xy 12.041694 -76.948292)
			(xy 11.959878 -76.913321) (xy 11.881525 -76.871158) (xy 11.807268 -76.822141) (xy 11.737703 -76.766665)
			(xy 11.673391 -76.705177) (xy 11.61485 -76.638171) (xy 11.562551 -76.566188) (xy 11.516915 -76.489806)
			(xy 11.478309 -76.409641) (xy 11.447045 -76.326338) (xy 11.423374 -76.240567) (xy 11.407487 -76.153021)
			(xy 11.399511 -76.064402) (xy 11.399012 -76.019914) (xy 10.841228 -76.019914) (xy 10.840729 -76.064402)
			(xy 10.832753 -76.153021) (xy 10.816866 -76.240567) (xy 10.793195 -76.326338) (xy 10.761931 -76.409641)
			(xy 10.723325 -76.489806) (xy 10.677689 -76.566188) (xy 10.62539 -76.638171) (xy 10.566849 -76.705177)
			(xy 10.502537 -76.766665) (xy 10.432972 -76.822141) (xy 10.358715 -76.871158) (xy 10.280362 -76.913321)
			(xy 10.198546 -76.948292) (xy 10.113924 -76.975787) (xy 10.027178 -76.995586) (xy 9.939007 -77.00753)
			(xy 9.85012 -77.011522) (xy 9.761233 -77.00753) (xy 9.673062 -76.995586) (xy 9.586316 -76.975787)
			(xy 9.501694 -76.948292) (xy 9.419878 -76.913321) (xy 9.341525 -76.871158) (xy 9.267268 -76.822141)
			(xy 9.197703 -76.766665) (xy 9.133391 -76.705177) (xy 9.07485 -76.638171) (xy 9.022551 -76.566188)
			(xy 8.976915 -76.489806) (xy 8.938309 -76.409641) (xy 8.907045 -76.326338) (xy 8.883374 -76.240567)
			(xy 8.867487 -76.153021) (xy 8.859511 -76.064402) (xy 8.859012 -76.019914) (xy 8.4582 -76.019914)
			(xy 8.4582 -76.788518) (xy 8.458627 -76.798587) (xy 8.466346 -76.817186) (xy 8.473186 -76.824586)
			(xy 9.129014 -77.480414) (xy 9.136409 -77.487268) (xy 9.155008 -77.49501) (xy 9.165082 -77.4954)
			(xy 11.67511 -77.4954) (xy 11.685179 -77.495825) (xy 11.703781 -77.503542) (xy 11.711178 -77.510386)
			(xy 16.911574 -82.710782) (xy 16.91841 -82.718184) (xy 16.926119 -82.736782) (xy 16.92656 -82.74685)
			(xy 16.92656 -89.536778) (xy 16.926671 -89.541875) (xy 16.928715 -89.551863) (xy 16.930624 -89.55659)
			(xy 16.945927 -89.593492) (xy 16.97062 -89.669474) (xy 16.988402 -89.747364) (xy 16.999128 -89.826535)
			(xy 17.002714 -89.906348) (xy 16.999129 -89.986162) (xy 16.988402 -90.065332) (xy 16.970621 -90.143222)
			(xy 16.945928 -90.219204) (xy 16.930624 -90.256106) (xy 16.928754 -90.260845) (xy 16.926708 -90.270825)
			(xy 16.92656 -90.275918) (xy 16.92656 -115.609116) (xy 16.926988 -115.619184) (xy 16.934713 -115.637778)
			(xy 16.941546 -115.645184) (xy 17.50949 -116.213128) (xy 17.516884 -116.219984) (xy 17.535483 -116.227733)
			(xy 17.545558 -116.228114)
		)
		(stroke
			(width 0)
			(type solid)
		)
		(fill yes)
		(layer "In7.Cu")
		(net "P52V_FAN")
	)
	(gr_poly
		(pts
			(xy 36.068 -145.984468)
			(arc
				(start 4.99999 -145.984468)
				(mid 2.182524 -144.817436)
				(end 1.015492 -141.99997)
			)
			(arc
				(start 1.015492 -131.729988)
				(mid 1.596724 -130.326643)
				(end 2.999994 -129.745232)
			)
			(arc
				(start 9.600184 -129.745232)
				(mid 10.671529 -129.301467)
				(end 11.115294 -128.230122)
			)
			(xy 11.115548 -128.230122)
			(arc
				(start 11.115548 -116.730018)
				(mid 10.671634 -115.658314)
				(end 9.59993 -115.2144)
			)
			(arc
				(start 2.999994 -115.2144)
				(mid 1.596739 -114.633153)
				(end 1.015492 -113.229898)
			)
			(arc
				(start 1.015492 -34.569908)
				(mid 1.596724 -33.166563)
				(end 2.999994 -32.585152)
			)
			(arc
				(start 9.600184 -32.585152)
				(mid 10.671454 -32.141312)
				(end 11.115294 -31.070042)
			)
			(xy 11.115548 -31.070042) (xy 11.115548 -19.569938)
			(arc
				(start 11.115294 -19.569938)
				(mid 10.671439 -18.498758)
				(end 9.600184 -18.054828)
			)
			(arc
				(start 2.999994 -18.054828)
				(mid 1.596829 -17.473671)
				(end 1.015492 -16.07058)
			)
			(arc
				(start 1.015492 -4.99999)
				(mid 2.182524 -2.182524)
				(end 4.99999 -1.015492)
			)
			(arc
				(start 323.000116 -1.015492)
				(mid 325.817582 -2.182524)
				(end 326.984614 -4.99999)
			)
			(arc
				(start 326.984614 -141.99997)
				(mid 325.817582 -144.817436)
				(end 323.000116 -145.984468)
			)
			(xy 236.728 -145.984468) (xy 236.728 -146.49196)
			(arc
				(start 323.000116 -146.49196)
				(mid 326.176433 -145.176287)
				(end 327.492106 -141.99997)
			)
			(arc
				(start 327.492106 -4.99999)
				(mid 326.176433 -1.823673)
				(end 323.000116 -0.508)
			)
			(arc
				(start 4.99999 -0.508)
				(mid 1.823673 -1.823673)
				(end 0.508 -4.99999)
			)
			(arc
				(start 0.508 -16.070072)
				(mid 1.237888 -17.832178)
				(end 2.999994 -18.562066)
			)
			(arc
				(start 9.600184 -18.562066)
				(mid 10.312947 -18.857249)
				(end 10.608056 -19.569938)
			)
			(arc
				(start 10.608056 -31.070042)
				(mid 10.312783 -31.782641)
				(end 9.600184 -32.077914)
			)
			(arc
				(start 2.999994 -32.077914)
				(mid 1.237888 -32.807802)
				(end 0.508 -34.569908)
			)
			(arc
				(start 0.508 -113.229898)
				(mid 1.237888 -114.992004)
				(end 2.999994 -115.721892)
			)
			(arc
				(start 9.59993 -115.721892)
				(mid 10.312783 -116.017165)
				(end 10.608056 -116.730018)
			)
			(arc
				(start 10.608056 -128.230122)
				(mid 10.312857 -128.942795)
				(end 9.600184 -129.237994)
			)
			(arc
				(start 2.999994 -129.237994)
				(mid 1.237888 -129.967882)
				(end 0.508 -131.729988)
			)
			(arc
				(start 0.508 -141.99997)
				(mid 1.823673 -145.176287)
				(end 4.99999 -146.49196)
			)
			(xy 36.068 -146.49196)
		)
		(stroke
			(width 0)
			(type solid)
		)
		(fill yes)
		(layer "In7.Cu")
		(net "GND")
	)
	(gr_poly
		(pts
			(xy 274.303744 -144.703546) (xy 274.313809 -144.703113) (xy 274.332397 -144.695382) (xy 274.339812 -144.68856)
			(xy 274.965922 -144.06245) (xy 274.972769 -144.055053) (xy 274.980498 -144.036453) (xy 274.980908 -144.026382)
			(xy 274.980908 -95.77578) (xy 274.980511 -95.767129) (xy 274.974653 -95.750843) (xy 274.963713 -95.737432)
			(xy 274.956524 -95.7326) (xy 274.870926 -95.680276) (xy 274.845018 -95.67926) (xy 274.832826 -95.68561)
			(xy 274.795024 -95.704465) (xy 274.716557 -95.735767) (xy 274.635477 -95.759493) (xy 274.552513 -95.775429)
			(xy 274.468412 -95.783431) (xy 274.426172 -95.783908) (xy 274.383824 -95.783403) (xy 274.299513 -95.77535)
			(xy 274.216348 -95.759319) (xy 274.135085 -95.735455) (xy 274.056457 -95.703975) (xy 273.981178 -95.665164)
			(xy 273.909928 -95.619373) (xy 273.843354 -95.567017) (xy 273.782058 -95.508569) (xy 273.726596 -95.44456)
			(xy 273.677468 -95.375569) (xy 273.635121 -95.30222) (xy 273.599938 -95.225178) (xy 273.572238 -95.145141)
			(xy 273.552271 -95.062833) (xy 273.540217 -94.978999) (xy 273.536187 -94.8944) (xy 273.540217 -94.809801)
			(xy 273.552271 -94.725967) (xy 273.572238 -94.643659) (xy 273.599938 -94.563622) (xy 273.635121 -94.48658)
			(xy 273.677468 -94.413231) (xy 273.726596 -94.34424) (xy 273.782058 -94.280231) (xy 273.843354 -94.221783)
			(xy 273.909928 -94.169427) (xy 273.981178 -94.123636) (xy 274.056457 -94.084825) (xy 274.135085 -94.053345)
			(xy 274.216348 -94.029481) (xy 274.299513 -94.01345) (xy 274.383824 -94.005397) (xy 274.426172 -94.004892)
			(xy 274.468413 -94.005376) (xy 274.552517 -94.01336) (xy 274.635483 -94.029286) (xy 274.716565 -94.053011)
			(xy 274.79503 -94.084322) (xy 274.832826 -94.10319) (xy 274.845018 -94.10954) (xy 274.870926 -94.108524)
			(xy 274.956524 -94.0562) (xy 274.963741 -94.051405) (xy 274.97468 -94.037983) (xy 274.980505 -94.021677)
			(xy 274.980908 -94.01302) (xy 274.980908 -93.426788) (xy 274.980368 -93.416801) (xy 274.972653 -93.398372)
			(xy 274.965922 -93.390974) (xy 273.559778 -91.98483) (xy 273.552934 -91.977431) (xy 273.545213 -91.958832)
			(xy 273.544792 -91.948762) (xy 273.544792 -88.899238) (xy 273.545226 -88.889173) (xy 273.552955 -88.870584)
			(xy 273.559778 -88.86317) (xy 274.965922 -87.457026) (xy 274.972729 -87.44968) (xy 274.980447 -87.431217)
			(xy 274.980908 -87.421212) (xy 274.980908 -62.40399) (xy 274.980484 -62.39392) (xy 274.972767 -62.375318)
			(xy 274.965922 -62.367922) (xy 273.953986 -61.355986) (xy 273.946591 -61.349132) (xy 273.927992 -61.34139)
			(xy 273.917918 -61.341) (xy 256.103882 -61.341) (xy 256.093813 -61.341427) (xy 256.075214 -61.349146)
			(xy 256.067814 -61.355986) (xy 253.811786 -63.612014) (xy 253.804391 -63.618868) (xy 253.785792 -63.62661)
			(xy 253.775718 -63.627) (xy 243.801646 -63.627) (xy 243.79158 -63.627433) (xy 243.77299 -63.635161)
			(xy 243.765578 -63.641986) (xy 242.83035 -64.577214) (xy 242.8235 -64.584611) (xy 242.815763 -64.603209)
			(xy 242.815364 -64.613282) (xy 242.815364 -68.734616) (xy 270.30705 -68.734616) (xy 270.30705 -68.64992)
			(xy 270.315101 -68.565606) (xy 270.33113 -68.48244) (xy 270.354991 -68.401173) (xy 270.38647 -68.322543)
			(xy 270.425281 -68.247262) (xy 270.471071 -68.17601) (xy 270.523427 -68.109434) (xy 270.581875 -68.048136)
			(xy 270.645885 -67.992671) (xy 270.714877 -67.943542) (xy 270.788227 -67.901193) (xy 270.86527 -67.866009)
			(xy 270.945309 -67.838307) (xy 271.027618 -67.818339) (xy 271.111453 -67.806286) (xy 271.196054 -67.802256)
			(xy 271.280655 -67.806286) (xy 271.36449 -67.818339) (xy 271.446799 -67.838307) (xy 271.526838 -67.866009)
			(xy 271.603881 -67.901193) (xy 271.677231 -67.943542) (xy 271.746223 -67.992671) (xy 271.810233 -68.048136)
			(xy 271.868681 -68.109434) (xy 271.921037 -68.17601) (xy 271.966827 -68.247262) (xy 272.005638 -68.322543)
			(xy 272.037117 -68.401173) (xy 272.060978 -68.48244) (xy 272.077007 -68.565606) (xy 272.085058 -68.64992)
			(xy 272.085562 -68.692268) (xy 272.085058 -68.734616) (xy 272.077007 -68.81893) (xy 272.060978 -68.902096)
			(xy 272.037117 -68.983363) (xy 272.005638 -69.061993) (xy 271.966827 -69.137274) (xy 271.921037 -69.208526)
			(xy 271.868681 -69.275102) (xy 271.810233 -69.3364) (xy 271.746223 -69.391865) (xy 271.677231 -69.440994)
			(xy 271.603881 -69.483343) (xy 271.526838 -69.518527) (xy 271.446799 -69.546229) (xy 271.36449 -69.566197)
			(xy 271.280655 -69.57825) (xy 271.196054 -69.582281) (xy 271.111453 -69.57825) (xy 271.027618 -69.566197)
			(xy 270.945309 -69.546229) (xy 270.86527 -69.518527) (xy 270.788227 -69.483343) (xy 270.714877 -69.440994)
			(xy 270.645885 -69.391865) (xy 270.581875 -69.3364) (xy 270.523427 -69.275102) (xy 270.471071 -69.208526)
			(xy 270.425281 -69.137274) (xy 270.38647 -69.061993) (xy 270.354991 -68.983363) (xy 270.33113 -68.902096)
			(xy 270.315101 -68.81893) (xy 270.30705 -68.734616) (xy 242.815364 -68.734616) (xy 242.815364 -70.207816)
			(xy 268.757396 -70.207816) (xy 268.757396 -70.12312) (xy 268.765447 -70.038806) (xy 268.781476 -69.95564)
			(xy 268.805337 -69.874373) (xy 268.836816 -69.795743) (xy 268.875627 -69.720462) (xy 268.921417 -69.64921)
			(xy 268.973773 -69.582634) (xy 269.032221 -69.521336) (xy 269.096231 -69.465871) (xy 269.165223 -69.416742)
			(xy 269.238573 -69.374393) (xy 269.315616 -69.339209) (xy 269.395655 -69.311507) (xy 269.477964 -69.291539)
			(xy 269.561799 -69.279486) (xy 269.6464 -69.275456) (xy 269.731001 -69.279486) (xy 269.814836 -69.291539)
			(xy 269.897145 -69.311507) (xy 269.977184 -69.339209) (xy 270.054227 -69.374393) (xy 270.127577 -69.416742)
			(xy 270.196569 -69.465871) (xy 270.260579 -69.521336) (xy 270.319027 -69.582634) (xy 270.371383 -69.64921)
			(xy 270.417173 -69.720462) (xy 270.455984 -69.795743) (xy 270.487463 -69.874373) (xy 270.511324 -69.95564)
			(xy 270.527353 -70.038806) (xy 270.535404 -70.12312) (xy 270.535908 -70.165468) (xy 270.535404 -70.207816)
			(xy 270.527353 -70.29213) (xy 270.511324 -70.375296) (xy 270.487463 -70.456563) (xy 270.455984 -70.535193)
			(xy 270.417173 -70.610474) (xy 270.371383 -70.681726) (xy 270.319027 -70.748302) (xy 270.260579 -70.8096)
			(xy 270.196569 -70.865065) (xy 270.127577 -70.914194) (xy 270.054227 -70.956543) (xy 269.977184 -70.991727)
			(xy 269.897145 -71.019429) (xy 269.814836 -71.039397) (xy 269.731001 -71.05145) (xy 269.6464 -71.055481)
			(xy 269.561799 -71.05145) (xy 269.477964 -71.039397) (xy 269.395655 -71.019429) (xy 269.315616 -70.991727)
			(xy 269.238573 -70.956543) (xy 269.165223 -70.914194) (xy 269.096231 -70.865065) (xy 269.032221 -70.8096)
			(xy 268.973773 -70.748302) (xy 268.921417 -70.681726) (xy 268.875627 -70.610474) (xy 268.836816 -70.535193)
			(xy 268.805337 -70.456563) (xy 268.781476 -70.375296) (xy 268.765447 -70.29213) (xy 268.757396 -70.207816)
			(xy 242.815364 -70.207816) (xy 242.815364 -80.799616) (xy 270.301462 -80.799616) (xy 270.301462 -80.71492)
			(xy 270.309513 -80.630606) (xy 270.325542 -80.54744) (xy 270.349403 -80.466173) (xy 270.380882 -80.387543)
			(xy 270.419693 -80.312262) (xy 270.465483 -80.24101) (xy 270.517839 -80.174434) (xy 270.576287 -80.113136)
			(xy 270.640297 -80.057671) (xy 270.709289 -80.008542) (xy 270.782639 -79.966193) (xy 270.859682 -79.931009)
			(xy 270.939721 -79.903307) (xy 271.02203 -79.883339) (xy 271.105865 -79.871286) (xy 271.190466 -79.867256)
			(xy 271.275067 -79.871286) (xy 271.358902 -79.883339) (xy 271.441211 -79.903307) (xy 271.52125 -79.931009)
			(xy 271.598293 -79.966193) (xy 271.671643 -80.008542) (xy 271.740635 -80.057671) (xy 271.804645 -80.113136)
			(xy 271.863093 -80.174434) (xy 271.915449 -80.24101) (xy 271.961239 -80.312262) (xy 272.00005 -80.387543)
			(xy 272.031529 -80.466173) (xy 272.05539 -80.54744) (xy 272.071419 -80.630606) (xy 272.07947 -80.71492)
			(xy 272.079974 -80.757268) (xy 272.07947 -80.799616) (xy 272.071419 -80.88393) (xy 272.05539 -80.967096)
			(xy 272.031529 -81.048363) (xy 272.00005 -81.126993) (xy 271.961239 -81.202274) (xy 271.915449 -81.273526)
			(xy 271.863093 -81.340102) (xy 271.804645 -81.4014) (xy 271.740635 -81.456865) (xy 271.671643 -81.505994)
			(xy 271.598293 -81.548343) (xy 271.52125 -81.583527) (xy 271.441211 -81.611229) (xy 271.358902 -81.631197)
			(xy 271.275067 -81.64325) (xy 271.190466 -81.647281) (xy 271.105865 -81.64325) (xy 271.02203 -81.631197)
			(xy 270.939721 -81.611229) (xy 270.859682 -81.583527) (xy 270.782639 -81.548343) (xy 270.709289 -81.505994)
			(xy 270.640297 -81.456865) (xy 270.576287 -81.4014) (xy 270.517839 -81.340102) (xy 270.465483 -81.273526)
			(xy 270.419693 -81.202274) (xy 270.380882 -81.126993) (xy 270.349403 -81.048363) (xy 270.325542 -80.967096)
			(xy 270.309513 -80.88393) (xy 270.301462 -80.799616) (xy 242.815364 -80.799616) (xy 242.815364 -82.272816)
			(xy 268.757396 -82.272816) (xy 268.757396 -82.18812) (xy 268.765447 -82.103806) (xy 268.781476 -82.02064)
			(xy 268.805337 -81.939373) (xy 268.836816 -81.860743) (xy 268.875627 -81.785462) (xy 268.921417 -81.71421)
			(xy 268.973773 -81.647634) (xy 269.032221 -81.586336) (xy 269.096231 -81.530871) (xy 269.165223 -81.481742)
			(xy 269.238573 -81.439393) (xy 269.315616 -81.404209) (xy 269.395655 -81.376507) (xy 269.477964 -81.356539)
			(xy 269.561799 -81.344486) (xy 269.6464 -81.340456) (xy 269.731001 -81.344486) (xy 269.814836 -81.356539)
			(xy 269.897145 -81.376507) (xy 269.977184 -81.404209) (xy 270.054227 -81.439393) (xy 270.127577 -81.481742)
			(xy 270.196569 -81.530871) (xy 270.260579 -81.586336) (xy 270.319027 -81.647634) (xy 270.371383 -81.71421)
			(xy 270.417173 -81.785462) (xy 270.455984 -81.860743) (xy 270.487463 -81.939373) (xy 270.511324 -82.02064)
			(xy 270.527353 -82.103806) (xy 270.535404 -82.18812) (xy 270.535908 -82.230468) (xy 270.535404 -82.272816)
			(xy 270.527353 -82.35713) (xy 270.511324 -82.440296) (xy 270.487463 -82.521563) (xy 270.455984 -82.600193)
			(xy 270.417173 -82.675474) (xy 270.371383 -82.746726) (xy 270.319027 -82.813302) (xy 270.260579 -82.8746)
			(xy 270.196569 -82.930065) (xy 270.127577 -82.979194) (xy 270.054227 -83.021543) (xy 269.977184 -83.056727)
			(xy 269.897145 -83.084429) (xy 269.814836 -83.104397) (xy 269.731001 -83.11645) (xy 269.6464 -83.120481)
			(xy 269.561799 -83.11645) (xy 269.477964 -83.104397) (xy 269.395655 -83.084429) (xy 269.315616 -83.056727)
			(xy 269.238573 -83.021543) (xy 269.165223 -82.979194) (xy 269.096231 -82.930065) (xy 269.032221 -82.8746)
			(xy 268.973773 -82.813302) (xy 268.921417 -82.746726) (xy 268.875627 -82.675474) (xy 268.836816 -82.600193)
			(xy 268.805337 -82.521563) (xy 268.781476 -82.440296) (xy 268.765447 -82.35713) (xy 268.757396 -82.272816)
			(xy 242.815364 -82.272816) (xy 242.815364 -91.391416) (xy 268.757396 -91.391416) (xy 268.757396 -91.30672)
			(xy 268.765447 -91.222406) (xy 268.781476 -91.13924) (xy 268.805337 -91.057973) (xy 268.836816 -90.979343)
			(xy 268.875627 -90.904062) (xy 268.921417 -90.83281) (xy 268.973773 -90.766234) (xy 269.032221 -90.704936)
			(xy 269.096231 -90.649471) (xy 269.165223 -90.600342) (xy 269.238573 -90.557993) (xy 269.315616 -90.522809)
			(xy 269.395655 -90.495107) (xy 269.477964 -90.475139) (xy 269.561799 -90.463086) (xy 269.6464 -90.459056)
			(xy 269.731001 -90.463086) (xy 269.814836 -90.475139) (xy 269.897145 -90.495107) (xy 269.977184 -90.522809)
			(xy 270.054227 -90.557993) (xy 270.127577 -90.600342) (xy 270.196569 -90.649471) (xy 270.260579 -90.704936)
			(xy 270.319027 -90.766234) (xy 270.371383 -90.83281) (xy 270.417173 -90.904062) (xy 270.455984 -90.979343)
			(xy 270.487463 -91.057973) (xy 270.511324 -91.13924) (xy 270.527353 -91.222406) (xy 270.535404 -91.30672)
			(xy 270.535908 -91.349068) (xy 270.535404 -91.391416) (xy 270.527353 -91.47573) (xy 270.511324 -91.558896)
			(xy 270.487463 -91.640163) (xy 270.455984 -91.718793) (xy 270.417173 -91.794074) (xy 270.371383 -91.865326)
			(xy 270.319027 -91.931902) (xy 270.260579 -91.9932) (xy 270.196569 -92.048665) (xy 270.127577 -92.097794)
			(xy 270.054227 -92.140143) (xy 269.977184 -92.175327) (xy 269.897145 -92.203029) (xy 269.814836 -92.222997)
			(xy 269.731001 -92.23505) (xy 269.6464 -92.239081) (xy 269.561799 -92.23505) (xy 269.477964 -92.222997)
			(xy 269.395655 -92.203029) (xy 269.315616 -92.175327) (xy 269.238573 -92.140143) (xy 269.165223 -92.097794)
			(xy 269.096231 -92.048665) (xy 269.032221 -91.9932) (xy 268.973773 -91.931902) (xy 268.921417 -91.865326)
			(xy 268.875627 -91.794074) (xy 268.836816 -91.718793) (xy 268.805337 -91.640163) (xy 268.781476 -91.558896)
			(xy 268.765447 -91.47573) (xy 268.757396 -91.391416) (xy 242.815364 -91.391416) (xy 242.815364 -92.062554)
			(xy 242.81493 -92.072619) (xy 242.807198 -92.091206) (xy 242.800378 -92.098622) (xy 242.760754 -92.138246)
			(xy 242.753614 -92.146072) (xy 242.74585 -92.165755) (xy 242.745768 -92.176346) (xy 242.74907 -92.26169)
			(xy 242.758214 -92.280486) (xy 242.766596 -92.287344) (xy 242.798752 -92.315471) (xy 242.858102 -92.376928)
			(xy 242.911288 -92.443792) (xy 242.957819 -92.515446) (xy 242.997267 -92.591231) (xy 243.029269 -92.670448)
			(xy 243.053529 -92.752368) (xy 243.069824 -92.836237) (xy 243.072554 -92.864616) (xy 270.308574 -92.864616)
			(xy 270.308574 -92.77992) (xy 270.316625 -92.695606) (xy 270.332654 -92.61244) (xy 270.356515 -92.531173)
			(xy 270.387994 -92.452543) (xy 270.426805 -92.377262) (xy 270.472595 -92.30601) (xy 270.524951 -92.239434)
			(xy 270.583399 -92.178136) (xy 270.647409 -92.122671) (xy 270.716401 -92.073542) (xy 270.789751 -92.031193)
			(xy 270.866794 -91.996009) (xy 270.946833 -91.968307) (xy 271.029142 -91.948339) (xy 271.112977 -91.936286)
			(xy 271.197578 -91.932256) (xy 271.282179 -91.936286) (xy 271.366014 -91.948339) (xy 271.448323 -91.968307)
			(xy 271.528362 -91.996009) (xy 271.605405 -92.031193) (xy 271.678755 -92.073542) (xy 271.747747 -92.122671)
			(xy 271.811757 -92.178136) (xy 271.870205 -92.239434) (xy 271.922561 -92.30601) (xy 271.968351 -92.377262)
			(xy 272.007162 -92.452543) (xy 272.038641 -92.531173) (xy 272.062502 -92.61244) (xy 272.078531 -92.695606)
			(xy 272.086582 -92.77992) (xy 272.087086 -92.822268) (xy 272.086582 -92.864616) (xy 272.078531 -92.94893)
			(xy 272.062502 -93.032096) (xy 272.038641 -93.113363) (xy 272.007162 -93.191993) (xy 271.968351 -93.267274)
			(xy 271.922561 -93.338526) (xy 271.870205 -93.405102) (xy 271.811757 -93.4664) (xy 271.747747 -93.521865)
			(xy 271.678755 -93.570994) (xy 271.605405 -93.613343) (xy 271.528362 -93.648527) (xy 271.448323 -93.676229)
			(xy 271.366014 -93.696197) (xy 271.282179 -93.70825) (xy 271.197578 -93.712281) (xy 271.112977 -93.70825)
			(xy 271.029142 -93.696197) (xy 270.946833 -93.676229) (xy 270.866794 -93.648527) (xy 270.789751 -93.613343)
			(xy 270.716401 -93.570994) (xy 270.647409 -93.521865) (xy 270.583399 -93.4664) (xy 270.524951 -93.405102)
			(xy 270.472595 -93.338526) (xy 270.426805 -93.267274) (xy 270.387994 -93.191993) (xy 270.356515 -93.113363)
			(xy 270.332654 -93.032096) (xy 270.316625 -92.94893) (xy 270.308574 -92.864616) (xy 243.072554 -92.864616)
			(xy 243.078005 -92.921281) (xy 243.078508 -92.964) (xy 243.078033 -93.005102) (xy 243.070448 -93.086957)
			(xy 243.055343 -93.167762) (xy 243.032847 -93.246829) (xy 243.003151 -93.323483) (xy 242.966509 -93.39707)
			(xy 242.923234 -93.466962) (xy 242.873694 -93.532563) (xy 242.818313 -93.593313) (xy 242.757563 -93.648694)
			(xy 242.691962 -93.698234) (xy 242.62207 -93.741509) (xy 242.548483 -93.778151) (xy 242.471829 -93.807847)
			(xy 242.392762 -93.830343) (xy 242.311957 -93.845448) (xy 242.230102 -93.853033) (xy 242.189 -93.853508)
			(xy 242.142604 -93.852923) (xy 242.050314 -93.84329) (xy 241.959529 -93.824097) (xy 241.871236 -93.795553)
			(xy 241.828574 -93.777308) (xy 241.818634 -93.773488) (xy 241.797366 -93.773488) (xy 241.787426 -93.777308)
			(xy 241.744761 -93.795546) (xy 241.656468 -93.824084) (xy 241.565684 -93.84328) (xy 241.473396 -93.852925)
			(xy 241.427 -93.853508) (xy 241.384979 -93.85302) (xy 241.301311 -93.845093) (xy 241.218763 -93.829309)
			(xy 241.138073 -93.80581) (xy 241.098832 -93.79077) (xy 241.09438 -93.789103) (xy 241.085043 -93.787314)
			(xy 241.08029 -93.787214) (xy 240.12271 -93.787214) (xy 240.117961 -93.787355) (xy 240.108633 -93.789146)
			(xy 240.104168 -93.79077) (xy 240.064929 -93.805815) (xy 239.984237 -93.829308) (xy 239.901689 -93.845087)
			(xy 239.818021 -93.853012) (xy 239.733979 -93.853012) (xy 239.650311 -93.845087) (xy 239.567763 -93.829308)
			(xy 239.487071 -93.805815) (xy 239.447832 -93.79077) (xy 239.438942 -93.787214) (xy 239.351058 -93.787214)
			(xy 239.342168 -93.79077) (xy 239.302929 -93.805815) (xy 239.222237 -93.829308) (xy 239.139689 -93.845087)
			(xy 239.056021 -93.853012) (xy 238.971979 -93.853012) (xy 238.888311 -93.845087) (xy 238.805763 -93.829308)
			(xy 238.725071 -93.805815) (xy 238.685832 -93.79077) (xy 238.68138 -93.789103) (xy 238.672043 -93.787314)
			(xy 238.66729 -93.787214) (xy 237.70971 -93.787214) (xy 237.704961 -93.787355) (xy 237.695633 -93.789146)
			(xy 237.691168 -93.79077) (xy 237.651929 -93.805815) (xy 237.571237 -93.829308) (xy 237.488689 -93.845087)
			(xy 237.405021 -93.853012) (xy 237.320979 -93.853012) (xy 237.237311 -93.845087) (xy 237.154763 -93.829308)
			(xy 237.074071 -93.805815) (xy 237.034832 -93.79077) (xy 237.025942 -93.787214) (xy 236.938058 -93.787214)
			(xy 236.929168 -93.79077) (xy 236.889929 -93.805815) (xy 236.809237 -93.829308) (xy 236.726689 -93.845087)
			(xy 236.643021 -93.853012) (xy 236.558979 -93.853012) (xy 236.475311 -93.845087) (xy 236.392763 -93.829308)
			(xy 236.312071 -93.805815) (xy 236.272832 -93.79077) (xy 236.26838 -93.789103) (xy 236.259043 -93.787314)
			(xy 236.25429 -93.787214) (xy 235.29671 -93.787214) (xy 235.291961 -93.787355) (xy 235.282633 -93.789146)
			(xy 235.278168 -93.79077) (xy 235.238929 -93.805815) (xy 235.158237 -93.829308) (xy 235.075689 -93.845087)
			(xy 234.992021 -93.853012) (xy 234.907979 -93.853012) (xy 234.824311 -93.845087) (xy 234.741763 -93.829308)
			(xy 234.661071 -93.805815) (xy 234.621832 -93.79077) (xy 234.612942 -93.787214) (xy 234.525058 -93.787214)
			(xy 234.516168 -93.79077) (xy 234.476929 -93.805815) (xy 234.396237 -93.829308) (xy 234.313689 -93.845087)
			(xy 234.230021 -93.853012) (xy 234.145979 -93.853012) (xy 234.062311 -93.845087) (xy 233.979763 -93.829308)
			(xy 233.899071 -93.805815) (xy 233.859832 -93.79077) (xy 233.85538 -93.789103) (xy 233.846043 -93.787314)
			(xy 233.84129 -93.787214) (xy 232.88371 -93.787214) (xy 232.878961 -93.787355) (xy 232.869633 -93.789146)
			(xy 232.865168 -93.79077) (xy 232.825929 -93.805815) (xy 232.745237 -93.829308) (xy 232.662689 -93.845087)
			(xy 232.579021 -93.853012) (xy 232.494979 -93.853012) (xy 232.411311 -93.845087) (xy 232.328763 -93.829308)
			(xy 232.248071 -93.805815) (xy 232.208832 -93.79077) (xy 232.199942 -93.787214) (xy 232.112058 -93.787214)
			(xy 232.103168 -93.79077) (xy 232.063929 -93.805815) (xy 231.983237 -93.829308) (xy 231.900689 -93.845087)
			(xy 231.817021 -93.853012) (xy 231.732979 -93.853012) (xy 231.649311 -93.845087) (xy 231.566763 -93.829308)
			(xy 231.486071 -93.805815) (xy 231.446832 -93.79077) (xy 231.44238 -93.789103) (xy 231.433043 -93.787314)
			(xy 231.42829 -93.787214) (xy 230.47071 -93.787214) (xy 230.465961 -93.787355) (xy 230.456633 -93.789146)
			(xy 230.452168 -93.79077) (xy 230.412929 -93.805815) (xy 230.332237 -93.829308) (xy 230.249689 -93.845087)
			(xy 230.166021 -93.853012) (xy 230.081979 -93.853012) (xy 229.998311 -93.845087) (xy 229.915763 -93.829308)
			(xy 229.835071 -93.805815) (xy 229.795832 -93.79077) (xy 229.786942 -93.787214) (xy 229.699058 -93.787214)
			(xy 229.690168 -93.79077) (xy 229.650929 -93.805815) (xy 229.570237 -93.829308) (xy 229.487689 -93.845087)
			(xy 229.404021 -93.853012) (xy 229.319979 -93.853012) (xy 229.236311 -93.845087) (xy 229.153763 -93.829308)
			(xy 229.073071 -93.805815) (xy 229.033832 -93.79077) (xy 229.02938 -93.789103) (xy 229.020043 -93.787314)
			(xy 229.01529 -93.787214) (xy 228.05771 -93.787214) (xy 228.052961 -93.787355) (xy 228.043633 -93.789146)
			(xy 228.039168 -93.79077) (xy 227.999929 -93.805815) (xy 227.919237 -93.829308) (xy 227.836689 -93.845087)
			(xy 227.753021 -93.853012) (xy 227.668979 -93.853012) (xy 227.585311 -93.845087) (xy 227.502763 -93.829308)
			(xy 227.422071 -93.805815) (xy 227.382832 -93.79077) (xy 227.373942 -93.787214) (xy 227.286058 -93.787214)
			(xy 227.277168 -93.79077) (xy 227.237929 -93.805815) (xy 227.157237 -93.829308) (xy 227.074689 -93.845087)
			(xy 226.991021 -93.853012) (xy 226.906979 -93.853012) (xy 226.823311 -93.845087) (xy 226.740763 -93.829308)
			(xy 226.660071 -93.805815) (xy 226.620832 -93.79077) (xy 226.61638 -93.789103) (xy 226.607043 -93.787314)
			(xy 226.60229 -93.787214) (xy 225.64471 -93.787214) (xy 225.639961 -93.787355) (xy 225.630633 -93.789146)
			(xy 225.626168 -93.79077) (xy 225.586929 -93.805815) (xy 225.506237 -93.829308) (xy 225.423689 -93.845087)
			(xy 225.340021 -93.853012) (xy 225.255979 -93.853012) (xy 225.172311 -93.845087) (xy 225.089763 -93.829308)
			(xy 225.009071 -93.805815) (xy 224.969832 -93.79077) (xy 224.960942 -93.787214) (xy 224.873058 -93.787214)
			(xy 224.864168 -93.79077) (xy 224.824929 -93.805815) (xy 224.744237 -93.829308) (xy 224.661689 -93.845087)
			(xy 224.578021 -93.853012) (xy 224.493979 -93.853012) (xy 224.410311 -93.845087) (xy 224.327763 -93.829308)
			(xy 224.247071 -93.805815) (xy 224.207832 -93.79077) (xy 224.20338 -93.789103) (xy 224.194043 -93.787314)
			(xy 224.18929 -93.787214) (xy 223.23171 -93.787214) (xy 223.226961 -93.787355) (xy 223.217633 -93.789146)
			(xy 223.213168 -93.79077) (xy 223.173929 -93.805815) (xy 223.093237 -93.829308) (xy 223.010689 -93.845087)
			(xy 222.927021 -93.853012) (xy 222.842979 -93.853012) (xy 222.759311 -93.845087) (xy 222.676763 -93.829308)
			(xy 222.596071 -93.805815) (xy 222.556832 -93.79077) (xy 222.547942 -93.787214) (xy 222.460058 -93.787214)
			(xy 222.451168 -93.79077) (xy 222.411929 -93.805815) (xy 222.331237 -93.829308) (xy 222.248689 -93.845087)
			(xy 222.165021 -93.853012) (xy 222.080979 -93.853012) (xy 221.997311 -93.845087) (xy 221.914763 -93.829308)
			(xy 221.834071 -93.805815) (xy 221.794832 -93.79077) (xy 221.79038 -93.789103) (xy 221.781043 -93.787314)
			(xy 221.77629 -93.787214) (xy 220.94571 -93.787214) (xy 220.940961 -93.787355) (xy 220.931633 -93.789146)
			(xy 220.927168 -93.79077) (xy 220.887929 -93.805815) (xy 220.807237 -93.829308) (xy 220.724689 -93.845087)
			(xy 220.641021 -93.853012) (xy 220.556979 -93.853012) (xy 220.473311 -93.845087) (xy 220.390763 -93.829308)
			(xy 220.310071 -93.805815) (xy 220.270832 -93.79077) (xy 220.261942 -93.787214) (xy 220.174058 -93.787214)
			(xy 220.165168 -93.79077) (xy 220.125929 -93.805815) (xy 220.045237 -93.829308) (xy 219.962689 -93.845087)
			(xy 219.879021 -93.853012) (xy 219.794979 -93.853012) (xy 219.711311 -93.845087) (xy 219.628763 -93.829308)
			(xy 219.548071 -93.805815) (xy 219.508832 -93.79077) (xy 219.50438 -93.789103) (xy 219.495043 -93.787314)
			(xy 219.49029 -93.787214) (xy 218.65971 -93.787214) (xy 218.654961 -93.787355) (xy 218.645633 -93.789146)
			(xy 218.641168 -93.79077) (xy 218.601929 -93.805815) (xy 218.521237 -93.829308) (xy 218.438689 -93.845087)
			(xy 218.355021 -93.853012) (xy 218.270979 -93.853012) (xy 218.187311 -93.845087) (xy 218.104763 -93.829308)
			(xy 218.024071 -93.805815) (xy 217.984832 -93.79077) (xy 217.975942 -93.787214) (xy 217.888058 -93.787214)
			(xy 217.879168 -93.79077) (xy 217.839929 -93.805815) (xy 217.759237 -93.829308) (xy 217.676689 -93.845087)
			(xy 217.593021 -93.853012) (xy 217.508979 -93.853012) (xy 217.425311 -93.845087) (xy 217.342763 -93.829308)
			(xy 217.262071 -93.805815) (xy 217.222832 -93.79077) (xy 217.21838 -93.789103) (xy 217.209043 -93.787314)
			(xy 217.20429 -93.787214) (xy 216.37371 -93.787214) (xy 216.368961 -93.787355) (xy 216.359633 -93.789146)
			(xy 216.355168 -93.79077) (xy 216.315929 -93.805815) (xy 216.235237 -93.829308) (xy 216.152689 -93.845087)
			(xy 216.069021 -93.853012) (xy 215.984979 -93.853012) (xy 215.901311 -93.845087) (xy 215.818763 -93.829308)
			(xy 215.738071 -93.805815) (xy 215.698832 -93.79077) (xy 215.689942 -93.787214) (xy 215.602058 -93.787214)
			(xy 215.593168 -93.79077) (xy 215.553929 -93.805815) (xy 215.473237 -93.829308) (xy 215.390689 -93.845087)
			(xy 215.307021 -93.853012) (xy 215.222979 -93.853012) (xy 215.139311 -93.845087) (xy 215.056763 -93.829308)
			(xy 214.976071 -93.805815) (xy 214.936832 -93.79077) (xy 214.93238 -93.789103) (xy 214.923043 -93.787314)
			(xy 214.91829 -93.787214) (xy 203.271374 -93.787214) (xy 203.264397 -93.787458) (xy 203.250986 -93.791315)
			(xy 203.244958 -93.794834) (xy 203.212421 -93.814315) (xy 203.144429 -93.847917) (xy 203.073643 -93.875146)
			(xy 203.00066 -93.895772) (xy 202.926093 -93.909621) (xy 202.850571 -93.916578) (xy 202.81265 -93.917008)
			(xy 190.351156 -93.917008) (xy 190.346416 -93.91707) (xy 190.337087 -93.91874) (xy 190.332614 -93.92031)
			(xy 190.294089 -93.934736) (xy 190.214965 -93.957271) (xy 190.134101 -93.972413) (xy 190.052185 -93.980032)
			(xy 190.01105 -93.980508) (xy 189.969913 -93.980052) (xy 189.887991 -93.972459) (xy 189.807121 -93.957324)
			(xy 189.727998 -93.934777) (xy 189.689486 -93.92031) (xy 189.685017 -93.918727) (xy 189.675684 -93.917069)
			(xy 189.670944 -93.917008) (xy 165.989 -93.917008) (xy 165.951079 -93.916578) (xy 165.875556 -93.909625)
			(xy 165.800989 -93.895777) (xy 165.728006 -93.87515) (xy 165.657221 -93.847919) (xy 165.589231 -93.814313)
			(xy 165.556692 -93.794834) (xy 165.550634 -93.791383) (xy 165.537241 -93.78753) (xy 165.530276 -93.787214)
			(xy 158.768796 -93.787214) (xy 158.758726 -93.786791) (xy 158.740121 -93.779077) (xy 158.732728 -93.772228)
			(xy 148.858986 -83.898486) (xy 148.851591 -83.891632) (xy 148.832992 -83.88389) (xy 148.822918 -83.8835)
			(xy 38.524688 -83.8835) (xy 38.514619 -83.883925) (xy 38.496018 -83.891643) (xy 38.48862 -83.898486)
			(xy 37.886386 -84.50072) (xy 37.879533 -84.508115) (xy 37.871793 -84.526714) (xy 37.8714 -84.536788)
			(xy 37.8714 -86.542556) (xy 43.120306 -86.542556) (xy 43.120306 -86.45786) (xy 43.128357 -86.373546)
			(xy 43.144386 -86.29038) (xy 43.168247 -86.209113) (xy 43.199726 -86.130483) (xy 43.238537 -86.055202)
			(xy 43.284327 -85.98395) (xy 43.336683 -85.917374) (xy 43.395131 -85.856076) (xy 43.459141 -85.800611)
			(xy 43.528133 -85.751482) (xy 43.601483 -85.709133) (xy 43.678526 -85.673949) (xy 43.758565 -85.646247)
			(xy 43.840874 -85.626279) (xy 43.924709 -85.614226) (xy 44.00931 -85.610196) (xy 44.093911 -85.614226)
			(xy 44.177746 -85.626279) (xy 44.260055 -85.646247) (xy 44.340094 -85.673949) (xy 44.417137 -85.709133)
			(xy 44.490487 -85.751482) (xy 44.559479 -85.800611) (xy 44.623489 -85.856076) (xy 44.681937 -85.917374)
			(xy 44.734293 -85.98395) (xy 44.780083 -86.055202) (xy 44.818894 -86.130483) (xy 44.850373 -86.209113)
			(xy 44.874234 -86.29038) (xy 44.890263 -86.373546) (xy 44.898314 -86.45786) (xy 44.898675 -86.4882)
			(xy 72.953876 -86.4882) (xy 72.953876 -86.403504) (xy 72.961927 -86.31919) (xy 72.977956 -86.236024)
			(xy 73.001817 -86.154757) (xy 73.033296 -86.076127) (xy 73.072107 -86.000846) (xy 73.117897 -85.929594)
			(xy 73.170253 -85.863018) (xy 73.228701 -85.80172) (xy 73.292711 -85.746255) (xy 73.361703 -85.697126)
			(xy 73.435053 -85.654777) (xy 73.512096 -85.619593) (xy 73.592135 -85.591891) (xy 73.674444 -85.571923)
			(xy 73.758279 -85.55987) (xy 73.84288 -85.55584) (xy 73.927481 -85.55987) (xy 74.011316 -85.571923)
			(xy 74.093625 -85.591891) (xy 74.173664 -85.619593) (xy 74.250707 -85.654777) (xy 74.324057 -85.697126)
			(xy 74.393049 -85.746255) (xy 74.457059 -85.80172) (xy 74.515507 -85.863018) (xy 74.567863 -85.929594)
			(xy 74.613653 -86.000846) (xy 74.652464 -86.076127) (xy 74.683943 -86.154757) (xy 74.707804 -86.236024)
			(xy 74.723833 -86.31919) (xy 74.731884 -86.403504) (xy 74.732388 -86.445852) (xy 74.731884 -86.4882)
			(xy 74.726694 -86.542556) (xy 78.75803 -86.542556) (xy 78.75803 -86.45786) (xy 78.766081 -86.373546)
			(xy 78.78211 -86.29038) (xy 78.805971 -86.209113) (xy 78.83745 -86.130483) (xy 78.876261 -86.055202)
			(xy 78.922051 -85.98395) (xy 78.974407 -85.917374) (xy 79.032855 -85.856076) (xy 79.096865 -85.800611)
			(xy 79.165857 -85.751482) (xy 79.239207 -85.709133) (xy 79.31625 -85.673949) (xy 79.396289 -85.646247)
			(xy 79.478598 -85.626279) (xy 79.562433 -85.614226) (xy 79.647034 -85.610196) (xy 79.731635 -85.614226)
			(xy 79.81547 -85.626279) (xy 79.897779 -85.646247) (xy 79.977818 -85.673949) (xy 80.054861 -85.709133)
			(xy 80.128211 -85.751482) (xy 80.197203 -85.800611) (xy 80.261213 -85.856076) (xy 80.319661 -85.917374)
			(xy 80.372017 -85.98395) (xy 80.417807 -86.055202) (xy 80.456618 -86.130483) (xy 80.488097 -86.209113)
			(xy 80.511958 -86.29038) (xy 80.527987 -86.373546) (xy 80.536038 -86.45786) (xy 80.536402 -86.488454)
			(xy 112.713766 -86.488454) (xy 112.713766 -86.403758) (xy 112.721817 -86.319444) (xy 112.737846 -86.236278)
			(xy 112.761707 -86.155011) (xy 112.793186 -86.076381) (xy 112.831997 -86.0011) (xy 112.877787 -85.929848)
			(xy 112.930143 -85.863272) (xy 112.988591 -85.801974) (xy 113.052601 -85.746509) (xy 113.121593 -85.69738)
			(xy 113.194943 -85.655031) (xy 113.271986 -85.619847) (xy 113.352025 -85.592145) (xy 113.434334 -85.572177)
			(xy 113.518169 -85.560124) (xy 113.60277 -85.556094) (xy 113.687371 -85.560124) (xy 113.771206 -85.572177)
			(xy 113.853515 -85.592145) (xy 113.933554 -85.619847) (xy 114.010597 -85.655031) (xy 114.083947 -85.69738)
			(xy 114.152939 -85.746509) (xy 114.216949 -85.801974) (xy 114.275397 -85.863272) (xy 114.327753 -85.929848)
			(xy 114.373543 -86.0011) (xy 114.412354 -86.076381) (xy 114.443833 -86.155011) (xy 114.467694 -86.236278)
			(xy 114.483723 -86.319444) (xy 114.491774 -86.403758) (xy 114.492278 -86.446106) (xy 114.491774 -86.488454)
			(xy 119.277126 -86.488454) (xy 119.277126 -86.403758) (xy 119.285177 -86.319444) (xy 119.301206 -86.236278)
			(xy 119.325067 -86.155011) (xy 119.356546 -86.076381) (xy 119.395357 -86.0011) (xy 119.441147 -85.929848)
			(xy 119.493503 -85.863272) (xy 119.551951 -85.801974) (xy 119.615961 -85.746509) (xy 119.684953 -85.69738)
			(xy 119.758303 -85.655031) (xy 119.835346 -85.619847) (xy 119.915385 -85.592145) (xy 119.997694 -85.572177)
			(xy 120.081529 -85.560124) (xy 120.16613 -85.556094) (xy 120.250731 -85.560124) (xy 120.334566 -85.572177)
			(xy 120.416875 -85.592145) (xy 120.496914 -85.619847) (xy 120.573957 -85.655031) (xy 120.647307 -85.69738)
			(xy 120.716299 -85.746509) (xy 120.780309 -85.801974) (xy 120.838757 -85.863272) (xy 120.891113 -85.929848)
			(xy 120.936903 -86.0011) (xy 120.975714 -86.076381) (xy 121.007193 -86.155011) (xy 121.031054 -86.236278)
			(xy 121.047083 -86.319444) (xy 121.055134 -86.403758) (xy 121.055638 -86.446106) (xy 121.055134 -86.488454)
			(xy 137.556998 -86.488454) (xy 137.556998 -86.403758) (xy 137.565049 -86.319444) (xy 137.581078 -86.236278)
			(xy 137.604939 -86.155011) (xy 137.636418 -86.076381) (xy 137.675229 -86.0011) (xy 137.721019 -85.929848)
			(xy 137.773375 -85.863272) (xy 137.831823 -85.801974) (xy 137.895833 -85.746509) (xy 137.964825 -85.69738)
			(xy 138.038175 -85.655031) (xy 138.115218 -85.619847) (xy 138.195257 -85.592145) (xy 138.277566 -85.572177)
			(xy 138.361401 -85.560124) (xy 138.446002 -85.556094) (xy 138.530603 -85.560124) (xy 138.614438 -85.572177)
			(xy 138.696747 -85.592145) (xy 138.776786 -85.619847) (xy 138.853829 -85.655031) (xy 138.927179 -85.69738)
			(xy 138.996171 -85.746509) (xy 139.060181 -85.801974) (xy 139.118629 -85.863272) (xy 139.170985 -85.929848)
			(xy 139.216775 -86.0011) (xy 139.255586 -86.076381) (xy 139.287065 -86.155011) (xy 139.310926 -86.236278)
			(xy 139.326955 -86.319444) (xy 139.335006 -86.403758) (xy 139.33551 -86.446106) (xy 139.335006 -86.488454)
			(xy 139.326955 -86.572768) (xy 139.310926 -86.655934) (xy 139.287065 -86.737201) (xy 139.255586 -86.815831)
			(xy 139.216775 -86.891112) (xy 139.170985 -86.962364) (xy 139.118629 -87.02894) (xy 139.060181 -87.090238)
			(xy 138.996171 -87.145703) (xy 138.927179 -87.194832) (xy 138.853829 -87.237181) (xy 138.776786 -87.272365)
			(xy 138.696747 -87.300067) (xy 138.614438 -87.320035) (xy 138.530603 -87.332088) (xy 138.446002 -87.336119)
			(xy 138.361401 -87.332088) (xy 138.277566 -87.320035) (xy 138.195257 -87.300067) (xy 138.115218 -87.272365)
			(xy 138.038175 -87.237181) (xy 137.964825 -87.194832) (xy 137.895833 -87.145703) (xy 137.831823 -87.090238)
			(xy 137.773375 -87.02894) (xy 137.721019 -86.962364) (xy 137.675229 -86.891112) (xy 137.636418 -86.815831)
			(xy 137.604939 -86.737201) (xy 137.581078 -86.655934) (xy 137.565049 -86.572768) (xy 137.556998 -86.488454)
			(xy 121.055134 -86.488454) (xy 121.047083 -86.572768) (xy 121.031054 -86.655934) (xy 121.007193 -86.737201)
			(xy 120.975714 -86.815831) (xy 120.936903 -86.891112) (xy 120.891113 -86.962364) (xy 120.838757 -87.02894)
			(xy 120.780309 -87.090238) (xy 120.716299 -87.145703) (xy 120.647307 -87.194832) (xy 120.573957 -87.237181)
			(xy 120.496914 -87.272365) (xy 120.416875 -87.300067) (xy 120.334566 -87.320035) (xy 120.250731 -87.332088)
			(xy 120.16613 -87.336119) (xy 120.081529 -87.332088) (xy 119.997694 -87.320035) (xy 119.915385 -87.300067)
			(xy 119.835346 -87.272365) (xy 119.758303 -87.237181) (xy 119.684953 -87.194832) (xy 119.615961 -87.145703)
			(xy 119.551951 -87.090238) (xy 119.493503 -87.02894) (xy 119.441147 -86.962364) (xy 119.395357 -86.891112)
			(xy 119.356546 -86.815831) (xy 119.325067 -86.737201) (xy 119.301206 -86.655934) (xy 119.285177 -86.572768)
			(xy 119.277126 -86.488454) (xy 114.491774 -86.488454) (xy 114.483723 -86.572768) (xy 114.467694 -86.655934)
			(xy 114.443833 -86.737201) (xy 114.412354 -86.815831) (xy 114.373543 -86.891112) (xy 114.327753 -86.962364)
			(xy 114.275397 -87.02894) (xy 114.216949 -87.090238) (xy 114.152939 -87.145703) (xy 114.083947 -87.194832)
			(xy 114.010597 -87.237181) (xy 113.933554 -87.272365) (xy 113.853515 -87.300067) (xy 113.771206 -87.320035)
			(xy 113.687371 -87.332088) (xy 113.60277 -87.336119) (xy 113.518169 -87.332088) (xy 113.434334 -87.320035)
			(xy 113.352025 -87.300067) (xy 113.271986 -87.272365) (xy 113.194943 -87.237181) (xy 113.121593 -87.194832)
			(xy 113.052601 -87.145703) (xy 112.988591 -87.090238) (xy 112.930143 -87.02894) (xy 112.877787 -86.962364)
			(xy 112.831997 -86.891112) (xy 112.793186 -86.815831) (xy 112.761707 -86.737201) (xy 112.737846 -86.655934)
			(xy 112.721817 -86.572768) (xy 112.713766 -86.488454) (xy 80.536402 -86.488454) (xy 80.536542 -86.500208)
			(xy 80.536038 -86.542556) (xy 80.527987 -86.62687) (xy 80.511958 -86.710036) (xy 80.488097 -86.791303)
			(xy 80.456618 -86.869933) (xy 80.417807 -86.945214) (xy 80.372017 -87.016466) (xy 80.319661 -87.083042)
			(xy 80.261213 -87.14434) (xy 80.197203 -87.199805) (xy 80.128211 -87.248934) (xy 80.054861 -87.291283)
			(xy 79.977818 -87.326467) (xy 79.897779 -87.354169) (xy 79.81547 -87.374137) (xy 79.731635 -87.38619)
			(xy 79.647034 -87.390221) (xy 79.562433 -87.38619) (xy 79.478598 -87.374137) (xy 79.396289 -87.354169)
			(xy 79.31625 -87.326467) (xy 79.239207 -87.291283) (xy 79.165857 -87.248934) (xy 79.096865 -87.199805)
			(xy 79.032855 -87.14434) (xy 78.974407 -87.083042) (xy 78.922051 -87.016466) (xy 78.876261 -86.945214)
			(xy 78.83745 -86.869933) (xy 78.805971 -86.791303) (xy 78.78211 -86.710036) (xy 78.766081 -86.62687)
			(xy 78.75803 -86.542556) (xy 74.726694 -86.542556) (xy 74.723833 -86.572514) (xy 74.707804 -86.65568)
			(xy 74.683943 -86.736947) (xy 74.652464 -86.815577) (xy 74.613653 -86.890858) (xy 74.567863 -86.96211)
			(xy 74.515507 -87.028686) (xy 74.457059 -87.089984) (xy 74.393049 -87.145449) (xy 74.324057 -87.194578)
			(xy 74.250707 -87.236927) (xy 74.173664 -87.272111) (xy 74.093625 -87.299813) (xy 74.011316 -87.319781)
			(xy 73.927481 -87.331834) (xy 73.84288 -87.335865) (xy 73.758279 -87.331834) (xy 73.674444 -87.319781)
			(xy 73.592135 -87.299813) (xy 73.512096 -87.272111) (xy 73.435053 -87.236927) (xy 73.361703 -87.194578)
			(xy 73.292711 -87.145449) (xy 73.228701 -87.089984) (xy 73.170253 -87.028686) (xy 73.117897 -86.96211)
			(xy 73.072107 -86.890858) (xy 73.033296 -86.815577) (xy 73.001817 -86.736947) (xy 72.977956 -86.65568)
			(xy 72.961927 -86.572514) (xy 72.953876 -86.4882) (xy 44.898675 -86.4882) (xy 44.898818 -86.500208)
			(xy 44.898314 -86.542556) (xy 44.890263 -86.62687) (xy 44.874234 -86.710036) (xy 44.850373 -86.791303)
			(xy 44.818894 -86.869933) (xy 44.780083 -86.945214) (xy 44.734293 -87.016466) (xy 44.681937 -87.083042)
			(xy 44.623489 -87.14434) (xy 44.559479 -87.199805) (xy 44.490487 -87.248934) (xy 44.417137 -87.291283)
			(xy 44.340094 -87.326467) (xy 44.260055 -87.354169) (xy 44.177746 -87.374137) (xy 44.093911 -87.38619)
			(xy 44.00931 -87.390221) (xy 43.924709 -87.38619) (xy 43.840874 -87.374137) (xy 43.758565 -87.354169)
			(xy 43.678526 -87.326467) (xy 43.601483 -87.291283) (xy 43.528133 -87.248934) (xy 43.459141 -87.199805)
			(xy 43.395131 -87.14434) (xy 43.336683 -87.083042) (xy 43.284327 -87.016466) (xy 43.238537 -86.945214)
			(xy 43.199726 -86.869933) (xy 43.168247 -86.791303) (xy 43.144386 -86.710036) (xy 43.128357 -86.62687)
			(xy 43.120306 -86.542556) (xy 37.8714 -86.542556) (xy 37.8714 -103.401298) (xy 271.98726 -103.401298)
			(xy 271.98726 -103.316602) (xy 271.995311 -103.232288) (xy 272.01134 -103.149122) (xy 272.035201 -103.067855)
			(xy 272.06668 -102.989225) (xy 272.105491 -102.913944) (xy 272.151281 -102.842692) (xy 272.203637 -102.776116)
			(xy 272.262085 -102.714818) (xy 272.326095 -102.659353) (xy 272.395087 -102.610224) (xy 272.468437 -102.567875)
			(xy 272.54548 -102.532691) (xy 272.625519 -102.504989) (xy 272.707828 -102.485021) (xy 272.791663 -102.472968)
			(xy 272.876264 -102.468938) (xy 272.960865 -102.472968) (xy 273.0447 -102.485021) (xy 273.127009 -102.504989)
			(xy 273.207048 -102.532691) (xy 273.284091 -102.567875) (xy 273.357441 -102.610224) (xy 273.426433 -102.659353)
			(xy 273.490443 -102.714818) (xy 273.548891 -102.776116) (xy 273.601247 -102.842692) (xy 273.647037 -102.913944)
			(xy 273.685848 -102.989225) (xy 273.717327 -103.067855) (xy 273.741188 -103.149122) (xy 273.757217 -103.232288)
			(xy 273.765268 -103.316602) (xy 273.765772 -103.35895) (xy 273.765268 -103.401298) (xy 273.757217 -103.485612)
			(xy 273.741188 -103.568778) (xy 273.717327 -103.650045) (xy 273.685848 -103.728675) (xy 273.647037 -103.803956)
			(xy 273.601247 -103.875208) (xy 273.548891 -103.941784) (xy 273.490443 -104.003082) (xy 273.426433 -104.058547)
			(xy 273.357441 -104.107676) (xy 273.284091 -104.150025) (xy 273.207048 -104.185209) (xy 273.127009 -104.212911)
			(xy 273.0447 -104.232879) (xy 272.960865 -104.244932) (xy 272.876264 -104.248963) (xy 272.791663 -104.244932)
			(xy 272.707828 -104.232879) (xy 272.625519 -104.212911) (xy 272.54548 -104.185209) (xy 272.468437 -104.150025)
			(xy 272.395087 -104.107676) (xy 272.326095 -104.058547) (xy 272.262085 -104.003082) (xy 272.203637 -103.941784)
			(xy 272.151281 -103.875208) (xy 272.105491 -103.803956) (xy 272.06668 -103.728675) (xy 272.035201 -103.650045)
			(xy 272.01134 -103.568778) (xy 271.995311 -103.485612) (xy 271.98726 -103.401298) (xy 37.8714 -103.401298)
			(xy 37.8714 -104.929616) (xy 270.26387 -104.929616) (xy 270.26387 -104.84492) (xy 270.271921 -104.760606)
			(xy 270.28795 -104.67744) (xy 270.311811 -104.596173) (xy 270.34329 -104.517543) (xy 270.382101 -104.442262)
			(xy 270.427891 -104.37101) (xy 270.480247 -104.304434) (xy 270.538695 -104.243136) (xy 270.602705 -104.187671)
			(xy 270.671697 -104.138542) (xy 270.745047 -104.096193) (xy 270.82209 -104.061009) (xy 270.902129 -104.033307)
			(xy 270.984438 -104.013339) (xy 271.068273 -104.001286) (xy 271.152874 -103.997256) (xy 271.237475 -104.001286)
			(xy 271.32131 -104.013339) (xy 271.403619 -104.033307) (xy 271.483658 -104.061009) (xy 271.560701 -104.096193)
			(xy 271.634051 -104.138542) (xy 271.703043 -104.187671) (xy 271.767053 -104.243136) (xy 271.825501 -104.304434)
			(xy 271.877857 -104.37101) (xy 271.923647 -104.442262) (xy 271.962458 -104.517543) (xy 271.993937 -104.596173)
			(xy 272.017798 -104.67744) (xy 272.033827 -104.760606) (xy 272.041878 -104.84492) (xy 272.042382 -104.887268)
			(xy 272.041878 -104.929616) (xy 272.033827 -105.01393) (xy 272.017798 -105.097096) (xy 271.993937 -105.178363)
			(xy 271.962458 -105.256993) (xy 271.923647 -105.332274) (xy 271.877857 -105.403526) (xy 271.825501 -105.470102)
			(xy 271.767053 -105.5314) (xy 271.703043 -105.586865) (xy 271.634051 -105.635994) (xy 271.560701 -105.678343)
			(xy 271.483658 -105.713527) (xy 271.403619 -105.741229) (xy 271.32131 -105.761197) (xy 271.237475 -105.77325)
			(xy 271.152874 -105.777281) (xy 271.068273 -105.77325) (xy 270.984438 -105.761197) (xy 270.902129 -105.741229)
			(xy 270.82209 -105.713527) (xy 270.745047 -105.678343) (xy 270.671697 -105.635994) (xy 270.602705 -105.586865)
			(xy 270.538695 -105.5314) (xy 270.480247 -105.470102) (xy 270.427891 -105.403526) (xy 270.382101 -105.332274)
			(xy 270.34329 -105.256993) (xy 270.311811 -105.178363) (xy 270.28795 -105.097096) (xy 270.271921 -105.01393)
			(xy 270.26387 -104.929616) (xy 37.8714 -104.929616) (xy 37.8714 -106.402816) (xy 268.600932 -106.402816)
			(xy 268.600932 -106.31812) (xy 268.608983 -106.233806) (xy 268.625012 -106.15064) (xy 268.648873 -106.069373)
			(xy 268.680352 -105.990743) (xy 268.719163 -105.915462) (xy 268.764953 -105.84421) (xy 268.817309 -105.777634)
			(xy 268.875757 -105.716336) (xy 268.939767 -105.660871) (xy 269.008759 -105.611742) (xy 269.082109 -105.569393)
			(xy 269.159152 -105.534209) (xy 269.239191 -105.506507) (xy 269.3215 -105.486539) (xy 269.405335 -105.474486)
			(xy 269.489936 -105.470456) (xy 269.574537 -105.474486) (xy 269.658372 -105.486539) (xy 269.740681 -105.506507)
			(xy 269.82072 -105.534209) (xy 269.897763 -105.569393) (xy 269.971113 -105.611742) (xy 270.040105 -105.660871)
			(xy 270.104115 -105.716336) (xy 270.162563 -105.777634) (xy 270.214919 -105.84421) (xy 270.260709 -105.915462)
			(xy 270.29952 -105.990743) (xy 270.330999 -106.069373) (xy 270.35486 -106.15064) (xy 270.370889 -106.233806)
			(xy 270.37894 -106.31812) (xy 270.379444 -106.360468) (xy 270.37894 -106.402816) (xy 270.370889 -106.48713)
			(xy 270.35486 -106.570296) (xy 270.330999 -106.651563) (xy 270.29952 -106.730193) (xy 270.260709 -106.805474)
			(xy 270.214919 -106.876726) (xy 270.162563 -106.943302) (xy 270.104115 -107.0046) (xy 270.040105 -107.060065)
			(xy 269.971113 -107.109194) (xy 269.897763 -107.151543) (xy 269.82072 -107.186727) (xy 269.740681 -107.214429)
			(xy 269.658372 -107.234397) (xy 269.574537 -107.24645) (xy 269.489936 -107.250481) (xy 269.405335 -107.24645)
			(xy 269.3215 -107.234397) (xy 269.239191 -107.214429) (xy 269.159152 -107.186727) (xy 269.082109 -107.151543)
			(xy 269.008759 -107.109194) (xy 268.939767 -107.060065) (xy 268.875757 -107.0046) (xy 268.817309 -106.943302)
			(xy 268.764953 -106.876726) (xy 268.719163 -106.805474) (xy 268.680352 -106.730193) (xy 268.648873 -106.651563)
			(xy 268.625012 -106.570296) (xy 268.608983 -106.48713) (xy 268.600932 -106.402816) (xy 37.8714 -106.402816)
			(xy 37.8714 -113.078698) (xy 55.961022 -113.078698) (xy 55.961022 -112.994002) (xy 55.969073 -112.909688)
			(xy 55.985102 -112.826522) (xy 56.008963 -112.745255) (xy 56.040442 -112.666625) (xy 56.079253 -112.591344)
			(xy 56.125043 -112.520092) (xy 56.177399 -112.453516) (xy 56.235847 -112.392218) (xy 56.299857 -112.336753)
			(xy 56.368849 -112.287624) (xy 56.442199 -112.245275) (xy 56.519242 -112.210091) (xy 56.599281 -112.182389)
			(xy 56.68159 -112.162421) (xy 56.765425 -112.150368) (xy 56.850026 -112.146338) (xy 56.934627 -112.150368)
			(xy 57.018462 -112.162421) (xy 57.100771 -112.182389) (xy 57.18081 -112.210091) (xy 57.257853 -112.245275)
			(xy 57.331203 -112.287624) (xy 57.400195 -112.336753) (xy 57.464205 -112.392218) (xy 57.522653 -112.453516)
			(xy 57.575009 -112.520092) (xy 57.620799 -112.591344) (xy 57.65961 -112.666625) (xy 57.691089 -112.745255)
			(xy 57.71495 -112.826522) (xy 57.730979 -112.909688) (xy 57.73903 -112.994002) (xy 57.739534 -113.03635)
			(xy 57.73903 -113.078698) (xy 95.960942 -113.078698) (xy 95.960942 -112.994002) (xy 95.968993 -112.909688)
			(xy 95.985022 -112.826522) (xy 96.008883 -112.745255) (xy 96.040362 -112.666625) (xy 96.079173 -112.591344)
			(xy 96.124963 -112.520092) (xy 96.177319 -112.453516) (xy 96.235767 -112.392218) (xy 96.299777 -112.336753)
			(xy 96.368769 -112.287624) (xy 96.442119 -112.245275) (xy 96.519162 -112.210091) (xy 96.599201 -112.182389)
			(xy 96.68151 -112.162421) (xy 96.765345 -112.150368) (xy 96.849946 -112.146338) (xy 96.934547 -112.150368)
			(xy 97.018382 -112.162421) (xy 97.100691 -112.182389) (xy 97.18073 -112.210091) (xy 97.257773 -112.245275)
			(xy 97.331123 -112.287624) (xy 97.400115 -112.336753) (xy 97.464125 -112.392218) (xy 97.522573 -112.453516)
			(xy 97.574929 -112.520092) (xy 97.620719 -112.591344) (xy 97.65953 -112.666625) (xy 97.691009 -112.745255)
			(xy 97.71487 -112.826522) (xy 97.726023 -112.884388) (xy 108.335822 -112.884388) (xy 108.335822 -112.799692)
			(xy 108.343873 -112.715378) (xy 108.359902 -112.632212) (xy 108.383763 -112.550945) (xy 108.415242 -112.472315)
			(xy 108.454053 -112.397034) (xy 108.499843 -112.325782) (xy 108.552199 -112.259206) (xy 108.610647 -112.197908)
			(xy 108.674657 -112.142443) (xy 108.743649 -112.093314) (xy 108.816999 -112.050965) (xy 108.894042 -112.015781)
			(xy 108.974081 -111.988079) (xy 109.05639 -111.968111) (xy 109.140225 -111.956058) (xy 109.224826 -111.952028)
			(xy 109.309427 -111.956058) (xy 109.393262 -111.968111) (xy 109.475571 -111.988079) (xy 109.55561 -112.015781)
			(xy 109.632653 -112.050965) (xy 109.706003 -112.093314) (xy 109.774995 -112.142443) (xy 109.839005 -112.197908)
			(xy 109.897453 -112.259206) (xy 109.949809 -112.325782) (xy 109.995599 -112.397034) (xy 110.03441 -112.472315)
			(xy 110.065889 -112.550945) (xy 110.08975 -112.632212) (xy 110.105779 -112.715378) (xy 110.11383 -112.799692)
			(xy 110.114334 -112.84204) (xy 110.11383 -112.884388) (xy 110.105779 -112.968702) (xy 110.08975 -113.051868)
			(xy 110.081872 -113.078698) (xy 135.961116 -113.078698) (xy 135.961116 -112.994002) (xy 135.969167 -112.909688)
			(xy 135.985196 -112.826522) (xy 136.009057 -112.745255) (xy 136.040536 -112.666625) (xy 136.079347 -112.591344)
			(xy 136.125137 -112.520092) (xy 136.177493 -112.453516) (xy 136.235941 -112.392218) (xy 136.299951 -112.336753)
			(xy 136.368943 -112.287624) (xy 136.442293 -112.245275) (xy 136.519336 -112.210091) (xy 136.599375 -112.182389)
			(xy 136.681684 -112.162421) (xy 136.765519 -112.150368) (xy 136.85012 -112.146338) (xy 136.934721 -112.150368)
			(xy 137.018556 -112.162421) (xy 137.100865 -112.182389) (xy 137.180904 -112.210091) (xy 137.257947 -112.245275)
			(xy 137.331297 -112.287624) (xy 137.400289 -112.336753) (xy 137.464299 -112.392218) (xy 137.522747 -112.453516)
			(xy 137.575103 -112.520092) (xy 137.620893 -112.591344) (xy 137.659704 -112.666625) (xy 137.691183 -112.745255)
			(xy 137.715044 -112.826522) (xy 137.731073 -112.909688) (xy 137.739124 -112.994002) (xy 137.739628 -113.03635)
			(xy 137.739127 -113.078444) (xy 138.683996 -113.078444) (xy 138.683996 -112.993748) (xy 138.692047 -112.909434)
			(xy 138.708076 -112.826268) (xy 138.731937 -112.745001) (xy 138.763416 -112.666371) (xy 138.802227 -112.59109)
			(xy 138.848017 -112.519838) (xy 138.900373 -112.453262) (xy 138.958821 -112.391964) (xy 139.022831 -112.336499)
			(xy 139.091823 -112.28737) (xy 139.165173 -112.245021) (xy 139.242216 -112.209837) (xy 139.322255 -112.182135)
			(xy 139.404564 -112.162167) (xy 139.488399 -112.150114) (xy 139.573 -112.146084) (xy 139.657601 -112.150114)
			(xy 139.741436 -112.162167) (xy 139.823745 -112.182135) (xy 139.903784 -112.209837) (xy 139.980827 -112.245021)
			(xy 140.054177 -112.28737) (xy 140.123169 -112.336499) (xy 140.187179 -112.391964) (xy 140.245627 -112.453262)
			(xy 140.297983 -112.519838) (xy 140.343773 -112.59109) (xy 140.382584 -112.666371) (xy 140.414063 -112.745001)
			(xy 140.437924 -112.826268) (xy 140.440964 -112.84204) (xy 148.335492 -112.84204) (xy 148.33599 -112.800937)
			(xy 148.343572 -112.719083) (xy 148.358674 -112.638277) (xy 148.381167 -112.559209) (xy 148.41086 -112.482554)
			(xy 148.4475 -112.408966) (xy 148.490773 -112.339073) (xy 148.540311 -112.273471) (xy 148.595691 -112.212719)
			(xy 148.65644 -112.157337) (xy 148.72204 -112.107796) (xy 148.791931 -112.06452) (xy 148.865518 -112.027877)
			(xy 148.942171 -111.99818) (xy 149.021238 -111.975683) (xy 149.102043 -111.960577) (xy 149.183898 -111.952992)
			(xy 149.225 -111.952532) (xy 149.268106 -111.953076) (xy 149.353915 -111.961408) (xy 149.438514 -111.978004)
			(xy 149.521111 -112.002707) (xy 149.600931 -112.035286) (xy 149.677223 -112.075436) (xy 149.749273 -112.122779)
			(xy 149.816403 -112.176872) (xy 149.877985 -112.237206) (xy 149.93344 -112.303215) (xy 149.982248 -112.37428)
			(xy 150.023951 -112.449735) (xy 150.058158 -112.52887) (xy 150.071836 -112.569752) (xy 150.075502 -112.579781)
			(xy 150.089727 -112.595687) (xy 150.099268 -112.600486) (xy 150.137783 -112.618446) (xy 150.211541 -112.660668)
			(xy 150.280935 -112.709732) (xy 150.345334 -112.765192) (xy 150.404149 -112.826541) (xy 150.456844 -112.89322)
			(xy 150.502939 -112.964621) (xy 150.542014 -113.040093) (xy 150.55743 -113.078444) (xy 175.96129 -113.078444)
			(xy 175.96129 -112.993748) (xy 175.969341 -112.909434) (xy 175.98537 -112.826268) (xy 176.009231 -112.745001)
			(xy 176.04071 -112.666371) (xy 176.079521 -112.59109) (xy 176.125311 -112.519838) (xy 176.177667 -112.453262)
			(xy 176.236115 -112.391964) (xy 176.300125 -112.336499) (xy 176.369117 -112.28737) (xy 176.442467 -112.245021)
			(xy 176.51951 -112.209837) (xy 176.599549 -112.182135) (xy 176.681858 -112.162167) (xy 176.765693 -112.150114)
			(xy 176.850294 -112.146084) (xy 176.934895 -112.150114) (xy 177.01873 -112.162167) (xy 177.101039 -112.182135)
			(xy 177.181078 -112.209837) (xy 177.258121 -112.245021) (xy 177.331471 -112.28737) (xy 177.400463 -112.336499)
			(xy 177.464473 -112.391964) (xy 177.522921 -112.453262) (xy 177.575277 -112.519838) (xy 177.621067 -112.59109)
			(xy 177.659878 -112.666371) (xy 177.691357 -112.745001) (xy 177.715218 -112.826268) (xy 177.731247 -112.909434)
			(xy 177.739298 -112.993748) (xy 177.739802 -113.036096) (xy 177.739298 -113.078444) (xy 177.731247 -113.162758)
			(xy 177.715218 -113.245924) (xy 177.691357 -113.327191) (xy 177.659878 -113.405821) (xy 177.621067 -113.481102)
			(xy 177.575277 -113.552354) (xy 177.522921 -113.61893) (xy 177.464473 -113.680228) (xy 177.400463 -113.735693)
			(xy 177.331471 -113.784822) (xy 177.258121 -113.827171) (xy 177.181078 -113.862355) (xy 177.101039 -113.890057)
			(xy 177.01873 -113.910025) (xy 176.934895 -113.922078) (xy 176.850294 -113.926109) (xy 176.765693 -113.922078)
			(xy 176.681858 -113.910025) (xy 176.599549 -113.890057) (xy 176.51951 -113.862355) (xy 176.442467 -113.827171)
			(xy 176.369117 -113.784822) (xy 176.300125 -113.735693) (xy 176.236115 -113.680228) (xy 176.177667 -113.61893)
			(xy 176.125311 -113.552354) (xy 176.079521 -113.481102) (xy 176.04071 -113.405821) (xy 176.009231 -113.327191)
			(xy 175.98537 -113.245924) (xy 175.969341 -113.162758) (xy 175.96129 -113.078444) (xy 150.55743 -113.078444)
			(xy 150.573712 -113.118948) (xy 150.597745 -113.200467) (xy 150.613893 -113.283907) (xy 150.622008 -113.368506)
			(xy 150.622508 -113.411) (xy 150.622033 -113.452102) (xy 150.614448 -113.533957) (xy 150.599343 -113.614762)
			(xy 150.576847 -113.693829) (xy 150.547151 -113.770483) (xy 150.510509 -113.84407) (xy 150.467234 -113.913962)
			(xy 150.417694 -113.979563) (xy 150.362313 -114.040313) (xy 150.301563 -114.095694) (xy 150.235962 -114.145234)
			(xy 150.16607 -114.188509) (xy 150.092483 -114.225151) (xy 150.015829 -114.254847) (xy 149.936762 -114.277343)
			(xy 149.855957 -114.292448) (xy 149.774102 -114.300033) (xy 149.733 -114.300508) (xy 149.689895 -114.299936)
			(xy 149.604088 -114.291605) (xy 149.51949 -114.27501) (xy 149.436894 -114.250308) (xy 149.357076 -114.21773)
			(xy 149.280785 -114.177583) (xy 149.208736 -114.130242) (xy 149.141605 -114.076152) (xy 149.080023 -114.015821)
			(xy 149.024567 -113.949815) (xy 148.975757 -113.878752) (xy 148.934052 -113.803301) (xy 148.899844 -113.724168)
			(xy 148.886164 -113.683288) (xy 148.882482 -113.673266) (xy 148.868269 -113.657356) (xy 148.858732 -113.652554)
			(xy 148.820193 -113.634642) (xy 148.746434 -113.592416) (xy 148.677039 -113.543348) (xy 148.612641 -113.487884)
			(xy 148.553826 -113.42653) (xy 148.501132 -113.359847) (xy 148.455039 -113.288441) (xy 148.415966 -113.212964)
			(xy 148.384271 -113.134105) (xy 148.360243 -113.052581) (xy 148.344099 -112.969138) (xy 148.335989 -112.884535)
			(xy 148.335492 -112.84204) (xy 140.440964 -112.84204) (xy 140.453953 -112.909434) (xy 140.462004 -112.993748)
			(xy 140.462508 -113.036096) (xy 140.462004 -113.078444) (xy 140.453953 -113.162758) (xy 140.437924 -113.245924)
			(xy 140.414063 -113.327191) (xy 140.382584 -113.405821) (xy 140.343773 -113.481102) (xy 140.297983 -113.552354)
			(xy 140.245627 -113.61893) (xy 140.187179 -113.680228) (xy 140.123169 -113.735693) (xy 140.054177 -113.784822)
			(xy 139.980827 -113.827171) (xy 139.903784 -113.862355) (xy 139.823745 -113.890057) (xy 139.741436 -113.910025)
			(xy 139.657601 -113.922078) (xy 139.573 -113.926109) (xy 139.488399 -113.922078) (xy 139.404564 -113.910025)
			(xy 139.322255 -113.890057) (xy 139.242216 -113.862355) (xy 139.165173 -113.827171) (xy 139.091823 -113.784822)
			(xy 139.022831 -113.735693) (xy 138.958821 -113.680228) (xy 138.900373 -113.61893) (xy 138.848017 -113.552354)
			(xy 138.802227 -113.481102) (xy 138.763416 -113.405821) (xy 138.731937 -113.327191) (xy 138.708076 -113.245924)
			(xy 138.692047 -113.162758) (xy 138.683996 -113.078444) (xy 137.739127 -113.078444) (xy 137.739124 -113.078698)
			(xy 137.731073 -113.163012) (xy 137.715044 -113.246178) (xy 137.691183 -113.327445) (xy 137.659704 -113.406075)
			(xy 137.620893 -113.481356) (xy 137.575103 -113.552608) (xy 137.522747 -113.619184) (xy 137.464299 -113.680482)
			(xy 137.400289 -113.735947) (xy 137.331297 -113.785076) (xy 137.257947 -113.827425) (xy 137.180904 -113.862609)
			(xy 137.100865 -113.890311) (xy 137.018556 -113.910279) (xy 136.934721 -113.922332) (xy 136.85012 -113.926363)
			(xy 136.765519 -113.922332) (xy 136.681684 -113.910279) (xy 136.599375 -113.890311) (xy 136.519336 -113.862609)
			(xy 136.442293 -113.827425) (xy 136.368943 -113.785076) (xy 136.299951 -113.735947) (xy 136.235941 -113.680482)
			(xy 136.177493 -113.619184) (xy 136.125137 -113.552608) (xy 136.079347 -113.481356) (xy 136.040536 -113.406075)
			(xy 136.009057 -113.327445) (xy 135.985196 -113.246178) (xy 135.969167 -113.163012) (xy 135.961116 -113.078698)
			(xy 110.081872 -113.078698) (xy 110.065889 -113.133135) (xy 110.03441 -113.211765) (xy 109.995599 -113.287046)
			(xy 109.949809 -113.358298) (xy 109.897453 -113.424874) (xy 109.839005 -113.486172) (xy 109.774995 -113.541637)
			(xy 109.706003 -113.590766) (xy 109.632653 -113.633115) (xy 109.55561 -113.668299) (xy 109.475571 -113.696001)
			(xy 109.393262 -113.715969) (xy 109.309427 -113.728022) (xy 109.224826 -113.732053) (xy 109.140225 -113.728022)
			(xy 109.05639 -113.715969) (xy 108.974081 -113.696001) (xy 108.894042 -113.668299) (xy 108.816999 -113.633115)
			(xy 108.743649 -113.590766) (xy 108.674657 -113.541637) (xy 108.610647 -113.486172) (xy 108.552199 -113.424874)
			(xy 108.499843 -113.358298) (xy 108.454053 -113.287046) (xy 108.415242 -113.211765) (xy 108.383763 -113.133135)
			(xy 108.359902 -113.051868) (xy 108.343873 -112.968702) (xy 108.335822 -112.884388) (xy 97.726023 -112.884388)
			(xy 97.730899 -112.909688) (xy 97.73895 -112.994002) (xy 97.739454 -113.03635) (xy 97.73895 -113.078698)
			(xy 97.730899 -113.163012) (xy 97.71487 -113.246178) (xy 97.691009 -113.327445) (xy 97.65953 -113.406075)
			(xy 97.620719 -113.481356) (xy 97.574929 -113.552608) (xy 97.522573 -113.619184) (xy 97.464125 -113.680482)
			(xy 97.400115 -113.735947) (xy 97.331123 -113.785076) (xy 97.257773 -113.827425) (xy 97.18073 -113.862609)
			(xy 97.100691 -113.890311) (xy 97.018382 -113.910279) (xy 96.934547 -113.922332) (xy 96.849946 -113.926363)
			(xy 96.765345 -113.922332) (xy 96.68151 -113.910279) (xy 96.599201 -113.890311) (xy 96.519162 -113.862609)
			(xy 96.442119 -113.827425) (xy 96.368769 -113.785076) (xy 96.299777 -113.735947) (xy 96.235767 -113.680482)
			(xy 96.177319 -113.619184) (xy 96.124963 -113.552608) (xy 96.079173 -113.481356) (xy 96.040362 -113.406075)
			(xy 96.008883 -113.327445) (xy 95.985022 -113.246178) (xy 95.968993 -113.163012) (xy 95.960942 -113.078698)
			(xy 57.73903 -113.078698) (xy 57.730979 -113.163012) (xy 57.71495 -113.246178) (xy 57.691089 -113.327445)
			(xy 57.65961 -113.406075) (xy 57.620799 -113.481356) (xy 57.575009 -113.552608) (xy 57.522653 -113.619184)
			(xy 57.464205 -113.680482) (xy 57.400195 -113.735947) (xy 57.331203 -113.785076) (xy 57.257853 -113.827425)
			(xy 57.18081 -113.862609) (xy 57.100771 -113.890311) (xy 57.018462 -113.910279) (xy 56.934627 -113.922332)
			(xy 56.850026 -113.926363) (xy 56.765425 -113.922332) (xy 56.68159 -113.910279) (xy 56.599281 -113.890311)
			(xy 56.519242 -113.862609) (xy 56.442199 -113.827425) (xy 56.368849 -113.785076) (xy 56.299857 -113.735947)
			(xy 56.235847 -113.680482) (xy 56.177399 -113.619184) (xy 56.125043 -113.552608) (xy 56.079253 -113.481356)
			(xy 56.040442 -113.406075) (xy 56.008963 -113.327445) (xy 55.985102 -113.246178) (xy 55.969073 -113.163012)
			(xy 55.961022 -113.078698) (xy 37.8714 -113.078698) (xy 37.8714 -114.856698) (xy 108.843822 -114.856698)
			(xy 108.843822 -114.772002) (xy 108.851873 -114.687688) (xy 108.867902 -114.604522) (xy 108.891763 -114.523255)
			(xy 108.923242 -114.444625) (xy 108.962053 -114.369344) (xy 109.007843 -114.298092) (xy 109.060199 -114.231516)
			(xy 109.118647 -114.170218) (xy 109.182657 -114.114753) (xy 109.251649 -114.065624) (xy 109.324999 -114.023275)
			(xy 109.402042 -113.988091) (xy 109.482081 -113.960389) (xy 109.56439 -113.940421) (xy 109.648225 -113.928368)
			(xy 109.732826 -113.924338) (xy 109.817427 -113.928368) (xy 109.901262 -113.940421) (xy 109.983571 -113.960389)
			(xy 110.06361 -113.988091) (xy 110.140653 -114.023275) (xy 110.214003 -114.065624) (xy 110.282995 -114.114753)
			(xy 110.347005 -114.170218) (xy 110.405453 -114.231516) (xy 110.457809 -114.298092) (xy 110.503599 -114.369344)
			(xy 110.54241 -114.444625) (xy 110.573889 -114.523255) (xy 110.59775 -114.604522) (xy 110.613779 -114.687688)
			(xy 110.62183 -114.772002) (xy 110.622334 -114.81435) (xy 110.62183 -114.856698) (xy 110.613779 -114.941012)
			(xy 110.59775 -115.024178) (xy 110.573889 -115.105445) (xy 110.54241 -115.184075) (xy 110.503599 -115.259356)
			(xy 110.457809 -115.330608) (xy 110.405453 -115.397184) (xy 110.347005 -115.458482) (xy 110.282995 -115.513947)
			(xy 110.214003 -115.563076) (xy 110.140653 -115.605425) (xy 110.06361 -115.640609) (xy 109.983571 -115.668311)
			(xy 109.901262 -115.688279) (xy 109.817427 -115.700332) (xy 109.732826 -115.704363) (xy 109.648225 -115.700332)
			(xy 109.56439 -115.688279) (xy 109.482081 -115.668311) (xy 109.402042 -115.640609) (xy 109.324999 -115.605425)
			(xy 109.251649 -115.563076) (xy 109.182657 -115.513947) (xy 109.118647 -115.458482) (xy 109.060199 -115.397184)
			(xy 109.007843 -115.330608) (xy 108.962053 -115.259356) (xy 108.923242 -115.184075) (xy 108.891763 -115.105445)
			(xy 108.867902 -115.024178) (xy 108.851873 -114.941012) (xy 108.843822 -114.856698) (xy 37.8714 -114.856698)
			(xy 37.8714 -115.874546) (xy 37.871832 -115.884612) (xy 37.879558 -115.903205) (xy 37.886386 -115.910614)
			(xy 38.165786 -116.190014) (xy 38.173185 -116.196856) (xy 38.191784 -116.204573) (xy 38.201854 -116.205)
			(xy 224.187258 -116.205) (xy 224.197323 -116.205434) (xy 224.215913 -116.213163) (xy 224.223326 -116.219986)
			(xy 224.975096 -116.971756) (xy 270.314416 -116.971756) (xy 270.314416 -116.88706) (xy 270.322467 -116.802746)
			(xy 270.338496 -116.71958) (xy 270.362357 -116.638313) (xy 270.393836 -116.559683) (xy 270.432647 -116.484402)
			(xy 270.478437 -116.41315) (xy 270.530793 -116.346574) (xy 270.589241 -116.285276) (xy 270.653251 -116.229811)
			(xy 270.722243 -116.180682) (xy 270.795593 -116.138333) (xy 270.872636 -116.103149) (xy 270.952675 -116.075447)
			(xy 271.034984 -116.055479) (xy 271.118819 -116.043426) (xy 271.20342 -116.039396) (xy 271.288021 -116.043426)
			(xy 271.371856 -116.055479) (xy 271.454165 -116.075447) (xy 271.534204 -116.103149) (xy 271.611247 -116.138333)
			(xy 271.684597 -116.180682) (xy 271.753589 -116.229811) (xy 271.817599 -116.285276) (xy 271.876047 -116.346574)
			(xy 271.928403 -116.41315) (xy 271.974193 -116.484402) (xy 272.013004 -116.559683) (xy 272.044483 -116.638313)
			(xy 272.068344 -116.71958) (xy 272.084373 -116.802746) (xy 272.092424 -116.88706) (xy 272.092928 -116.929408)
			(xy 272.092424 -116.971756) (xy 272.084373 -117.05607) (xy 272.068344 -117.139236) (xy 272.044483 -117.220503)
			(xy 272.013004 -117.299133) (xy 271.974193 -117.374414) (xy 271.928403 -117.445666) (xy 271.876047 -117.512242)
			(xy 271.817599 -117.57354) (xy 271.753589 -117.629005) (xy 271.684597 -117.678134) (xy 271.611247 -117.720483)
			(xy 271.534204 -117.755667) (xy 271.454165 -117.783369) (xy 271.371856 -117.803337) (xy 271.288021 -117.81539)
			(xy 271.20342 -117.819421) (xy 271.118819 -117.81539) (xy 271.034984 -117.803337) (xy 270.952675 -117.783369)
			(xy 270.872636 -117.755667) (xy 270.795593 -117.720483) (xy 270.722243 -117.678134) (xy 270.653251 -117.629005)
			(xy 270.589241 -117.57354) (xy 270.530793 -117.512242) (xy 270.478437 -117.445666) (xy 270.432647 -117.374414)
			(xy 270.393836 -117.299133) (xy 270.362357 -117.220503) (xy 270.338496 -117.139236) (xy 270.322467 -117.05607)
			(xy 270.314416 -116.971756) (xy 224.975096 -116.971756) (xy 225.948494 -117.945154) (xy 225.955333 -117.952555)
			(xy 225.963048 -117.971153) (xy 225.96348 -117.981222) (xy 225.96348 -118.467816) (xy 268.757396 -118.467816)
			(xy 268.757396 -118.38312) (xy 268.765447 -118.298806) (xy 268.781476 -118.21564) (xy 268.805337 -118.134373)
			(xy 268.836816 -118.055743) (xy 268.875627 -117.980462) (xy 268.921417 -117.90921) (xy 268.973773 -117.842634)
			(xy 269.032221 -117.781336) (xy 269.096231 -117.725871) (xy 269.165223 -117.676742) (xy 269.238573 -117.634393)
			(xy 269.315616 -117.599209) (xy 269.395655 -117.571507) (xy 269.477964 -117.551539) (xy 269.561799 -117.539486)
			(xy 269.6464 -117.535456) (xy 269.731001 -117.539486) (xy 269.814836 -117.551539) (xy 269.897145 -117.571507)
			(xy 269.977184 -117.599209) (xy 270.054227 -117.634393) (xy 270.127577 -117.676742) (xy 270.196569 -117.725871)
			(xy 270.260579 -117.781336) (xy 270.319027 -117.842634) (xy 270.371383 -117.90921) (xy 270.417173 -117.980462)
			(xy 270.455984 -118.055743) (xy 270.487463 -118.134373) (xy 270.511324 -118.21564) (xy 270.527353 -118.298806)
			(xy 270.535404 -118.38312) (xy 270.535908 -118.425468) (xy 270.535404 -118.467816) (xy 270.527353 -118.55213)
			(xy 270.511324 -118.635296) (xy 270.487463 -118.716563) (xy 270.455984 -118.795193) (xy 270.417173 -118.870474)
			(xy 270.371383 -118.941726) (xy 270.319027 -119.008302) (xy 270.260579 -119.0696) (xy 270.196569 -119.125065)
			(xy 270.127577 -119.174194) (xy 270.054227 -119.216543) (xy 269.977184 -119.251727) (xy 269.897145 -119.279429)
			(xy 269.814836 -119.299397) (xy 269.731001 -119.31145) (xy 269.6464 -119.315481) (xy 269.561799 -119.31145)
			(xy 269.477964 -119.299397) (xy 269.395655 -119.279429) (xy 269.315616 -119.251727) (xy 269.238573 -119.216543)
			(xy 269.165223 -119.174194) (xy 269.096231 -119.125065) (xy 269.032221 -119.0696) (xy 268.973773 -119.008302)
			(xy 268.921417 -118.941726) (xy 268.875627 -118.870474) (xy 268.836816 -118.795193) (xy 268.805337 -118.716563)
			(xy 268.781476 -118.635296) (xy 268.765447 -118.55213) (xy 268.757396 -118.467816) (xy 225.96348 -118.467816)
			(xy 225.96348 -128.980114) (xy 270.34896 -128.980114) (xy 270.34896 -128.895418) (xy 270.357011 -128.811104)
			(xy 270.37304 -128.727938) (xy 270.396901 -128.646671) (xy 270.42838 -128.568041) (xy 270.467191 -128.49276)
			(xy 270.512981 -128.421508) (xy 270.565337 -128.354932) (xy 270.623785 -128.293634) (xy 270.687795 -128.238169)
			(xy 270.756787 -128.18904) (xy 270.830137 -128.146691) (xy 270.90718 -128.111507) (xy 270.987219 -128.083805)
			(xy 271.069528 -128.063837) (xy 271.153363 -128.051784) (xy 271.237964 -128.047754) (xy 271.322565 -128.051784)
			(xy 271.4064 -128.063837) (xy 271.488709 -128.083805) (xy 271.568748 -128.111507) (xy 271.645791 -128.146691)
			(xy 271.719141 -128.18904) (xy 271.788133 -128.238169) (xy 271.852143 -128.293634) (xy 271.910591 -128.354932)
			(xy 271.962947 -128.421508) (xy 272.008737 -128.49276) (xy 272.047548 -128.568041) (xy 272.079027 -128.646671)
			(xy 272.102888 -128.727938) (xy 272.118917 -128.811104) (xy 272.126968 -128.895418) (xy 272.127472 -128.937766)
			(xy 272.126968 -128.980114) (xy 272.118917 -129.064428) (xy 272.102888 -129.147594) (xy 272.079027 -129.228861)
			(xy 272.047548 -129.307491) (xy 272.008737 -129.382772) (xy 271.962947 -129.454024) (xy 271.910591 -129.5206)
			(xy 271.852143 -129.581898) (xy 271.788133 -129.637363) (xy 271.719141 -129.686492) (xy 271.645791 -129.728841)
			(xy 271.568748 -129.764025) (xy 271.488709 -129.791727) (xy 271.4064 -129.811695) (xy 271.322565 -129.823748)
			(xy 271.237964 -129.827779) (xy 271.153363 -129.823748) (xy 271.069528 -129.811695) (xy 270.987219 -129.791727)
			(xy 270.90718 -129.764025) (xy 270.830137 -129.728841) (xy 270.756787 -129.686492) (xy 270.687795 -129.637363)
			(xy 270.623785 -129.581898) (xy 270.565337 -129.5206) (xy 270.512981 -129.454024) (xy 270.467191 -129.382772)
			(xy 270.42838 -129.307491) (xy 270.396901 -129.228861) (xy 270.37304 -129.147594) (xy 270.357011 -129.064428)
			(xy 270.34896 -128.980114) (xy 225.96348 -128.980114) (xy 225.96348 -130.532816) (xy 268.757396 -130.532816)
			(xy 268.757396 -130.44812) (xy 268.765447 -130.363806) (xy 268.781476 -130.28064) (xy 268.805337 -130.199373)
			(xy 268.836816 -130.120743) (xy 268.875627 -130.045462) (xy 268.921417 -129.97421) (xy 268.973773 -129.907634)
			(xy 269.032221 -129.846336) (xy 269.096231 -129.790871) (xy 269.165223 -129.741742) (xy 269.238573 -129.699393)
			(xy 269.315616 -129.664209) (xy 269.395655 -129.636507) (xy 269.477964 -129.616539) (xy 269.561799 -129.604486)
			(xy 269.6464 -129.600456) (xy 269.731001 -129.604486) (xy 269.814836 -129.616539) (xy 269.897145 -129.636507)
			(xy 269.977184 -129.664209) (xy 270.054227 -129.699393) (xy 270.127577 -129.741742) (xy 270.196569 -129.790871)
			(xy 270.260579 -129.846336) (xy 270.319027 -129.907634) (xy 270.371383 -129.97421) (xy 270.417173 -130.045462)
			(xy 270.455984 -130.120743) (xy 270.487463 -130.199373) (xy 270.511324 -130.28064) (xy 270.527353 -130.363806)
			(xy 270.535404 -130.44812) (xy 270.535908 -130.490468) (xy 270.535404 -130.532816) (xy 270.527353 -130.61713)
			(xy 270.511324 -130.700296) (xy 270.487463 -130.781563) (xy 270.455984 -130.860193) (xy 270.417173 -130.935474)
			(xy 270.371383 -131.006726) (xy 270.319027 -131.073302) (xy 270.260579 -131.1346) (xy 270.196569 -131.190065)
			(xy 270.127577 -131.239194) (xy 270.054227 -131.281543) (xy 269.977184 -131.316727) (xy 269.897145 -131.344429)
			(xy 269.814836 -131.364397) (xy 269.731001 -131.37645) (xy 269.6464 -131.380481) (xy 269.561799 -131.37645)
			(xy 269.477964 -131.364397) (xy 269.395655 -131.344429) (xy 269.315616 -131.316727) (xy 269.238573 -131.281543)
			(xy 269.165223 -131.239194) (xy 269.096231 -131.190065) (xy 269.032221 -131.1346) (xy 268.973773 -131.073302)
			(xy 268.921417 -131.006726) (xy 268.875627 -130.935474) (xy 268.836816 -130.860193) (xy 268.805337 -130.781563)
			(xy 268.781476 -130.700296) (xy 268.765447 -130.61713) (xy 268.757396 -130.532816) (xy 225.96348 -130.532816)
			(xy 225.96348 -137.795) (xy 234.110777 -137.795) (xy 234.114814 -137.581715) (xy 234.126919 -137.368736)
			(xy 234.147075 -137.156368) (xy 234.175253 -136.944914) (xy 234.211412 -136.734678) (xy 234.255501 -136.525961)
			(xy 234.307457 -136.319062) (xy 234.367204 -136.114277) (xy 234.434659 -135.9119) (xy 234.509723 -135.712221)
			(xy 234.59229 -135.515524) (xy 234.68224 -135.322094) (xy 234.779447 -135.132205) (xy 234.883769 -134.946131)
			(xy 234.995057 -134.764138) (xy 235.113153 -134.586487) (xy 235.237887 -134.413432) (xy 235.369081 -134.245221)
			(xy 235.506545 -134.082095) (xy 235.650084 -133.924288) (xy 235.799492 -133.772025) (xy 235.954555 -133.625525)
			(xy 236.115051 -133.484998) (xy 236.280749 -133.350646) (xy 236.451413 -133.222659) (xy 236.626797 -133.101223)
			(xy 236.806652 -132.98651) (xy 236.990718 -132.878685) (xy 237.178733 -132.777903) (xy 237.370427 -132.684308)
			(xy 237.565525 -132.598034) (xy 237.763749 -132.519205) (xy 237.964813 -132.447933) (xy 238.168431 -132.38432)
			(xy 238.37431 -132.328459) (xy 238.582155 -132.280428) (xy 238.791669 -132.240297) (xy 239.002552 -132.208123)
			(xy 239.214501 -132.183952) (xy 239.427213 -132.167819) (xy 239.640383 -132.159746) (xy 239.747044 -132.159248)
			(xy 261.747 -132.159248) (xy 261.853661 -132.159753) (xy 262.066831 -132.167825) (xy 262.279542 -132.183959)
			(xy 262.491491 -132.20813) (xy 262.702373 -132.240304) (xy 262.911887 -132.280435) (xy 263.119732 -132.328466)
			(xy 263.32561 -132.384328) (xy 263.529228 -132.44794) (xy 263.730292 -132.519212) (xy 263.928515 -132.598041)
			(xy 264.123613 -132.684315) (xy 264.315306 -132.77791) (xy 264.503321 -132.878692) (xy 264.687387 -132.986517)
			(xy 264.867241 -133.101229) (xy 265.042626 -133.222666) (xy 265.213289 -133.350652) (xy 265.378987 -133.485005)
			(xy 265.539482 -133.625532) (xy 265.694545 -133.772031) (xy 265.843952 -133.924293) (xy 265.987491 -134.082101)
			(xy 266.124956 -134.245226) (xy 266.256148 -134.413437) (xy 266.380882 -134.586492) (xy 266.498978 -134.764143)
			(xy 266.610266 -134.946136) (xy 266.714588 -135.132209) (xy 266.811794 -135.322097) (xy 266.901745 -135.515528)
			(xy 266.984311 -135.712224) (xy 267.059376 -135.911903) (xy 267.12683 -136.11428) (xy 267.186577 -136.319065)
			(xy 267.238533 -136.525963) (xy 267.282622 -136.73468) (xy 267.318781 -136.944916) (xy 267.346959 -137.156369)
			(xy 267.367115 -137.368737) (xy 267.37922 -137.581716) (xy 267.383257 -137.795) (xy 267.37922 -138.008284)
			(xy 267.367115 -138.221263) (xy 267.346959 -138.433631) (xy 267.318781 -138.645084) (xy 267.282622 -138.85532)
			(xy 267.238533 -139.064037) (xy 267.186577 -139.270935) (xy 267.12683 -139.47572) (xy 267.059376 -139.678097)
			(xy 266.984311 -139.877776) (xy 266.901745 -140.074472) (xy 266.811794 -140.267903) (xy 266.714588 -140.457791)
			(xy 266.610266 -140.643864) (xy 266.498978 -140.825857) (xy 266.380882 -141.003508) (xy 266.256148 -141.176563)
			(xy 266.124956 -141.344774) (xy 265.987491 -141.507899) (xy 265.843952 -141.665707) (xy 265.694545 -141.817969)
			(xy 265.539482 -141.964468) (xy 265.378987 -142.104995) (xy 265.213289 -142.239348) (xy 265.042626 -142.367334)
			(xy 264.867241 -142.488771) (xy 264.687387 -142.603483) (xy 264.503321 -142.711308) (xy 264.315306 -142.81209)
			(xy 264.123613 -142.905685) (xy 263.928515 -142.991959) (xy 263.730292 -143.070788) (xy 263.529228 -143.14206)
			(xy 263.32561 -143.205672) (xy 263.119732 -143.261534) (xy 262.911887 -143.309565) (xy 262.702373 -143.349696)
			(xy 262.491491 -143.38187) (xy 262.279542 -143.406041) (xy 262.066831 -143.422175) (xy 261.853661 -143.430247)
			(xy 261.747 -143.430752) (xy 239.747044 -143.430752) (xy 239.640383 -143.430254) (xy 239.427213 -143.422181)
			(xy 239.214501 -143.406048) (xy 239.002552 -143.381877) (xy 238.791669 -143.349703) (xy 238.582155 -143.309572)
			(xy 238.37431 -143.261541) (xy 238.168431 -143.20568) (xy 237.964813 -143.142067) (xy 237.763749 -143.070795)
			(xy 237.565525 -142.991966) (xy 237.370427 -142.905692) (xy 237.178733 -142.812097) (xy 236.990718 -142.711315)
			(xy 236.806652 -142.60349) (xy 236.626797 -142.488777) (xy 236.451413 -142.367341) (xy 236.280749 -142.239354)
			(xy 236.115051 -142.105002) (xy 235.954555 -141.964475) (xy 235.799492 -141.817975) (xy 235.650084 -141.665712)
			(xy 235.506545 -141.507905) (xy 235.369081 -141.344779) (xy 235.237887 -141.176568) (xy 235.113153 -141.003513)
			(xy 234.995057 -140.825862) (xy 234.883769 -140.643869) (xy 234.779447 -140.457795) (xy 234.68224 -140.267906)
			(xy 234.59229 -140.074476) (xy 234.509723 -139.877779) (xy 234.434659 -139.6781) (xy 234.367204 -139.475723)
			(xy 234.307457 -139.270938) (xy 234.255501 -139.064039) (xy 234.211412 -138.855322) (xy 234.175253 -138.645086)
			(xy 234.147075 -138.433632) (xy 234.126919 -138.221264) (xy 234.114814 -138.008285) (xy 234.110777 -137.795)
			(xy 225.96348 -137.795) (xy 225.96348 -143.321278) (xy 225.963917 -143.331342) (xy 225.971649 -143.349928)
			(xy 225.978466 -143.357346) (xy 227.30968 -144.68856) (xy 227.317081 -144.695398) (xy 227.33568 -144.70311)
			(xy 227.345748 -144.703546)
		)
		(stroke
			(width 0)
			(type solid)
		)
		(fill yes)
		(layer "In7.Cu")
		(net "P52V_HS")
	)
	(gr_poly
		(pts
			(xy 323.778118 -145.5674) (xy 323.788187 -145.566973) (xy 323.806786 -145.559254) (xy 323.814186 -145.552414)
			(xy 326.502014 -142.864586) (xy 326.508868 -142.857191) (xy 326.51661 -142.838592) (xy 326.517 -142.828518)
			(xy 326.517 -4.847082) (xy 326.516573 -4.837013) (xy 326.508854 -4.818414) (xy 326.502014 -4.811014)
			(xy 323.232272 -1.541272) (xy 323.224875 -1.534422) (xy 323.206277 -1.526687) (xy 323.196204 -1.526286)
			(xy 166.261796 -1.526286) (xy 166.251726 -1.526709) (xy 166.233121 -1.534423) (xy 166.225728 -1.541272)
			(xy 165.318186 -2.448814) (xy 165.311332 -2.456209) (xy 165.30359 -2.474808) (xy 165.3032 -2.484882)
			(xy 165.3032 -4.36987) (xy 242.877075 -4.36987) (xy 242.877075 -4.24073) (xy 242.885025 -4.111835)
			(xy 242.900895 -3.983675) (xy 242.924624 -3.856734) (xy 242.956123 -3.731495) (xy 242.995272 -3.608432)
			(xy 243.041923 -3.488013) (xy 243.095898 -3.370694) (xy 243.156993 -3.25692) (xy 243.224976 -3.147123)
			(xy 243.29959 -3.04172) (xy 243.380551 -2.94111) (xy 243.467551 -2.845675) (xy 243.560262 -2.755776)
			(xy 243.658332 -2.671755) (xy 243.761387 -2.593931) (xy 243.869038 -2.522599) (xy 243.980877 -2.458029)
			(xy 244.096478 -2.400467) (xy 244.215403 -2.35013) (xy 244.337202 -2.30721) (xy 244.461412 -2.271869)
			(xy 244.587561 -2.244242) (xy 244.715173 -2.224433) (xy 244.843762 -2.212517) (xy 244.97284 -2.208541)
			(xy 245.101918 -2.212517) (xy 245.230507 -2.224433) (xy 245.358119 -2.244242) (xy 245.484268 -2.271869)
			(xy 245.608478 -2.30721) (xy 245.730277 -2.35013) (xy 245.849202 -2.400467) (xy 245.964803 -2.458029)
			(xy 246.076642 -2.522599) (xy 246.184293 -2.593931) (xy 246.287348 -2.671755) (xy 246.385418 -2.755776)
			(xy 246.478129 -2.845675) (xy 246.565129 -2.94111) (xy 246.64609 -3.04172) (xy 246.720704 -3.147123)
			(xy 246.788687 -3.25692) (xy 246.849782 -3.370694) (xy 246.903757 -3.488013) (xy 246.950408 -3.608432)
			(xy 246.989557 -3.731495) (xy 247.021056 -3.856734) (xy 247.044785 -3.983675) (xy 247.060655 -4.111835)
			(xy 247.068605 -4.24073) (xy 247.069102 -4.3053) (xy 247.068605 -4.36987) (xy 247.060655 -4.498765)
			(xy 247.044785 -4.626925) (xy 247.021056 -4.753866) (xy 246.989557 -4.879105) (xy 246.950408 -5.002168)
			(xy 246.903757 -5.122587) (xy 246.849782 -5.239906) (xy 246.788687 -5.35368) (xy 246.720704 -5.463477)
			(xy 246.64609 -5.56888) (xy 246.565129 -5.66949) (xy 246.478129 -5.764925) (xy 246.385418 -5.854824)
			(xy 246.287348 -5.938845) (xy 246.184293 -6.016669) (xy 246.076642 -6.088001) (xy 245.964803 -6.152571)
			(xy 245.849202 -6.210133) (xy 245.730277 -6.26047) (xy 245.608478 -6.30339) (xy 245.484268 -6.338731)
			(xy 245.358119 -6.366358) (xy 245.230507 -6.386167) (xy 245.101918 -6.398083) (xy 244.97284 -6.40206)
			(xy 244.843762 -6.398083) (xy 244.715173 -6.386167) (xy 244.587561 -6.366358) (xy 244.461412 -6.338731)
			(xy 244.337202 -6.30339) (xy 244.215403 -6.26047) (xy 244.096478 -6.210133) (xy 243.980877 -6.152571)
			(xy 243.869038 -6.088001) (xy 243.761387 -6.016669) (xy 243.658332 -5.938845) (xy 243.560262 -5.854824)
			(xy 243.467551 -5.764925) (xy 243.380551 -5.66949) (xy 243.29959 -5.56888) (xy 243.224976 -5.463477)
			(xy 243.156993 -5.35368) (xy 243.095898 -5.239906) (xy 243.041923 -5.122587) (xy 242.995272 -5.002168)
			(xy 242.956123 -4.879105) (xy 242.924624 -4.753866) (xy 242.900895 -4.626925) (xy 242.885025 -4.498765)
			(xy 242.877075 -4.36987) (xy 165.3032 -4.36987) (xy 165.3032 -7.493) (xy 176.001932 -7.493) (xy 176.006003 -7.437378)
			(xy 176.018129 -7.382941) (xy 176.038052 -7.33085) (xy 176.065348 -7.282215) (xy 176.099434 -7.238072)
			(xy 176.139583 -7.199363) (xy 176.184941 -7.166912) (xy 176.234541 -7.141411) (xy 176.287325 -7.123404)
			(xy 176.342168 -7.113274) (xy 176.397902 -7.111237) (xy 176.453339 -7.117337) (xy 176.507296 -7.131443)
			(xy 176.558625 -7.153255) (xy 176.606231 -7.182309) (xy 176.649099 -7.217984) (xy 176.686316 -7.259521)
			(xy 176.717089 -7.306034) (xy 176.740761 -7.356531) (xy 176.756829 -7.409938) (xy 176.764949 -7.465114)
			(xy 176.765458 -7.493) (xy 176.764949 -7.520886) (xy 176.756829 -7.576062) (xy 176.74361 -7.62) (xy 188.889132 -7.62)
			(xy 188.889637 -7.577094) (xy 188.89791 -7.491682) (xy 188.914369 -7.407463) (xy 188.938862 -7.32522)
			(xy 188.97116 -7.245718) (xy 189.010964 -7.169696) (xy 189.057903 -7.09786) (xy 189.111542 -7.030878)
			(xy 189.171381 -6.969372) (xy 189.236865 -6.913915) (xy 189.307385 -6.865021) (xy 189.382286 -6.823144)
			(xy 189.460871 -6.788675) (xy 189.54241 -6.761934) (xy 189.626145 -6.743168) (xy 189.668658 -6.73735)
			(xy 189.678792 -6.735601) (xy 189.696558 -6.725277) (xy 189.708904 -6.708852) (xy 189.711838 -6.698996)
			(xy 189.722338 -6.657972) (xy 189.750038 -6.577943) (xy 189.785219 -6.50091) (xy 189.827563 -6.42757)
			(xy 189.876686 -6.358586) (xy 189.932145 -6.294585) (xy 189.993436 -6.236145) (xy 190.060005 -6.183796)
			(xy 190.131248 -6.138011) (xy 190.20652 -6.099206) (xy 190.285141 -6.067731) (xy 190.366397 -6.043872)
			(xy 190.449553 -6.027845) (xy 190.533857 -6.019795) (xy 190.5762 -6.019292) (xy 190.618559 -6.019838)
			(xy 190.702893 -6.027909) (xy 190.786078 -6.043958) (xy 190.867361 -6.067841) (xy 190.946006 -6.099341)
			(xy 191.021301 -6.138173) (xy 191.092565 -6.183985) (xy 191.159152 -6.236363) (xy 191.22046 -6.294832)
			(xy 191.275933 -6.358864) (xy 191.325069 -6.427878) (xy 191.367424 -6.501249) (xy 191.402614 -6.578314)
			(xy 191.43032 -6.658374) (xy 191.450291 -6.740705) (xy 191.456818 -6.782562) (xy 191.458444 -6.791251)
			(xy 191.466704 -6.806863) (xy 191.479781 -6.818734) (xy 191.487806 -6.82244) (xy 191.52812 -6.839574)
			(xy 191.605508 -6.88062) (xy 191.678487 -6.929075) (xy 191.746349 -6.98447) (xy 191.808436 -7.046268)
			(xy 191.864148 -7.11387) (xy 191.912944 -7.186622) (xy 191.954351 -7.263818) (xy 191.987969 -7.344711)
			(xy 192.013471 -7.428517) (xy 192.030611 -7.514424) (xy 192.039223 -7.6016) (xy 192.039748 -7.6454)
			(xy 192.039233 -7.686501) (xy 192.031649 -7.768353) (xy 192.016545 -7.849156) (xy 191.994049 -7.928221)
			(xy 191.964355 -8.004873) (xy 191.927715 -8.078458) (xy 191.884442 -8.148349) (xy 191.834905 -8.213949)
			(xy 191.779527 -8.274699) (xy 191.71878 -8.33008) (xy 191.653182 -8.37962) (xy 191.583293 -8.422896)
			(xy 191.50971 -8.459539) (xy 191.433059 -8.489237) (xy 191.353995 -8.511736) (xy 191.273193 -8.526843)
			(xy 191.191341 -8.534432) (xy 191.15024 -8.534908) (xy 191.107122 -8.534391) (xy 191.021289 -8.526046)
			(xy 190.936668 -8.509431) (xy 190.854053 -8.484702) (xy 190.813944 -8.468868) (xy 190.804575 -8.465531)
			(xy 190.784705 -8.465531) (xy 190.775336 -8.468868) (xy 190.735223 -8.484692) (xy 190.652609 -8.509425)
			(xy 190.56799 -8.526046) (xy 190.482158 -8.534397) (xy 190.43904 -8.534908) (xy 190.394823 -8.534366)
			(xy 190.306823 -8.525614) (xy 190.220127 -8.508163) (xy 190.135595 -8.482185) (xy 190.094616 -8.465566)
			(xy 190.086044 -8.462444) (xy 190.067826 -8.461785) (xy 190.059056 -8.464296) (xy 190.013723 -8.478678)
			(xy 189.920769 -8.49882) (xy 189.826196 -8.508918) (xy 189.77864 -8.509508) (xy 189.737537 -8.50901)
			(xy 189.655683 -8.501428) (xy 189.574877 -8.486326) (xy 189.495809 -8.463833) (xy 189.419154 -8.43414)
			(xy 189.345566 -8.3975) (xy 189.275673 -8.354227) (xy 189.210071 -8.304689) (xy 189.149319 -8.249309)
			(xy 189.093937 -8.18856) (xy 189.044396 -8.12296) (xy 189.00112 -8.053069) (xy 188.964477 -7.979482)
			(xy 188.93478 -7.902829) (xy 188.912283 -7.823762) (xy 188.897177 -7.742957) (xy 188.889592 -7.661102)
			(xy 188.889132 -7.62) (xy 176.74361 -7.62) (xy 176.740761 -7.629469) (xy 176.717089 -7.679966) (xy 176.686316 -7.726479)
			(xy 176.649099 -7.768016) (xy 176.606231 -7.803691) (xy 176.558625 -7.832745) (xy 176.507296 -7.854557)
			(xy 176.453339 -7.868663) (xy 176.397902 -7.874763) (xy 176.342168 -7.872726) (xy 176.287325 -7.862596)
			(xy 176.234541 -7.844589) (xy 176.184941 -7.819088) (xy 176.139583 -7.786637) (xy 176.099434 -7.747928)
			(xy 176.065348 -7.703785) (xy 176.038052 -7.65515) (xy 176.018129 -7.603059) (xy 176.006003 -7.548622)
			(xy 176.001932 -7.493) (xy 165.3032 -7.493) (xy 165.3032 -8.128) (xy 179.195982 -8.128) (xy 179.200053 -8.072378)
			(xy 179.212179 -8.017941) (xy 179.232102 -7.96585) (xy 179.259398 -7.917215) (xy 179.293484 -7.873072)
			(xy 179.333633 -7.834363) (xy 179.378991 -7.801912) (xy 179.428591 -7.776411) (xy 179.481375 -7.758404)
			(xy 179.536218 -7.748274) (xy 179.591952 -7.746237) (xy 179.647389 -7.752337) (xy 179.701346 -7.766443)
			(xy 179.752675 -7.788255) (xy 179.800281 -7.817309) (xy 179.843149 -7.852984) (xy 179.880366 -7.894521)
			(xy 179.911139 -7.941034) (xy 179.934811 -7.991531) (xy 179.950879 -8.044938) (xy 179.958999 -8.100114)
			(xy 179.959508 -8.128) (xy 179.958999 -8.155886) (xy 179.950879 -8.211062) (xy 179.934811 -8.264469)
			(xy 179.911139 -8.314966) (xy 179.880366 -8.361479) (xy 179.843149 -8.403016) (xy 179.800281 -8.438691)
			(xy 179.752675 -8.467745) (xy 179.701346 -8.489557) (xy 179.647389 -8.503663) (xy 179.591952 -8.509763)
			(xy 179.536218 -8.507726) (xy 179.481375 -8.497596) (xy 179.428591 -8.479589) (xy 179.378991 -8.454088)
			(xy 179.333633 -8.421637) (xy 179.293484 -8.382928) (xy 179.259398 -8.338785) (xy 179.232102 -8.29015)
			(xy 179.212179 -8.238059) (xy 179.200053 -8.183622) (xy 179.195982 -8.128) (xy 165.3032 -8.128) (xy 165.3032 -10.033)
			(xy 174.897032 -10.033) (xy 174.901103 -9.977378) (xy 174.913229 -9.922941) (xy 174.933152 -9.87085)
			(xy 174.960448 -9.822215) (xy 174.994534 -9.778072) (xy 175.034683 -9.739363) (xy 175.080041 -9.706912)
			(xy 175.129641 -9.681411) (xy 175.182425 -9.663404) (xy 175.237268 -9.653274) (xy 175.293002 -9.651237)
			(xy 175.348439 -9.657337) (xy 175.402396 -9.671443) (xy 175.453725 -9.693255) (xy 175.501331 -9.722309)
			(xy 175.544199 -9.757984) (xy 175.563029 -9.779) (xy 188.888572 -9.779) (xy 188.892602 -9.694395)
			(xy 188.904657 -9.610556) (xy 188.924626 -9.528243) (xy 188.95233 -9.448201) (xy 188.987517 -9.371155)
			(xy 189.029869 -9.297802) (xy 189.079001 -9.228808) (xy 189.13447 -9.164796) (xy 189.195772 -9.106347)
			(xy 189.262353 -9.053991) (xy 189.333609 -9.0082) (xy 189.408895 -8.96939) (xy 189.48753 -8.937912)
			(xy 189.568801 -8.914052) (xy 189.651972 -8.898026) (xy 189.73629 -8.889978) (xy 189.77864 -8.889492)
			(xy 189.822857 -8.89004) (xy 189.910857 -8.89879) (xy 189.997552 -8.91624) (xy 190.082085 -8.942216)
			(xy 190.123064 -8.958834) (xy 190.131639 -8.961946) (xy 190.149854 -8.962612) (xy 190.158624 -8.960104)
			(xy 190.203958 -8.945727) (xy 190.296912 -8.925584) (xy 190.391484 -8.915483) (xy 190.43904 -8.914892)
			(xy 190.482158 -8.915416) (xy 190.56799 -8.923759) (xy 190.652611 -8.940372) (xy 190.735227 -8.965099)
			(xy 190.775336 -8.980932) (xy 190.784705 -8.984269) (xy 190.804575 -8.984269) (xy 190.813944 -8.980932)
			(xy 190.854048 -8.965083) (xy 190.936665 -8.940356) (xy 191.021287 -8.923743) (xy 191.107121 -8.915399)
			(xy 191.15024 -8.914892) (xy 191.192587 -8.915397) (xy 191.276898 -8.923452) (xy 191.360061 -8.939484)
			(xy 191.441324 -8.963348) (xy 191.519951 -8.994828) (xy 191.595229 -9.03364) (xy 191.666478 -9.079431)
			(xy 191.733051 -9.131788) (xy 191.794346 -9.190235) (xy 191.849808 -9.254244) (xy 191.898934 -9.323235)
			(xy 191.94128 -9.396583) (xy 191.976463 -9.473625) (xy 192.004163 -9.553661) (xy 192.02413 -9.635969)
			(xy 192.036183 -9.719801) (xy 192.040213 -9.8044) (xy 192.036183 -9.888999) (xy 192.02413 -9.972831)
			(xy 192.004163 -10.055139) (xy 191.976463 -10.135175) (xy 191.94128 -10.212217) (xy 191.898934 -10.285565)
			(xy 191.849808 -10.354556) (xy 191.794346 -10.418565) (xy 191.733051 -10.477012) (xy 191.666478 -10.529369)
			(xy 191.595229 -10.57516) (xy 191.519951 -10.613972) (xy 191.441324 -10.645452) (xy 191.360061 -10.669316)
			(xy 191.276898 -10.685348) (xy 191.192587 -10.693403) (xy 191.15024 -10.693908) (xy 191.107122 -10.693391)
			(xy 191.021289 -10.685046) (xy 190.936668 -10.668431) (xy 190.854053 -10.643702) (xy 190.813944 -10.627868)
			(xy 190.804575 -10.624531) (xy 190.784705 -10.624531) (xy 190.775336 -10.627868) (xy 190.735223 -10.643692)
			(xy 190.652609 -10.668425) (xy 190.56799 -10.685046) (xy 190.482158 -10.693397) (xy 190.43904 -10.693908)
			(xy 190.394823 -10.693366) (xy 190.306823 -10.684614) (xy 190.220127 -10.667163) (xy 190.135595 -10.641185)
			(xy 190.094616 -10.624566) (xy 190.086044 -10.621444) (xy 190.067826 -10.620785) (xy 190.059056 -10.623296)
			(xy 190.013723 -10.637678) (xy 189.920769 -10.65782) (xy 189.826196 -10.667918) (xy 189.77864 -10.668508)
			(xy 189.73629 -10.668022) (xy 189.651972 -10.659974) (xy 189.568801 -10.643948) (xy 189.48753 -10.620088)
			(xy 189.408895 -10.58861) (xy 189.333609 -10.5498) (xy 189.262353 -10.504009) (xy 189.195772 -10.451653)
			(xy 189.13447 -10.393204) (xy 189.079001 -10.329192) (xy 189.029869 -10.260198) (xy 188.987517 -10.186845)
			(xy 188.95233 -10.109799) (xy 188.924626 -10.029757) (xy 188.904657 -9.947444) (xy 188.892602 -9.863605)
			(xy 188.888572 -9.779) (xy 175.563029 -9.779) (xy 175.581416 -9.799521) (xy 175.612189 -9.846034)
			(xy 175.635861 -9.896531) (xy 175.651929 -9.949938) (xy 175.660049 -10.005114) (xy 175.660558 -10.033)
			(xy 175.660049 -10.060886) (xy 175.651929 -10.116062) (xy 175.635861 -10.169469) (xy 175.612189 -10.219966)
			(xy 175.581416 -10.266479) (xy 175.544199 -10.308016) (xy 175.501331 -10.343691) (xy 175.453725 -10.372745)
			(xy 175.402396 -10.394557) (xy 175.348439 -10.408663) (xy 175.299936 -10.414) (xy 178.367942 -10.414)
			(xy 178.372013 -10.358378) (xy 178.384139 -10.303941) (xy 178.404062 -10.25185) (xy 178.431358 -10.203215)
			(xy 178.465444 -10.159072) (xy 178.505593 -10.120363) (xy 178.550951 -10.087912) (xy 178.600551 -10.062411)
			(xy 178.653335 -10.044404) (xy 178.708178 -10.034274) (xy 178.763912 -10.032237) (xy 178.819349 -10.038337)
			(xy 178.873306 -10.052443) (xy 178.924635 -10.074255) (xy 178.972241 -10.103309) (xy 179.015109 -10.138984)
			(xy 179.052326 -10.180521) (xy 179.083099 -10.227034) (xy 179.106771 -10.277531) (xy 179.122839 -10.330938)
			(xy 179.130959 -10.386114) (xy 179.131468 -10.414) (xy 179.130959 -10.441886) (xy 179.122839 -10.497062)
			(xy 179.106771 -10.550469) (xy 179.083099 -10.600966) (xy 179.052326 -10.647479) (xy 179.015109 -10.689016)
			(xy 178.972241 -10.724691) (xy 178.924635 -10.753745) (xy 178.873306 -10.775557) (xy 178.819349 -10.789663)
			(xy 178.763912 -10.795763) (xy 178.708178 -10.793726) (xy 178.653335 -10.783596) (xy 178.600551 -10.765589)
			(xy 178.550951 -10.740088) (xy 178.505593 -10.707637) (xy 178.465444 -10.668928) (xy 178.431358 -10.624785)
			(xy 178.404062 -10.57615) (xy 178.384139 -10.524059) (xy 178.372013 -10.469622) (xy 178.367942 -10.414)
			(xy 175.299936 -10.414) (xy 175.293002 -10.414763) (xy 175.237268 -10.412726) (xy 175.182425 -10.402596)
			(xy 175.129641 -10.384589) (xy 175.080041 -10.359088) (xy 175.034683 -10.326637) (xy 174.994534 -10.287928)
			(xy 174.960448 -10.243785) (xy 174.933152 -10.19515) (xy 174.913229 -10.143059) (xy 174.901103 -10.088622)
			(xy 174.897032 -10.033) (xy 165.3032 -10.033) (xy 165.3032 -11.938) (xy 188.888572 -11.938) (xy 188.892602 -11.853395)
			(xy 188.904657 -11.769556) (xy 188.924626 -11.687243) (xy 188.95233 -11.607201) (xy 188.987517 -11.530155)
			(xy 189.029869 -11.456802) (xy 189.079001 -11.387808) (xy 189.13447 -11.323796) (xy 189.195772 -11.265347)
			(xy 189.262353 -11.212991) (xy 189.333609 -11.1672) (xy 189.408895 -11.12839) (xy 189.48753 -11.096912)
			(xy 189.568801 -11.073052) (xy 189.651972 -11.057026) (xy 189.73629 -11.048978) (xy 189.77864 -11.048492)
			(xy 189.822857 -11.04904) (xy 189.910857 -11.05779) (xy 189.997552 -11.07524) (xy 190.082085 -11.101216)
			(xy 190.123064 -11.117834) (xy 190.131639 -11.120946) (xy 190.149854 -11.121612) (xy 190.158624 -11.119104)
			(xy 190.203958 -11.104727) (xy 190.296912 -11.084584) (xy 190.391484 -11.074483) (xy 190.43904 -11.073892)
			(xy 190.482158 -11.074416) (xy 190.56799 -11.082759) (xy 190.652611 -11.099372) (xy 190.735227 -11.124099)
			(xy 190.775336 -11.139932) (xy 190.784705 -11.143269) (xy 190.804575 -11.143269) (xy 190.813944 -11.139932)
			(xy 190.854048 -11.124083) (xy 190.936665 -11.099356) (xy 191.021287 -11.082743) (xy 191.107121 -11.074399)
			(xy 191.15024 -11.073892) (xy 191.192587 -11.074397) (xy 191.276898 -11.082452) (xy 191.360061 -11.098484)
			(xy 191.441324 -11.122348) (xy 191.519951 -11.153828) (xy 191.595229 -11.19264) (xy 191.666478 -11.238431)
			(xy 191.733051 -11.290788) (xy 191.794346 -11.349235) (xy 191.849808 -11.413244) (xy 191.898934 -11.482235)
			(xy 191.94128 -11.555583) (xy 191.976463 -11.632625) (xy 192.004163 -11.712661) (xy 192.02413 -11.794969)
			(xy 192.036183 -11.878801) (xy 192.040213 -11.9634) (xy 192.036183 -12.047999) (xy 192.02413 -12.131831)
			(xy 192.004163 -12.214139) (xy 191.976463 -12.294175) (xy 191.94128 -12.371217) (xy 191.898934 -12.444565)
			(xy 191.849808 -12.513556) (xy 191.794346 -12.577565) (xy 191.733051 -12.636012) (xy 191.666478 -12.688369)
			(xy 191.595229 -12.73416) (xy 191.519951 -12.772972) (xy 191.441324 -12.804452) (xy 191.360061 -12.828316)
			(xy 191.276898 -12.844348) (xy 191.192587 -12.852403) (xy 191.15024 -12.852908) (xy 191.107122 -12.852391)
			(xy 191.021289 -12.844046) (xy 190.936668 -12.827431) (xy 190.854053 -12.802702) (xy 190.813944 -12.786868)
			(xy 190.804575 -12.783531) (xy 190.784705 -12.783531) (xy 190.775336 -12.786868) (xy 190.735223 -12.802692)
			(xy 190.652609 -12.827425) (xy 190.56799 -12.844046) (xy 190.482158 -12.852397) (xy 190.43904 -12.852908)
			(xy 190.394823 -12.852366) (xy 190.306823 -12.843614) (xy 190.220127 -12.826163) (xy 190.135595 -12.800185)
			(xy 190.094616 -12.783566) (xy 190.086044 -12.780444) (xy 190.067826 -12.779785) (xy 190.059056 -12.782296)
			(xy 190.013723 -12.796678) (xy 189.920769 -12.81682) (xy 189.826196 -12.826918) (xy 189.77864 -12.827508)
			(xy 189.73629 -12.827022) (xy 189.651972 -12.818974) (xy 189.568801 -12.802948) (xy 189.48753 -12.779088)
			(xy 189.408895 -12.74761) (xy 189.333609 -12.7088) (xy 189.262353 -12.663009) (xy 189.195772 -12.610653)
			(xy 189.13447 -12.552204) (xy 189.079001 -12.488192) (xy 189.029869 -12.419198) (xy 188.987517 -12.345845)
			(xy 188.95233 -12.268799) (xy 188.924626 -12.188757) (xy 188.904657 -12.106444) (xy 188.892602 -12.022605)
			(xy 188.888572 -11.938) (xy 165.3032 -11.938) (xy 165.3032 -13.745972) (xy 178.367942 -13.745972)
			(xy 178.372013 -13.69035) (xy 178.384139 -13.635913) (xy 178.404062 -13.583822) (xy 178.431358 -13.535187)
			(xy 178.465444 -13.491044) (xy 178.505593 -13.452335) (xy 178.550951 -13.419884) (xy 178.600551 -13.394383)
			(xy 178.653335 -13.376376) (xy 178.708178 -13.366246) (xy 178.763912 -13.364209) (xy 178.819349 -13.370309)
			(xy 178.873306 -13.384415) (xy 178.924635 -13.406227) (xy 178.972241 -13.435281) (xy 179.015109 -13.470956)
			(xy 179.052326 -13.512493) (xy 179.083099 -13.559006) (xy 179.106771 -13.609503) (xy 179.122839 -13.66291)
			(xy 179.130959 -13.718086) (xy 179.131468 -13.745972) (xy 179.130959 -13.773858) (xy 179.122839 -13.829034)
			(xy 179.106771 -13.882441) (xy 179.083099 -13.932938) (xy 179.052326 -13.979451) (xy 179.015109 -14.020988)
			(xy 178.972241 -14.056663) (xy 178.924635 -14.085717) (xy 178.898083 -14.097) (xy 188.888572 -14.097)
			(xy 188.892602 -14.012395) (xy 188.904657 -13.928556) (xy 188.924626 -13.846243) (xy 188.95233 -13.766201)
			(xy 188.987517 -13.689155) (xy 189.029869 -13.615802) (xy 189.079001 -13.546808) (xy 189.13447 -13.482796)
			(xy 189.195772 -13.424347) (xy 189.262353 -13.371991) (xy 189.333609 -13.3262) (xy 189.408895 -13.28739)
			(xy 189.48753 -13.255912) (xy 189.568801 -13.232052) (xy 189.651972 -13.216026) (xy 189.73629 -13.207978)
			(xy 189.77864 -13.207492) (xy 189.822857 -13.20804) (xy 189.910857 -13.21679) (xy 189.997552 -13.23424)
			(xy 190.082085 -13.260216) (xy 190.123064 -13.276834) (xy 190.131639 -13.279946) (xy 190.149854 -13.280612)
			(xy 190.158624 -13.278104) (xy 190.203958 -13.263727) (xy 190.296912 -13.243584) (xy 190.391484 -13.233483)
			(xy 190.43904 -13.232892) (xy 190.482158 -13.233416) (xy 190.56799 -13.241759) (xy 190.652611 -13.258372)
			(xy 190.735227 -13.283099) (xy 190.775336 -13.298932) (xy 190.784705 -13.302269) (xy 190.804575 -13.302269)
			(xy 190.813944 -13.298932) (xy 190.854048 -13.283083) (xy 190.936665 -13.258356) (xy 191.021287 -13.241743)
			(xy 191.107121 -13.233399) (xy 191.15024 -13.232892) (xy 191.192587 -13.233397) (xy 191.276898 -13.241452)
			(xy 191.360061 -13.257484) (xy 191.441324 -13.281348) (xy 191.519951 -13.312828) (xy 191.595229 -13.35164)
			(xy 191.666478 -13.397431) (xy 191.733051 -13.449788) (xy 191.794346 -13.508235) (xy 191.849808 -13.572244)
			(xy 191.898934 -13.641235) (xy 191.94128 -13.714583) (xy 191.976463 -13.791625) (xy 192.004163 -13.871661)
			(xy 192.02413 -13.953969) (xy 192.036183 -14.037801) (xy 192.040213 -14.1224) (xy 192.036183 -14.206999)
			(xy 192.02413 -14.290831) (xy 192.004163 -14.373139) (xy 191.976463 -14.453175) (xy 191.94128 -14.530217)
			(xy 191.898934 -14.603565) (xy 191.849808 -14.672556) (xy 191.794346 -14.736565) (xy 191.733051 -14.795012)
			(xy 191.666478 -14.847369) (xy 191.595229 -14.89316) (xy 191.519951 -14.931972) (xy 191.441324 -14.963452)
			(xy 191.360061 -14.987316) (xy 191.276898 -15.003348) (xy 191.192587 -15.011403) (xy 191.15024 -15.011908)
			(xy 191.107122 -15.011391) (xy 191.021289 -15.003046) (xy 190.936668 -14.986431) (xy 190.854053 -14.961702)
			(xy 190.813944 -14.945868) (xy 190.804575 -14.942531) (xy 190.784705 -14.942531) (xy 190.775336 -14.945868)
			(xy 190.735223 -14.961692) (xy 190.652609 -14.986425) (xy 190.56799 -15.003046) (xy 190.482158 -15.011397)
			(xy 190.43904 -15.011908) (xy 190.394823 -15.011366) (xy 190.306823 -15.002614) (xy 190.220127 -14.985163)
			(xy 190.135595 -14.959185) (xy 190.094616 -14.942566) (xy 190.086044 -14.939444) (xy 190.067826 -14.938785)
			(xy 190.059056 -14.941296) (xy 190.013723 -14.955678) (xy 189.920769 -14.97582) (xy 189.826196 -14.985918)
			(xy 189.77864 -14.986508) (xy 189.73629 -14.986022) (xy 189.651972 -14.977974) (xy 189.568801 -14.961948)
			(xy 189.48753 -14.938088) (xy 189.408895 -14.90661) (xy 189.333609 -14.8678) (xy 189.262353 -14.822009)
			(xy 189.195772 -14.769653) (xy 189.13447 -14.711204) (xy 189.079001 -14.647192) (xy 189.029869 -14.578198)
			(xy 188.987517 -14.504845) (xy 188.95233 -14.427799) (xy 188.924626 -14.347757) (xy 188.904657 -14.265444)
			(xy 188.892602 -14.181605) (xy 188.888572 -14.097) (xy 178.898083 -14.097) (xy 178.873306 -14.107529)
			(xy 178.819349 -14.121635) (xy 178.763912 -14.127735) (xy 178.708178 -14.125698) (xy 178.653335 -14.115568)
			(xy 178.600551 -14.097561) (xy 178.550951 -14.07206) (xy 178.505593 -14.039609) (xy 178.465444 -14.0009)
			(xy 178.431358 -13.956757) (xy 178.404062 -13.908122) (xy 178.384139 -13.856031) (xy 178.372013 -13.801594)
			(xy 178.367942 -13.745972) (xy 165.3032 -13.745972) (xy 165.3032 -16.256) (xy 188.888572 -16.256)
			(xy 188.892602 -16.171395) (xy 188.904657 -16.087556) (xy 188.924626 -16.005243) (xy 188.95233 -15.925201)
			(xy 188.987517 -15.848155) (xy 189.029869 -15.774802) (xy 189.079001 -15.705808) (xy 189.13447 -15.641796)
			(xy 189.195772 -15.583347) (xy 189.262353 -15.530991) (xy 189.333609 -15.4852) (xy 189.408895 -15.44639)
			(xy 189.48753 -15.414912) (xy 189.568801 -15.391052) (xy 189.651972 -15.375026) (xy 189.73629 -15.366978)
			(xy 189.77864 -15.366492) (xy 189.822857 -15.36704) (xy 189.910857 -15.37579) (xy 189.997552 -15.39324)
			(xy 190.082085 -15.419216) (xy 190.123064 -15.435834) (xy 190.131639 -15.438946) (xy 190.149854 -15.439612)
			(xy 190.158624 -15.437104) (xy 190.203958 -15.422727) (xy 190.296912 -15.402584) (xy 190.391484 -15.392483)
			(xy 190.43904 -15.391892) (xy 190.482158 -15.392416) (xy 190.56799 -15.400759) (xy 190.652611 -15.417372)
			(xy 190.735227 -15.442099) (xy 190.775336 -15.457932) (xy 190.784705 -15.461269) (xy 190.804575 -15.461269)
			(xy 190.813944 -15.457932) (xy 190.854048 -15.442083) (xy 190.936665 -15.417356) (xy 191.021287 -15.400743)
			(xy 191.107121 -15.392399) (xy 191.15024 -15.391892) (xy 191.192587 -15.392397) (xy 191.276898 -15.400452)
			(xy 191.360061 -15.416484) (xy 191.441324 -15.440348) (xy 191.519951 -15.471828) (xy 191.595229 -15.51064)
			(xy 191.666478 -15.556431) (xy 191.733051 -15.608788) (xy 191.794346 -15.667235) (xy 191.849808 -15.731244)
			(xy 191.898934 -15.800235) (xy 191.94128 -15.873583) (xy 191.976463 -15.950625) (xy 192.004163 -16.030661)
			(xy 192.02413 -16.112969) (xy 192.036183 -16.196801) (xy 192.040213 -16.2814) (xy 192.036183 -16.365999)
			(xy 192.02413 -16.449831) (xy 192.004163 -16.532139) (xy 191.976463 -16.612175) (xy 191.94128 -16.689217)
			(xy 191.898934 -16.762565) (xy 191.849808 -16.831556) (xy 191.794346 -16.895565) (xy 191.733051 -16.954012)
			(xy 191.666478 -17.006369) (xy 191.595229 -17.05216) (xy 191.519951 -17.090972) (xy 191.441324 -17.122452)
			(xy 191.360061 -17.146316) (xy 191.276898 -17.162348) (xy 191.192587 -17.170403) (xy 191.15024 -17.170908)
			(xy 191.107122 -17.170391) (xy 191.021289 -17.162046) (xy 190.936668 -17.145431) (xy 190.854053 -17.120702)
			(xy 190.813944 -17.104868) (xy 190.804575 -17.101531) (xy 190.784705 -17.101531) (xy 190.775336 -17.104868)
			(xy 190.735223 -17.120692) (xy 190.652609 -17.145425) (xy 190.56799 -17.162046) (xy 190.482158 -17.170397)
			(xy 190.43904 -17.170908) (xy 190.394823 -17.170366) (xy 190.306823 -17.161614) (xy 190.220127 -17.144163)
			(xy 190.135595 -17.118185) (xy 190.094616 -17.101566) (xy 190.086044 -17.098444) (xy 190.067826 -17.097785)
			(xy 190.059056 -17.100296) (xy 190.013723 -17.114678) (xy 189.920769 -17.13482) (xy 189.826196 -17.144918)
			(xy 189.77864 -17.145508) (xy 189.73629 -17.145022) (xy 189.651972 -17.136974) (xy 189.568801 -17.120948)
			(xy 189.48753 -17.097088) (xy 189.408895 -17.06561) (xy 189.333609 -17.0268) (xy 189.262353 -16.981009)
			(xy 189.195772 -16.928653) (xy 189.13447 -16.870204) (xy 189.079001 -16.806192) (xy 189.029869 -16.737198)
			(xy 188.987517 -16.663845) (xy 188.95233 -16.586799) (xy 188.924626 -16.506757) (xy 188.904657 -16.424444)
			(xy 188.892602 -16.340605) (xy 188.888572 -16.256) (xy 165.3032 -16.256) (xy 165.3032 -17.504918)
			(xy 165.303627 -17.514987) (xy 165.311346 -17.533586) (xy 165.318186 -17.540986) (xy 166.547038 -18.769838)
			(xy 166.554436 -18.776685) (xy 166.573034 -18.784416) (xy 166.583106 -18.784824) (xy 201.020934 -18.784824)
			(xy 201.031001 -18.785254) (xy 201.049594 -18.79298) (xy 201.057002 -18.79981) (xy 203.25454 -20.997348)
			(xy 276.478996 -20.997348) (xy 276.478996 -20.912652) (xy 276.487047 -20.828338) (xy 276.503076 -20.745172)
			(xy 276.526937 -20.663905) (xy 276.558416 -20.585275) (xy 276.597227 -20.509994) (xy 276.643017 -20.438742)
			(xy 276.695373 -20.372166) (xy 276.753821 -20.310868) (xy 276.817831 -20.255403) (xy 276.886823 -20.206274)
			(xy 276.960173 -20.163925) (xy 277.037216 -20.128741) (xy 277.117255 -20.101039) (xy 277.199564 -20.081071)
			(xy 277.283399 -20.069018) (xy 277.368 -20.064988) (xy 277.452601 -20.069018) (xy 277.536436 -20.081071)
			(xy 277.618745 -20.101039) (xy 277.698784 -20.128741) (xy 277.775827 -20.163925) (xy 277.849177 -20.206274)
			(xy 277.918169 -20.255403) (xy 277.982179 -20.310868) (xy 278.040627 -20.372166) (xy 278.092983 -20.438742)
			(xy 278.138773 -20.509994) (xy 278.177584 -20.585275) (xy 278.209063 -20.663905) (xy 278.232924 -20.745172)
			(xy 278.248953 -20.828338) (xy 278.257004 -20.912652) (xy 278.257508 -20.955) (xy 278.257004 -20.997348)
			(xy 278.248953 -21.081662) (xy 278.232924 -21.164828) (xy 278.209063 -21.246095) (xy 278.177584 -21.324725)
			(xy 278.138773 -21.400006) (xy 278.092983 -21.471258) (xy 278.040627 -21.537834) (xy 277.982179 -21.599132)
			(xy 277.918169 -21.654597) (xy 277.849177 -21.703726) (xy 277.775827 -21.746075) (xy 277.698784 -21.781259)
			(xy 277.618745 -21.808961) (xy 277.536436 -21.828929) (xy 277.452601 -21.840982) (xy 277.368 -21.845013)
			(xy 277.283399 -21.840982) (xy 277.199564 -21.828929) (xy 277.117255 -21.808961) (xy 277.037216 -21.781259)
			(xy 276.960173 -21.746075) (xy 276.886823 -21.703726) (xy 276.817831 -21.654597) (xy 276.753821 -21.599132)
			(xy 276.695373 -21.537834) (xy 276.643017 -21.471258) (xy 276.597227 -21.400006) (xy 276.558416 -21.324725)
			(xy 276.526937 -21.246095) (xy 276.503076 -21.164828) (xy 276.487047 -21.081662) (xy 276.478996 -20.997348)
			(xy 203.25454 -20.997348) (xy 203.820014 -21.562822) (xy 203.826866 -21.570218) (xy 203.834606 -21.588817)
			(xy 203.835 -21.59889) (xy 203.835 -23.0886) (xy 271.702788 -23.0886) (xy 271.706818 -23.003999)
			(xy 271.718871 -22.920164) (xy 271.738839 -22.837855) (xy 271.766541 -22.757816) (xy 271.801725 -22.680773)
			(xy 271.844074 -22.607423) (xy 271.893203 -22.538431) (xy 271.948668 -22.474421) (xy 272.009966 -22.415973)
			(xy 272.076542 -22.363617) (xy 272.147794 -22.317827) (xy 272.223075 -22.279016) (xy 272.301705 -22.247537)
			(xy 272.382972 -22.223676) (xy 272.466138 -22.207647) (xy 272.550452 -22.199596) (xy 272.5928 -22.199092)
			(xy 272.635115 -22.199595) (xy 272.719363 -22.207626) (xy 272.802466 -22.223624) (xy 272.883675 -22.247445)
			(xy 272.962252 -22.278872) (xy 273.037489 -22.317623) (xy 273.073368 -22.340062) (xy 273.081757 -22.344945)
			(xy 273.1008 -22.348616) (xy 273.119843 -22.344945) (xy 273.128232 -22.340062) (xy 273.164106 -22.317616)
			(xy 273.239347 -22.278873) (xy 273.317926 -22.247449) (xy 273.399135 -22.22363) (xy 273.482238 -22.20763)
			(xy 273.566485 -22.199594) (xy 273.6088 -22.199092) (xy 273.651148 -22.199596) (xy 273.735462 -22.207647)
			(xy 273.818628 -22.223676) (xy 273.899895 -22.247537) (xy 273.978525 -22.279016) (xy 274.053806 -22.317827)
			(xy 274.125058 -22.363617) (xy 274.191634 -22.415973) (xy 274.252932 -22.474421) (xy 274.308397 -22.538431)
			(xy 274.357526 -22.607423) (xy 274.399875 -22.680773) (xy 274.435059 -22.757816) (xy 274.462761 -22.837855)
			(xy 274.482729 -22.920164) (xy 274.488686 -22.9616) (xy 291.387791 -22.9616) (xy 291.391794 -22.873738)
			(xy 291.40377 -22.786604) (xy 291.423621 -22.70092) (xy 291.45118 -22.617396) (xy 291.486221 -22.536724)
			(xy 291.528452 -22.459573) (xy 291.577524 -22.386582) (xy 291.633031 -22.318356) (xy 291.694511 -22.25546)
			(xy 291.761456 -22.198415) (xy 291.833311 -22.147694) (xy 291.909481 -22.103717) (xy 291.989334 -22.066849)
			(xy 292.072209 -22.037396) (xy 292.157419 -22.0156) (xy 292.244258 -22.001644) (xy 292.332006 -21.995641)
			(xy 292.419936 -21.997643) (xy 292.507321 -22.007633) (xy 292.593434 -22.025528) (xy 292.677564 -22.051179)
			(xy 292.759012 -22.084374) (xy 292.837105 -22.124838) (xy 292.911194 -22.172236) (xy 292.980666 -22.226175)
			(xy 293.044945 -22.286208) (xy 293.103499 -22.351837) (xy 293.155843 -22.422519) (xy 293.201542 -22.497668)
			(xy 293.240218 -22.576661) (xy 293.27155 -22.658844) (xy 293.29528 -22.743536) (xy 293.31121 -22.830035)
			(xy 293.319208 -22.917623) (xy 293.319708 -22.9616) (xy 293.319208 -23.005577) (xy 293.31121 -23.093165)
			(xy 293.29528 -23.179664) (xy 293.27155 -23.264356) (xy 293.240218 -23.346539) (xy 293.201542 -23.425532)
			(xy 293.155843 -23.500681) (xy 293.103499 -23.571363) (xy 293.044945 -23.636992) (xy 292.980666 -23.697025)
			(xy 292.911194 -23.750964) (xy 292.837105 -23.798362) (xy 292.759012 -23.838826) (xy 292.677564 -23.872021)
			(xy 292.593434 -23.897672) (xy 292.507321 -23.915567) (xy 292.419936 -23.925557) (xy 292.332006 -23.927559)
			(xy 292.244258 -23.921556) (xy 292.157419 -23.9076) (xy 292.072209 -23.885804) (xy 291.989334 -23.856351)
			(xy 291.909481 -23.819483) (xy 291.833311 -23.775506) (xy 291.761456 -23.724785) (xy 291.694511 -23.66774)
			(xy 291.633031 -23.604844) (xy 291.577524 -23.536618) (xy 291.528452 -23.463627) (xy 291.486221 -23.386476)
			(xy 291.45118 -23.305804) (xy 291.423621 -23.22228) (xy 291.40377 -23.136596) (xy 291.391794 -23.049462)
			(xy 291.387791 -22.9616) (xy 274.488686 -22.9616) (xy 274.494782 -23.003999) (xy 274.498813 -23.0886)
			(xy 274.494782 -23.173201) (xy 274.482729 -23.257036) (xy 274.462761 -23.339345) (xy 274.435059 -23.419384)
			(xy 274.399875 -23.496427) (xy 274.357526 -23.569777) (xy 274.308397 -23.638769) (xy 274.252932 -23.702779)
			(xy 274.191634 -23.761227) (xy 274.125058 -23.813583) (xy 274.053806 -23.859373) (xy 273.978525 -23.898184)
			(xy 273.899895 -23.929663) (xy 273.818628 -23.953524) (xy 273.735462 -23.969553) (xy 273.651148 -23.977604)
			(xy 273.6088 -23.978108) (xy 273.566485 -23.977605) (xy 273.482237 -23.969574) (xy 273.399134 -23.953576)
			(xy 273.317925 -23.929755) (xy 273.239348 -23.898328) (xy 273.164111 -23.859577) (xy 273.128232 -23.837138)
			(xy 273.119843 -23.832255) (xy 273.1008 -23.828584) (xy 273.081757 -23.832255) (xy 273.073368 -23.837138)
			(xy 273.037494 -23.859584) (xy 272.962253 -23.898327) (xy 272.883674 -23.929751) (xy 272.802465 -23.95357)
			(xy 272.719362 -23.96957) (xy 272.635115 -23.977606) (xy 272.5928 -23.978108) (xy 272.550452 -23.977604)
			(xy 272.466138 -23.969553) (xy 272.382972 -23.953524) (xy 272.301705 -23.929663) (xy 272.223075 -23.898184)
			(xy 272.147794 -23.859373) (xy 272.076542 -23.813583) (xy 272.009966 -23.761227) (xy 271.948668 -23.702779)
			(xy 271.893203 -23.638769) (xy 271.844074 -23.569777) (xy 271.801725 -23.496427) (xy 271.766541 -23.419384)
			(xy 271.738839 -23.339345) (xy 271.718871 -23.257036) (xy 271.706818 -23.173201) (xy 271.702788 -23.0886)
			(xy 203.835 -23.0886) (xy 203.835 -24.892) (xy 255.827791 -24.892) (xy 255.831794 -24.804138) (xy 255.84377 -24.717004)
			(xy 255.863621 -24.63132) (xy 255.89118 -24.547796) (xy 255.926221 -24.467124) (xy 255.968452 -24.389973)
			(xy 256.017524 -24.316982) (xy 256.073031 -24.248756) (xy 256.134511 -24.18586) (xy 256.201456 -24.128815)
			(xy 256.273311 -24.078094) (xy 256.349481 -24.034117) (xy 256.429334 -23.997249) (xy 256.512209 -23.967796)
			(xy 256.597419 -23.946) (xy 256.684258 -23.932044) (xy 256.772006 -23.926041) (xy 256.859936 -23.928043)
			(xy 256.947321 -23.938033) (xy 257.033434 -23.955928) (xy 257.117564 -23.981579) (xy 257.199012 -24.014774)
			(xy 257.277105 -24.055238) (xy 257.351194 -24.102636) (xy 257.420666 -24.156575) (xy 257.484945 -24.216608)
			(xy 257.543499 -24.282237) (xy 257.595843 -24.352919) (xy 257.641542 -24.428068) (xy 257.680218 -24.507061)
			(xy 257.71155 -24.589244) (xy 257.73528 -24.673936) (xy 257.75121 -24.760435) (xy 257.759208 -24.848023)
			(xy 257.759708 -24.892) (xy 257.759208 -24.935977) (xy 257.75121 -25.023565) (xy 257.73528 -25.110064)
			(xy 257.71155 -25.194756) (xy 257.680218 -25.276939) (xy 257.641542 -25.355932) (xy 257.595843 -25.431081)
			(xy 257.543499 -25.501763) (xy 257.484945 -25.567392) (xy 257.420666 -25.627425) (xy 257.351194 -25.681364)
			(xy 257.277105 -25.728762) (xy 257.199012 -25.769226) (xy 257.117564 -25.802421) (xy 257.033434 -25.828072)
			(xy 256.947321 -25.845967) (xy 256.859936 -25.855957) (xy 256.772006 -25.857959) (xy 256.684258 -25.851956)
			(xy 256.597419 -25.838) (xy 256.512209 -25.816204) (xy 256.429334 -25.786751) (xy 256.349481 -25.749883)
			(xy 256.273311 -25.705906) (xy 256.201456 -25.655185) (xy 256.134511 -25.59814) (xy 256.073031 -25.535244)
			(xy 256.017524 -25.467018) (xy 255.968452 -25.394027) (xy 255.926221 -25.316876) (xy 255.89118 -25.236204)
			(xy 255.863621 -25.15268) (xy 255.84377 -25.066996) (xy 255.831794 -24.979862) (xy 255.827791 -24.892)
			(xy 203.835 -24.892) (xy 203.835 -30.372065) (xy 205.499205 -30.372065) (xy 205.499205 -30.287199)
			(xy 205.507272 -30.202717) (xy 205.523333 -30.119384) (xy 205.547242 -30.037956) (xy 205.578784 -29.959168)
			(xy 205.617672 -29.883736) (xy 205.663554 -29.812342) (xy 205.716015 -29.745633) (xy 205.774579 -29.684212)
			(xy 205.838717 -29.628637) (xy 205.907847 -29.579409) (xy 205.981343 -29.536976) (xy 206.058541 -29.501721)
			(xy 206.138739 -29.473964) (xy 206.221213 -29.453956) (xy 206.305216 -29.441879) (xy 206.389986 -29.437841)
			(xy 206.474756 -29.441879) (xy 206.558759 -29.453956) (xy 206.641233 -29.473964) (xy 206.721431 -29.501721)
			(xy 206.798629 -29.536976) (xy 206.872125 -29.579409) (xy 206.941255 -29.628637) (xy 207.005393 -29.684212)
			(xy 207.063957 -29.745633) (xy 207.116418 -29.812342) (xy 207.1623 -29.883736) (xy 207.201188 -29.959168)
			(xy 207.23273 -30.037956) (xy 207.256639 -30.119384) (xy 207.2727 -30.202717) (xy 207.280767 -30.287199)
			(xy 207.281272 -30.329632) (xy 207.280767 -30.372065) (xy 208.039205 -30.372065) (xy 208.039205 -30.287199)
			(xy 208.047272 -30.202717) (xy 208.063333 -30.119384) (xy 208.087242 -30.037956) (xy 208.118784 -29.959168)
			(xy 208.157672 -29.883736) (xy 208.203554 -29.812342) (xy 208.256015 -29.745633) (xy 208.314579 -29.684212)
			(xy 208.378717 -29.628637) (xy 208.447847 -29.579409) (xy 208.521343 -29.536976) (xy 208.598541 -29.501721)
			(xy 208.678739 -29.473964) (xy 208.761213 -29.453956) (xy 208.845216 -29.441879) (xy 208.929986 -29.437841)
			(xy 209.014756 -29.441879) (xy 209.098759 -29.453956) (xy 209.181233 -29.473964) (xy 209.261431 -29.501721)
			(xy 209.338629 -29.536976) (xy 209.412125 -29.579409) (xy 209.481255 -29.628637) (xy 209.545393 -29.684212)
			(xy 209.603957 -29.745633) (xy 209.656418 -29.812342) (xy 209.7023 -29.883736) (xy 209.741188 -29.959168)
			(xy 209.77273 -30.037956) (xy 209.796639 -30.119384) (xy 209.8127 -30.202717) (xy 209.820767 -30.287199)
			(xy 209.821272 -30.329632) (xy 209.820767 -30.372065) (xy 210.579205 -30.372065) (xy 210.579205 -30.287199)
			(xy 210.587272 -30.202717) (xy 210.603333 -30.119384) (xy 210.627242 -30.037956) (xy 210.658784 -29.959168)
			(xy 210.697672 -29.883736) (xy 210.743554 -29.812342) (xy 210.796015 -29.745633) (xy 210.854579 -29.684212)
			(xy 210.918717 -29.628637) (xy 210.987847 -29.579409) (xy 211.061343 -29.536976) (xy 211.138541 -29.501721)
			(xy 211.218739 -29.473964) (xy 211.301213 -29.453956) (xy 211.385216 -29.441879) (xy 211.469986 -29.437841)
			(xy 211.554756 -29.441879) (xy 211.638759 -29.453956) (xy 211.721233 -29.473964) (xy 211.801431 -29.501721)
			(xy 211.878629 -29.536976) (xy 211.952125 -29.579409) (xy 212.021255 -29.628637) (xy 212.085393 -29.684212)
			(xy 212.143957 -29.745633) (xy 212.196418 -29.812342) (xy 212.2423 -29.883736) (xy 212.281188 -29.959168)
			(xy 212.31273 -30.037956) (xy 212.336639 -30.119384) (xy 212.3527 -30.202717) (xy 212.360767 -30.287199)
			(xy 212.361272 -30.329632) (xy 212.360767 -30.372065) (xy 212.3527 -30.456547) (xy 212.336639 -30.53988)
			(xy 212.31273 -30.621308) (xy 212.281188 -30.700096) (xy 212.2423 -30.775528) (xy 212.196418 -30.846922)
			(xy 212.143957 -30.913631) (xy 212.085393 -30.975052) (xy 212.021255 -31.030627) (xy 211.952125 -31.079855)
			(xy 211.878629 -31.122288) (xy 211.801431 -31.157543) (xy 211.721233 -31.1853) (xy 211.638759 -31.205308)
			(xy 211.554756 -31.217385) (xy 211.469986 -31.221424) (xy 211.385216 -31.217385) (xy 211.301213 -31.205308)
			(xy 211.218739 -31.1853) (xy 211.138541 -31.157543) (xy 211.061343 -31.122288) (xy 210.987847 -31.079855)
			(xy 210.918717 -31.030627) (xy 210.854579 -30.975052) (xy 210.796015 -30.913631) (xy 210.743554 -30.846922)
			(xy 210.697672 -30.775528) (xy 210.658784 -30.700096) (xy 210.627242 -30.621308) (xy 210.603333 -30.53988)
			(xy 210.587272 -30.456547) (xy 210.579205 -30.372065) (xy 209.820767 -30.372065) (xy 209.8127 -30.456547)
			(xy 209.796639 -30.53988) (xy 209.77273 -30.621308) (xy 209.741188 -30.700096) (xy 209.7023 -30.775528)
			(xy 209.656418 -30.846922) (xy 209.603957 -30.913631) (xy 209.545393 -30.975052) (xy 209.481255 -31.030627)
			(xy 209.412125 -31.079855) (xy 209.338629 -31.122288) (xy 209.261431 -31.157543) (xy 209.181233 -31.1853)
			(xy 209.098759 -31.205308) (xy 209.014756 -31.217385) (xy 208.929986 -31.221424) (xy 208.845216 -31.217385)
			(xy 208.761213 -31.205308) (xy 208.678739 -31.1853) (xy 208.598541 -31.157543) (xy 208.521343 -31.122288)
			(xy 208.447847 -31.079855) (xy 208.378717 -31.030627) (xy 208.314579 -30.975052) (xy 208.256015 -30.913631)
			(xy 208.203554 -30.846922) (xy 208.157672 -30.775528) (xy 208.118784 -30.700096) (xy 208.087242 -30.621308)
			(xy 208.063333 -30.53988) (xy 208.047272 -30.456547) (xy 208.039205 -30.372065) (xy 207.280767 -30.372065)
			(xy 207.2727 -30.456547) (xy 207.256639 -30.53988) (xy 207.23273 -30.621308) (xy 207.201188 -30.700096)
			(xy 207.1623 -30.775528) (xy 207.116418 -30.846922) (xy 207.063957 -30.913631) (xy 207.005393 -30.975052)
			(xy 206.941255 -31.030627) (xy 206.872125 -31.079855) (xy 206.798629 -31.122288) (xy 206.721431 -31.157543)
			(xy 206.641233 -31.1853) (xy 206.558759 -31.205308) (xy 206.474756 -31.217385) (xy 206.389986 -31.221424)
			(xy 206.305216 -31.217385) (xy 206.221213 -31.205308) (xy 206.138739 -31.1853) (xy 206.058541 -31.157543)
			(xy 205.981343 -31.122288) (xy 205.907847 -31.079855) (xy 205.838717 -31.030627) (xy 205.774579 -30.975052)
			(xy 205.716015 -30.913631) (xy 205.663554 -30.846922) (xy 205.617672 -30.775528) (xy 205.578784 -30.700096)
			(xy 205.547242 -30.621308) (xy 205.523333 -30.53988) (xy 205.507272 -30.456547) (xy 205.499205 -30.372065)
			(xy 203.835 -30.372065) (xy 203.835 -32.912065) (xy 205.499205 -32.912065) (xy 205.499205 -32.827199)
			(xy 205.507272 -32.742717) (xy 205.523333 -32.659384) (xy 205.547242 -32.577956) (xy 205.578784 -32.499168)
			(xy 205.617672 -32.423736) (xy 205.663554 -32.352342) (xy 205.716015 -32.285633) (xy 205.774579 -32.224212)
			(xy 205.838717 -32.168637) (xy 205.907847 -32.119409) (xy 205.981343 -32.076976) (xy 206.058541 -32.041721)
			(xy 206.138739 -32.013964) (xy 206.221213 -31.993956) (xy 206.305216 -31.981879) (xy 206.389986 -31.977841)
			(xy 206.474756 -31.981879) (xy 206.558759 -31.993956) (xy 206.641233 -32.013964) (xy 206.721431 -32.041721)
			(xy 206.798629 -32.076976) (xy 206.872125 -32.119409) (xy 206.941255 -32.168637) (xy 207.005393 -32.224212)
			(xy 207.063957 -32.285633) (xy 207.116418 -32.352342) (xy 207.1623 -32.423736) (xy 207.201188 -32.499168)
			(xy 207.23273 -32.577956) (xy 207.256639 -32.659384) (xy 207.2727 -32.742717) (xy 207.280767 -32.827199)
			(xy 207.281272 -32.869632) (xy 207.280767 -32.912065) (xy 208.039205 -32.912065) (xy 208.039205 -32.827199)
			(xy 208.047272 -32.742717) (xy 208.063333 -32.659384) (xy 208.087242 -32.577956) (xy 208.118784 -32.499168)
			(xy 208.157672 -32.423736) (xy 208.203554 -32.352342) (xy 208.256015 -32.285633) (xy 208.314579 -32.224212)
			(xy 208.378717 -32.168637) (xy 208.447847 -32.119409) (xy 208.521343 -32.076976) (xy 208.598541 -32.041721)
			(xy 208.678739 -32.013964) (xy 208.761213 -31.993956) (xy 208.845216 -31.981879) (xy 208.929986 -31.977841)
			(xy 209.014756 -31.981879) (xy 209.098759 -31.993956) (xy 209.181233 -32.013964) (xy 209.261431 -32.041721)
			(xy 209.338629 -32.076976) (xy 209.412125 -32.119409) (xy 209.481255 -32.168637) (xy 209.545393 -32.224212)
			(xy 209.603957 -32.285633) (xy 209.656418 -32.352342) (xy 209.7023 -32.423736) (xy 209.741188 -32.499168)
			(xy 209.77273 -32.577956) (xy 209.796639 -32.659384) (xy 209.8127 -32.742717) (xy 209.820767 -32.827199)
			(xy 209.821272 -32.869632) (xy 209.820767 -32.912065) (xy 210.579205 -32.912065) (xy 210.579205 -32.827199)
			(xy 210.587272 -32.742717) (xy 210.603333 -32.659384) (xy 210.627242 -32.577956) (xy 210.658784 -32.499168)
			(xy 210.697672 -32.423736) (xy 210.743554 -32.352342) (xy 210.796015 -32.285633) (xy 210.854579 -32.224212)
			(xy 210.918717 -32.168637) (xy 210.987847 -32.119409) (xy 211.061343 -32.076976) (xy 211.138541 -32.041721)
			(xy 211.218739 -32.013964) (xy 211.301213 -31.993956) (xy 211.385216 -31.981879) (xy 211.469986 -31.977841)
			(xy 211.554756 -31.981879) (xy 211.638759 -31.993956) (xy 211.721233 -32.013964) (xy 211.801431 -32.041721)
			(xy 211.878629 -32.076976) (xy 211.952125 -32.119409) (xy 212.021255 -32.168637) (xy 212.085393 -32.224212)
			(xy 212.143957 -32.285633) (xy 212.196418 -32.352342) (xy 212.2423 -32.423736) (xy 212.281188 -32.499168)
			(xy 212.31273 -32.577956) (xy 212.336639 -32.659384) (xy 212.3527 -32.742717) (xy 212.360767 -32.827199)
			(xy 212.361272 -32.869632) (xy 212.360767 -32.912065) (xy 212.3527 -32.996547) (xy 212.336639 -33.07988)
			(xy 212.31273 -33.161308) (xy 212.281188 -33.240096) (xy 212.2423 -33.315528) (xy 212.196418 -33.386922)
			(xy 212.143957 -33.453631) (xy 212.085393 -33.515052) (xy 212.021255 -33.570627) (xy 211.952125 -33.619855)
			(xy 211.878629 -33.662288) (xy 211.801431 -33.697543) (xy 211.721233 -33.7253) (xy 211.638759 -33.745308)
			(xy 211.554756 -33.757385) (xy 211.469986 -33.761424) (xy 211.385216 -33.757385) (xy 211.301213 -33.745308)
			(xy 211.218739 -33.7253) (xy 211.138541 -33.697543) (xy 211.061343 -33.662288) (xy 210.987847 -33.619855)
			(xy 210.918717 -33.570627) (xy 210.854579 -33.515052) (xy 210.796015 -33.453631) (xy 210.743554 -33.386922)
			(xy 210.697672 -33.315528) (xy 210.658784 -33.240096) (xy 210.627242 -33.161308) (xy 210.603333 -33.07988)
			(xy 210.587272 -32.996547) (xy 210.579205 -32.912065) (xy 209.820767 -32.912065) (xy 209.8127 -32.996547)
			(xy 209.796639 -33.07988) (xy 209.77273 -33.161308) (xy 209.741188 -33.240096) (xy 209.7023 -33.315528)
			(xy 209.656418 -33.386922) (xy 209.603957 -33.453631) (xy 209.545393 -33.515052) (xy 209.481255 -33.570627)
			(xy 209.412125 -33.619855) (xy 209.338629 -33.662288) (xy 209.261431 -33.697543) (xy 209.181233 -33.7253)
			(xy 209.098759 -33.745308) (xy 209.014756 -33.757385) (xy 208.929986 -33.761424) (xy 208.845216 -33.757385)
			(xy 208.761213 -33.745308) (xy 208.678739 -33.7253) (xy 208.598541 -33.697543) (xy 208.521343 -33.662288)
			(xy 208.447847 -33.619855) (xy 208.378717 -33.570627) (xy 208.314579 -33.515052) (xy 208.256015 -33.453631)
			(xy 208.203554 -33.386922) (xy 208.157672 -33.315528) (xy 208.118784 -33.240096) (xy 208.087242 -33.161308)
			(xy 208.063333 -33.07988) (xy 208.047272 -32.996547) (xy 208.039205 -32.912065) (xy 207.280767 -32.912065)
			(xy 207.2727 -32.996547) (xy 207.256639 -33.07988) (xy 207.23273 -33.161308) (xy 207.201188 -33.240096)
			(xy 207.1623 -33.315528) (xy 207.116418 -33.386922) (xy 207.063957 -33.453631) (xy 207.005393 -33.515052)
			(xy 206.941255 -33.570627) (xy 206.872125 -33.619855) (xy 206.798629 -33.662288) (xy 206.721431 -33.697543)
			(xy 206.641233 -33.7253) (xy 206.558759 -33.745308) (xy 206.474756 -33.757385) (xy 206.389986 -33.761424)
			(xy 206.305216 -33.757385) (xy 206.221213 -33.745308) (xy 206.138739 -33.7253) (xy 206.058541 -33.697543)
			(xy 205.981343 -33.662288) (xy 205.907847 -33.619855) (xy 205.838717 -33.570627) (xy 205.774579 -33.515052)
			(xy 205.716015 -33.453631) (xy 205.663554 -33.386922) (xy 205.617672 -33.315528) (xy 205.578784 -33.240096)
			(xy 205.547242 -33.161308) (xy 205.523333 -33.07988) (xy 205.507272 -32.996547) (xy 205.499205 -32.912065)
			(xy 203.835 -32.912065) (xy 203.835 -35.452065) (xy 208.039205 -35.452065) (xy 208.039205 -35.367199)
			(xy 208.047272 -35.282717) (xy 208.063333 -35.199384) (xy 208.087242 -35.117956) (xy 208.118784 -35.039168)
			(xy 208.157672 -34.963736) (xy 208.203554 -34.892342) (xy 208.256015 -34.825633) (xy 208.314579 -34.764212)
			(xy 208.378717 -34.708637) (xy 208.447847 -34.659409) (xy 208.521343 -34.616976) (xy 208.598541 -34.581721)
			(xy 208.678739 -34.553964) (xy 208.761213 -34.533956) (xy 208.845216 -34.521879) (xy 208.929986 -34.517841)
			(xy 209.014756 -34.521879) (xy 209.098759 -34.533956) (xy 209.181233 -34.553964) (xy 209.261431 -34.581721)
			(xy 209.338629 -34.616976) (xy 209.412125 -34.659409) (xy 209.481255 -34.708637) (xy 209.545393 -34.764212)
			(xy 209.603957 -34.825633) (xy 209.656418 -34.892342) (xy 209.7023 -34.963736) (xy 209.741188 -35.039168)
			(xy 209.77273 -35.117956) (xy 209.796639 -35.199384) (xy 209.8127 -35.282717) (xy 209.820767 -35.367199)
			(xy 209.821272 -35.409632) (xy 209.820767 -35.452065) (xy 210.579205 -35.452065) (xy 210.579205 -35.367199)
			(xy 210.587272 -35.282717) (xy 210.603333 -35.199384) (xy 210.627242 -35.117956) (xy 210.658784 -35.039168)
			(xy 210.697672 -34.963736) (xy 210.743554 -34.892342) (xy 210.796015 -34.825633) (xy 210.854579 -34.764212)
			(xy 210.918717 -34.708637) (xy 210.987847 -34.659409) (xy 211.061343 -34.616976) (xy 211.138541 -34.581721)
			(xy 211.218739 -34.553964) (xy 211.301213 -34.533956) (xy 211.385216 -34.521879) (xy 211.469986 -34.517841)
			(xy 211.554756 -34.521879) (xy 211.638759 -34.533956) (xy 211.721233 -34.553964) (xy 211.801431 -34.581721)
			(xy 211.878629 -34.616976) (xy 211.952125 -34.659409) (xy 212.021255 -34.708637) (xy 212.085393 -34.764212)
			(xy 212.143957 -34.825633) (xy 212.196418 -34.892342) (xy 212.2423 -34.963736) (xy 212.281188 -35.039168)
			(xy 212.31273 -35.117956) (xy 212.336639 -35.199384) (xy 212.3527 -35.282717) (xy 212.360767 -35.367199)
			(xy 212.361272 -35.409632) (xy 212.360767 -35.452065) (xy 212.3527 -35.536547) (xy 212.336639 -35.61988)
			(xy 212.31273 -35.701308) (xy 212.281188 -35.780096) (xy 212.2423 -35.855528) (xy 212.196418 -35.926922)
			(xy 212.143957 -35.993631) (xy 212.085393 -36.055052) (xy 212.021255 -36.110627) (xy 211.952125 -36.159855)
			(xy 211.878629 -36.202288) (xy 211.801431 -36.237543) (xy 211.721233 -36.2653) (xy 211.638759 -36.285308)
			(xy 211.554756 -36.297385) (xy 211.469986 -36.301424) (xy 211.385216 -36.297385) (xy 211.301213 -36.285308)
			(xy 211.218739 -36.2653) (xy 211.138541 -36.237543) (xy 211.061343 -36.202288) (xy 210.987847 -36.159855)
			(xy 210.918717 -36.110627) (xy 210.854579 -36.055052) (xy 210.796015 -35.993631) (xy 210.743554 -35.926922)
			(xy 210.697672 -35.855528) (xy 210.658784 -35.780096) (xy 210.627242 -35.701308) (xy 210.603333 -35.61988)
			(xy 210.587272 -35.536547) (xy 210.579205 -35.452065) (xy 209.820767 -35.452065) (xy 209.8127 -35.536547)
			(xy 209.796639 -35.61988) (xy 209.77273 -35.701308) (xy 209.741188 -35.780096) (xy 209.7023 -35.855528)
			(xy 209.656418 -35.926922) (xy 209.603957 -35.993631) (xy 209.545393 -36.055052) (xy 209.481255 -36.110627)
			(xy 209.412125 -36.159855) (xy 209.338629 -36.202288) (xy 209.261431 -36.237543) (xy 209.181233 -36.2653)
			(xy 209.098759 -36.285308) (xy 209.014756 -36.297385) (xy 208.929986 -36.301424) (xy 208.845216 -36.297385)
			(xy 208.761213 -36.285308) (xy 208.678739 -36.2653) (xy 208.598541 -36.237543) (xy 208.521343 -36.202288)
			(xy 208.447847 -36.159855) (xy 208.378717 -36.110627) (xy 208.314579 -36.055052) (xy 208.256015 -35.993631)
			(xy 208.203554 -35.926922) (xy 208.157672 -35.855528) (xy 208.118784 -35.780096) (xy 208.087242 -35.701308)
			(xy 208.063333 -35.61988) (xy 208.047272 -35.536547) (xy 208.039205 -35.452065) (xy 203.835 -35.452065)
			(xy 203.835 -37.992065) (xy 205.499205 -37.992065) (xy 205.499205 -37.907199) (xy 205.507272 -37.822717)
			(xy 205.523333 -37.739384) (xy 205.547242 -37.657956) (xy 205.578784 -37.579168) (xy 205.617672 -37.503736)
			(xy 205.663554 -37.432342) (xy 205.716015 -37.365633) (xy 205.774579 -37.304212) (xy 205.838717 -37.248637)
			(xy 205.907847 -37.199409) (xy 205.981343 -37.156976) (xy 206.058541 -37.121721) (xy 206.138739 -37.093964)
			(xy 206.221213 -37.073956) (xy 206.305216 -37.061879) (xy 206.389986 -37.057841) (xy 206.474756 -37.061879)
			(xy 206.558759 -37.073956) (xy 206.641233 -37.093964) (xy 206.721431 -37.121721) (xy 206.798629 -37.156976)
			(xy 206.872125 -37.199409) (xy 206.941255 -37.248637) (xy 207.005393 -37.304212) (xy 207.063957 -37.365633)
			(xy 207.116418 -37.432342) (xy 207.1623 -37.503736) (xy 207.201188 -37.579168) (xy 207.23273 -37.657956)
			(xy 207.256639 -37.739384) (xy 207.2727 -37.822717) (xy 207.280767 -37.907199) (xy 207.281272 -37.949632)
			(xy 207.280767 -37.992065) (xy 208.039205 -37.992065) (xy 208.039205 -37.907199) (xy 208.047272 -37.822717)
			(xy 208.063333 -37.739384) (xy 208.087242 -37.657956) (xy 208.118784 -37.579168) (xy 208.157672 -37.503736)
			(xy 208.203554 -37.432342) (xy 208.256015 -37.365633) (xy 208.314579 -37.304212) (xy 208.378717 -37.248637)
			(xy 208.447847 -37.199409) (xy 208.521343 -37.156976) (xy 208.598541 -37.121721) (xy 208.678739 -37.093964)
			(xy 208.761213 -37.073956) (xy 208.845216 -37.061879) (xy 208.929986 -37.057841) (xy 209.014756 -37.061879)
			(xy 209.098759 -37.073956) (xy 209.181233 -37.093964) (xy 209.261431 -37.121721) (xy 209.338629 -37.156976)
			(xy 209.412125 -37.199409) (xy 209.481255 -37.248637) (xy 209.545393 -37.304212) (xy 209.603957 -37.365633)
			(xy 209.656418 -37.432342) (xy 209.7023 -37.503736) (xy 209.741188 -37.579168) (xy 209.77273 -37.657956)
			(xy 209.796639 -37.739384) (xy 209.8127 -37.822717) (xy 209.820767 -37.907199) (xy 209.821272 -37.949632)
			(xy 209.820767 -37.992065) (xy 210.579205 -37.992065) (xy 210.579205 -37.907199) (xy 210.587272 -37.822717)
			(xy 210.603333 -37.739384) (xy 210.627242 -37.657956) (xy 210.658784 -37.579168) (xy 210.697672 -37.503736)
			(xy 210.743554 -37.432342) (xy 210.796015 -37.365633) (xy 210.854579 -37.304212) (xy 210.918717 -37.248637)
			(xy 210.987847 -37.199409) (xy 211.061343 -37.156976) (xy 211.138541 -37.121721) (xy 211.218739 -37.093964)
			(xy 211.301213 -37.073956) (xy 211.385216 -37.061879) (xy 211.469986 -37.057841) (xy 211.554756 -37.061879)
			(xy 211.638759 -37.073956) (xy 211.721233 -37.093964) (xy 211.801431 -37.121721) (xy 211.878629 -37.156976)
			(xy 211.952125 -37.199409) (xy 212.021255 -37.248637) (xy 212.085393 -37.304212) (xy 212.143957 -37.365633)
			(xy 212.196418 -37.432342) (xy 212.2423 -37.503736) (xy 212.281188 -37.579168) (xy 212.31273 -37.657956)
			(xy 212.336639 -37.739384) (xy 212.3527 -37.822717) (xy 212.360767 -37.907199) (xy 212.361272 -37.949632)
			(xy 212.360767 -37.992065) (xy 212.3527 -38.076547) (xy 212.336639 -38.15988) (xy 212.31273 -38.241308)
			(xy 212.281188 -38.320096) (xy 212.2423 -38.395528) (xy 212.196418 -38.466922) (xy 212.143957 -38.533631)
			(xy 212.085393 -38.595052) (xy 212.021255 -38.650627) (xy 211.952125 -38.699855) (xy 211.878629 -38.742288)
			(xy 211.801431 -38.777543) (xy 211.721233 -38.8053) (xy 211.638759 -38.825308) (xy 211.554756 -38.837385)
			(xy 211.469986 -38.841424) (xy 211.385216 -38.837385) (xy 211.301213 -38.825308) (xy 211.218739 -38.8053)
			(xy 211.138541 -38.777543) (xy 211.061343 -38.742288) (xy 210.987847 -38.699855) (xy 210.918717 -38.650627)
			(xy 210.854579 -38.595052) (xy 210.796015 -38.533631) (xy 210.743554 -38.466922) (xy 210.697672 -38.395528)
			(xy 210.658784 -38.320096) (xy 210.627242 -38.241308) (xy 210.603333 -38.15988) (xy 210.587272 -38.076547)
			(xy 210.579205 -37.992065) (xy 209.820767 -37.992065) (xy 209.8127 -38.076547) (xy 209.796639 -38.15988)
			(xy 209.77273 -38.241308) (xy 209.741188 -38.320096) (xy 209.7023 -38.395528) (xy 209.656418 -38.466922)
			(xy 209.603957 -38.533631) (xy 209.545393 -38.595052) (xy 209.481255 -38.650627) (xy 209.412125 -38.699855)
			(xy 209.338629 -38.742288) (xy 209.261431 -38.777543) (xy 209.181233 -38.8053) (xy 209.098759 -38.825308)
			(xy 209.014756 -38.837385) (xy 208.929986 -38.841424) (xy 208.845216 -38.837385) (xy 208.761213 -38.825308)
			(xy 208.678739 -38.8053) (xy 208.598541 -38.777543) (xy 208.521343 -38.742288) (xy 208.447847 -38.699855)
			(xy 208.378717 -38.650627) (xy 208.314579 -38.595052) (xy 208.256015 -38.533631) (xy 208.203554 -38.466922)
			(xy 208.157672 -38.395528) (xy 208.118784 -38.320096) (xy 208.087242 -38.241308) (xy 208.063333 -38.15988)
			(xy 208.047272 -38.076547) (xy 208.039205 -37.992065) (xy 207.280767 -37.992065) (xy 207.2727 -38.076547)
			(xy 207.256639 -38.15988) (xy 207.23273 -38.241308) (xy 207.201188 -38.320096) (xy 207.1623 -38.395528)
			(xy 207.116418 -38.466922) (xy 207.063957 -38.533631) (xy 207.005393 -38.595052) (xy 206.941255 -38.650627)
			(xy 206.872125 -38.699855) (xy 206.798629 -38.742288) (xy 206.721431 -38.777543) (xy 206.641233 -38.8053)
			(xy 206.558759 -38.825308) (xy 206.474756 -38.837385) (xy 206.389986 -38.841424) (xy 206.305216 -38.837385)
			(xy 206.221213 -38.825308) (xy 206.138739 -38.8053) (xy 206.058541 -38.777543) (xy 205.981343 -38.742288)
			(xy 205.907847 -38.699855) (xy 205.838717 -38.650627) (xy 205.774579 -38.595052) (xy 205.716015 -38.533631)
			(xy 205.663554 -38.466922) (xy 205.617672 -38.395528) (xy 205.578784 -38.320096) (xy 205.547242 -38.241308)
			(xy 205.523333 -38.15988) (xy 205.507272 -38.076547) (xy 205.499205 -37.992065) (xy 203.835 -37.992065)
			(xy 203.835 -41.888918) (xy 203.835427 -41.898987) (xy 203.843146 -41.917586) (xy 203.849986 -41.924986)
			(xy 205.090014 -43.165014) (xy 205.097409 -43.171868) (xy 205.116008 -43.17961) (xy 205.126082 -43.18)
			(xy 231.499918 -43.18) (xy 231.509987 -43.180427) (xy 231.528586 -43.188146) (xy 231.535986 -43.194986)
			(xy 233.792014 -45.451014) (xy 233.799409 -45.457868) (xy 233.818008 -45.46561) (xy 233.828082 -45.466)
			(xy 235.063538 -45.466) (xy 235.073605 -45.46557) (xy 235.092199 -45.457846) (xy 235.099606 -45.451014)
			(xy 254.531114 -26.019506) (xy 254.538513 -26.012661) (xy 254.557111 -26.004931) (xy 254.567182 -26.00452)
			(xy 258.777232 -26.00452) (xy 258.787237 -26.004027) (xy 258.805721 -25.996362) (xy 258.819869 -25.982211)
			(xy 258.827529 -25.963725) (xy 258.828032 -25.95372) (xy 258.828032 -25.555194) (xy 258.828516 -25.530113)
			(xy 258.836405 -25.480576) (xy 258.851954 -25.432885) (xy 258.874782 -25.388218) (xy 258.904323 -25.347677)
			(xy 258.921758 -25.329642) (xy 259.313172 -24.938228) (xy 259.33122 -24.920821) (xy 259.371773 -24.891335)
			(xy 259.416444 -24.868563) (xy 259.46413 -24.853069) (xy 259.513654 -24.845236) (xy 259.538724 -24.844756)
			(xy 260.092952 -24.844756) (xy 260.118021 -24.845226) (xy 260.16754 -24.853079) (xy 260.21522 -24.868583)
			(xy 260.259888 -24.891355) (xy 260.300443 -24.920836) (xy 260.318504 -24.938228) (xy 261.370064 -25.989534)
			(xy 261.377463 -25.996378) (xy 261.396062 -26.004099) (xy 261.406132 -26.00452) (xy 275.472398 -26.00452)
			(xy 275.482469 -26.004098) (xy 275.501076 -25.996386) (xy 275.508466 -25.989534) (xy 275.808186 -25.689814)
			(xy 275.810472 -25.65146) (xy 275.79828 -25.63622) (xy 275.782854 -25.615939) (xy 275.756943 -25.572064)
			(xy 275.737096 -25.525133) (xy 275.723666 -25.47598) (xy 275.71689 -25.425477) (xy 275.716492 -25.4)
			(xy 275.716978 -25.372749) (xy 275.724734 -25.318801) (xy 275.740089 -25.266506) (xy 275.762731 -25.216929)
			(xy 275.792197 -25.171079) (xy 275.827888 -25.129888) (xy 275.869079 -25.094197) (xy 275.914929 -25.064731)
			(xy 275.964506 -25.042089) (xy 276.016801 -25.026734) (xy 276.070749 -25.018978) (xy 276.098 -25.018492)
			(xy 276.123942 -25.018946) (xy 276.175343 -25.026007) (xy 276.225317 -25.039959) (xy 276.272943 -25.060544)
			(xy 276.295358 -25.07361) (xy 276.301454 -25.077166) (xy 276.314662 -25.080976) (xy 276.352 -25.080976)
			(xy 276.37707 -25.081442) (xy 276.426593 -25.089288) (xy 276.474278 -25.104787) (xy 276.518951 -25.127556)
			(xy 276.55951 -25.157035) (xy 276.577552 -25.174448) (xy 277.321772 -25.918414) (xy 277.32917 -25.925258)
			(xy 277.34777 -25.93298) (xy 277.35784 -25.9334) (xy 291.44976 -25.9334) (xy 291.459825 -25.932966)
			(xy 291.478414 -25.925236) (xy 291.485828 -25.918414) (xy 294.01008 -23.394162) (xy 294.015922 -23.363682)
			(xy 294.009572 -23.349204) (xy 293.993926 -23.312506) (xy 293.968022 -23.237044) (xy 293.948438 -23.1597)
			(xy 293.935307 -23.081004) (xy 293.928719 -23.001492) (xy 293.928292 -22.9616) (xy 293.928783 -22.917835)
			(xy 293.936704 -22.830663) (xy 293.952482 -22.744566) (xy 293.975987 -22.660251) (xy 294.007026 -22.578408)
			(xy 294.045344 -22.49971) (xy 294.090627 -22.424803) (xy 294.142503 -22.354301) (xy 294.200546 -22.288784)
			(xy 294.264281 -22.228788) (xy 294.333184 -22.174806) (xy 294.406689 -22.127281) (xy 294.484193 -22.086604)
			(xy 294.565061 -22.053107) (xy 294.648629 -22.027067) (xy 294.73421 -22.008696) (xy 294.821102 -21.998145)
			(xy 294.908593 -21.995501) (xy 294.995964 -22.000786) (xy 295.082498 -22.013956) (xy 295.167485 -22.034904)
			(xy 295.250228 -22.063457) (xy 295.330047 -22.09938) (xy 295.406288 -22.14238) (xy 295.478324 -22.192103)
			(xy 295.545565 -22.248142) (xy 295.607458 -22.310035) (xy 295.663497 -22.377276) (xy 295.71322 -22.449312)
			(xy 295.75622 -22.525553) (xy 295.792143 -22.605372) (xy 295.820696 -22.688115) (xy 295.841644 -22.773102)
			(xy 295.854814 -22.859636) (xy 295.860099 -22.947007) (xy 295.859658 -22.9616) (xy 296.467791 -22.9616)
			(xy 296.471794 -22.873738) (xy 296.48377 -22.786604) (xy 296.503621 -22.70092) (xy 296.53118 -22.617396)
			(xy 296.566221 -22.536724) (xy 296.608452 -22.459573) (xy 296.657524 -22.386582) (xy 296.713031 -22.318356)
			(xy 296.774511 -22.25546) (xy 296.841456 -22.198415) (xy 296.913311 -22.147694) (xy 296.989481 -22.103717)
			(xy 297.069334 -22.066849) (xy 297.152209 -22.037396) (xy 297.237419 -22.0156) (xy 297.324258 -22.001644)
			(xy 297.412006 -21.995641) (xy 297.499936 -21.997643) (xy 297.587321 -22.007633) (xy 297.673434 -22.025528)
			(xy 297.757564 -22.051179) (xy 297.839012 -22.084374) (xy 297.917105 -22.124838) (xy 297.991194 -22.172236)
			(xy 298.060666 -22.226175) (xy 298.124945 -22.286208) (xy 298.183499 -22.351837) (xy 298.235843 -22.422519)
			(xy 298.281542 -22.497668) (xy 298.320218 -22.576661) (xy 298.35155 -22.658844) (xy 298.37528 -22.743536)
			(xy 298.39121 -22.830035) (xy 298.399208 -22.917623) (xy 298.399708 -22.9616) (xy 298.399208 -23.005577)
			(xy 298.39121 -23.093165) (xy 298.37528 -23.179664) (xy 298.35155 -23.264356) (xy 298.320218 -23.346539)
			(xy 298.281542 -23.425532) (xy 298.235843 -23.500681) (xy 298.183499 -23.571363) (xy 298.124945 -23.636992)
			(xy 298.060666 -23.697025) (xy 297.991194 -23.750964) (xy 297.917105 -23.798362) (xy 297.839012 -23.838826)
			(xy 297.757564 -23.872021) (xy 297.673434 -23.897672) (xy 297.587321 -23.915567) (xy 297.499936 -23.925557)
			(xy 297.412006 -23.927559) (xy 297.324258 -23.921556) (xy 297.237419 -23.9076) (xy 297.152209 -23.885804)
			(xy 297.069334 -23.856351) (xy 296.989481 -23.819483) (xy 296.913311 -23.775506) (xy 296.841456 -23.724785)
			(xy 296.774511 -23.66774) (xy 296.713031 -23.604844) (xy 296.657524 -23.536618) (xy 296.608452 -23.463627)
			(xy 296.566221 -23.386476) (xy 296.53118 -23.305804) (xy 296.503621 -23.22228) (xy 296.48377 -23.136596)
			(xy 296.471794 -23.049462) (xy 296.467791 -22.9616) (xy 295.859658 -22.9616) (xy 295.857455 -23.034498)
			(xy 295.846904 -23.12139) (xy 295.828533 -23.206971) (xy 295.802493 -23.290539) (xy 295.768996 -23.371407)
			(xy 295.728319 -23.448911) (xy 295.680794 -23.522416) (xy 295.626812 -23.591319) (xy 295.566816 -23.655054)
			(xy 295.501299 -23.713097) (xy 295.430797 -23.764973) (xy 295.35589 -23.810256) (xy 295.277192 -23.848574)
			(xy 295.195349 -23.879613) (xy 295.111034 -23.903118) (xy 295.024937 -23.918896) (xy 294.937765 -23.926817)
			(xy 294.894 -23.927308) (xy 294.854108 -23.926885) (xy 294.774598 -23.920282) (xy 294.695903 -23.907146)
			(xy 294.618559 -23.887566) (xy 294.543093 -23.861676) (xy 294.506396 -23.846028) (xy 294.491918 -23.839678)
			(xy 294.461438 -23.84552) (xy 292.598856 -25.708102) (xy 292.60419 -25.720802) (xy 292.605988 -25.725489)
			(xy 292.607907 -25.735341) (xy 292.608 -25.74036) (xy 292.608 -28.282646) (xy 292.608432 -28.292712)
			(xy 292.616158 -28.311305) (xy 292.622986 -28.318714) (xy 297.045634 -32.741362) (xy 297.052478 -32.748761)
			(xy 297.0602 -32.76736) (xy 297.06062 -32.77743) (xy 297.06062 -36.987734) (xy 297.06105 -36.997801)
			(xy 297.068775 -37.016395) (xy 297.075606 -37.023802) (xy 297.497246 -37.445442) (xy 297.504644 -37.452287)
			(xy 297.523243 -37.460014) (xy 297.533314 -37.460428) (xy 302.691546 -37.460428) (xy 302.701612 -37.46086)
			(xy 302.720202 -37.468589) (xy 302.727614 -37.475414) (xy 303.351184 -38.098984) (xy 303.358019 -38.106386)
			(xy 303.365725 -38.124985) (xy 303.36617 -38.135052) (xy 303.36617 -44.304966) (xy 306.278033 -44.304966)
			(xy 306.28204 -44.102216) (xy 306.294053 -43.899782) (xy 306.314054 -43.697981) (xy 306.342013 -43.497127)
			(xy 306.377884 -43.297535) (xy 306.421613 -43.099516) (xy 306.473131 -42.903379) (xy 306.532357 -42.709431)
			(xy 306.599199 -42.517973) (xy 306.673553 -42.329306) (xy 306.755302 -42.143724) (xy 306.84432 -41.961516)
			(xy 306.940466 -41.782967) (xy 307.043591 -41.608356) (xy 307.153534 -41.437956) (xy 307.270123 -41.272032)
			(xy 307.393176 -41.110843) (xy 307.522501 -40.954642) (xy 307.657896 -40.803672) (xy 307.799149 -40.658168)
			(xy 307.946041 -40.518359) (xy 308.098341 -40.384462) (xy 308.255812 -40.256687) (xy 308.418209 -40.135232)
			(xy 308.585276 -40.020288) (xy 308.756755 -39.912034) (xy 308.932376 -39.810639) (xy 309.111866 -39.716261)
			(xy 309.294944 -39.629049) (xy 309.481325 -39.549137) (xy 309.670718 -39.47665) (xy 309.862826 -39.411703)
			(xy 310.05735 -39.354395) (xy 310.253986 -39.304818) (xy 310.452428 -39.263047) (xy 310.652365 -39.229149)
			(xy 310.853484 -39.203177) (xy 311.055473 -39.18517) (xy 311.258016 -39.175157) (xy 311.460796 -39.173153)
			(xy 311.663497 -39.179163) (xy 311.865802 -39.193175) (xy 312.067396 -39.21517) (xy 312.267963 -39.245111)
			(xy 312.467191 -39.282952) (xy 312.664769 -39.328635) (xy 312.860387 -39.382088) (xy 313.053741 -39.443227)
			(xy 313.244529 -39.511958) (xy 313.432452 -39.588172) (xy 313.617218 -39.671751) (xy 313.798537 -39.762564)
			(xy 313.976128 -39.860469) (xy 314.149711 -39.965314) (xy 314.319017 -40.076935) (xy 314.483782 -40.195157)
			(xy 314.643747 -40.319797) (xy 314.798663 -40.450658) (xy 314.948288 -40.587538) (xy 315.092388 -40.730222)
			(xy 315.23074 -40.878488) (xy 315.363125 -41.032104) (xy 315.489339 -41.190829) (xy 315.609183 -41.354418)
			(xy 315.722471 -41.522613) (xy 315.829026 -41.695152) (xy 315.928681 -41.871767) (xy 316.021281 -42.05218)
			(xy 316.106681 -42.236111) (xy 316.184748 -42.423272) (xy 316.25536 -42.613372) (xy 316.318406 -42.806112)
			(xy 316.373789 -43.001193) (xy 316.421421 -43.19831) (xy 316.461229 -43.397154) (xy 316.493151 -43.597416)
			(xy 316.517135 -43.798782) (xy 316.533146 -44.000939) (xy 316.541157 -44.203571) (xy 316.541658 -44.304966)
			(xy 316.541157 -44.406361) (xy 316.533146 -44.608993) (xy 316.517135 -44.81115) (xy 316.493151 -45.012516)
			(xy 316.461229 -45.212778) (xy 316.421421 -45.411622) (xy 316.373789 -45.608739) (xy 316.318406 -45.80382)
			(xy 316.25536 -45.99656) (xy 316.184748 -46.18666) (xy 316.106681 -46.373821) (xy 316.021281 -46.557752)
			(xy 315.928681 -46.738165) (xy 315.829026 -46.91478) (xy 315.722471 -47.087319) (xy 315.609183 -47.255514)
			(xy 315.489339 -47.419103) (xy 315.363125 -47.577828) (xy 315.23074 -47.731444) (xy 315.092388 -47.87971)
			(xy 314.948288 -48.022394) (xy 314.798663 -48.159274) (xy 314.643747 -48.290135) (xy 314.483782 -48.414775)
			(xy 314.319017 -48.532997) (xy 314.149711 -48.644618) (xy 313.976128 -48.749463) (xy 313.798537 -48.847368)
			(xy 313.617218 -48.938181) (xy 313.432452 -49.02176) (xy 313.244529 -49.097974) (xy 313.053741 -49.166705)
			(xy 312.860387 -49.227844) (xy 312.664769 -49.281297) (xy 312.467191 -49.32698) (xy 312.267963 -49.364821)
			(xy 312.067396 -49.394762) (xy 311.865802 -49.416757) (xy 311.663497 -49.430769) (xy 311.460796 -49.436779)
			(xy 311.258016 -49.434775) (xy 311.055473 -49.424762) (xy 310.853484 -49.406755) (xy 310.652365 -49.380783)
			(xy 310.452428 -49.346885) (xy 310.253986 -49.305114) (xy 310.05735 -49.255537) (xy 309.862826 -49.198229)
			(xy 309.670718 -49.133282) (xy 309.481325 -49.060795) (xy 309.294944 -48.980883) (xy 309.111866 -48.893671)
			(xy 308.932376 -48.799293) (xy 308.756755 -48.697898) (xy 308.585276 -48.589644) (xy 308.418209 -48.4747)
			(xy 308.255812 -48.353245) (xy 308.098341 -48.22547) (xy 307.946041 -48.091573) (xy 307.799149 -47.951764)
			(xy 307.657896 -47.80626) (xy 307.522501 -47.65529) (xy 307.393176 -47.499089) (xy 307.270123 -47.3379)
			(xy 307.153534 -47.171976) (xy 307.043591 -47.001576) (xy 306.940466 -46.826965) (xy 306.84432 -46.648416)
			(xy 306.755302 -46.466208) (xy 306.673553 -46.280626) (xy 306.599199 -46.091959) (xy 306.532357 -45.900501)
			(xy 306.473131 -45.706553) (xy 306.421613 -45.510416) (xy 306.377884 -45.312397) (xy 306.342013 -45.112805)
			(xy 306.314054 -44.911951) (xy 306.294053 -44.71015) (xy 306.28204 -44.507716) (xy 306.278033 -44.304966)
			(xy 303.36617 -44.304966) (xy 303.36617 -51.885088) (xy 303.36659 -51.89516) (xy 303.374298 -51.91377)
			(xy 303.381156 -51.921156) (xy 307.346858 -55.886858) (xy 307.3537 -55.894258) (xy 307.36142 -55.912856)
			(xy 307.361844 -55.922926) (xy 307.361844 -72.879966) (xy 310.010309 -72.879966) (xy 310.014317 -72.774102)
			(xy 310.026321 -72.668844) (xy 310.046251 -72.564796) (xy 310.073993 -72.462552) (xy 310.109388 -72.3627)
			(xy 310.152234 -72.26581) (xy 310.202284 -72.172439) (xy 310.259252 -72.08312) (xy 310.322813 -71.998365)
			(xy 310.392601 -71.91866) (xy 310.468217 -71.844461) (xy 310.549229 -71.776194) (xy 310.635171 -71.714249)
			(xy 310.725552 -71.658981) (xy 310.819854 -71.610706) (xy 310.917537 -71.569702) (xy 311.018042 -71.536203)
			(xy 311.120792 -71.510401) (xy 311.225199 -71.492444) (xy 311.330665 -71.482434) (xy 311.436586 -71.480429)
			(xy 311.542355 -71.486441) (xy 311.647367 -71.500434) (xy 311.75102 -71.52233) (xy 311.85272 -71.552002)
			(xy 311.951884 -71.58928) (xy 312.047945 -71.633951) (xy 312.140353 -71.685759) (xy 312.228578 -71.744408)
			(xy 312.312115 -71.809561) (xy 312.390485 -71.880845) (xy 312.463239 -71.957852) (xy 312.529962 -72.040141)
			(xy 312.590269 -72.12724) (xy 312.643817 -72.218651) (xy 312.690298 -72.31385) (xy 312.729446 -72.412291)
			(xy 312.761037 -72.513411) (xy 312.78489 -72.616631) (xy 312.800869 -72.721359) (xy 312.808881 -72.826996)
			(xy 312.809382 -72.879966) (xy 312.808981 -72.922399) (xy 313.059315 -72.922399) (xy 313.059315 -72.837533)
			(xy 313.067382 -72.753051) (xy 313.083443 -72.669718) (xy 313.107352 -72.58829) (xy 313.138894 -72.509502)
			(xy 313.177782 -72.43407) (xy 313.223664 -72.362676) (xy 313.276125 -72.295967) (xy 313.334689 -72.234546)
			(xy 313.398827 -72.178971) (xy 313.467957 -72.129743) (xy 313.541453 -72.08731) (xy 313.618651 -72.052055)
			(xy 313.698849 -72.024298) (xy 313.781323 -72.00429) (xy 313.865326 -71.992213) (xy 313.950096 -71.988175)
			(xy 314.034866 -71.992213) (xy 314.118869 -72.00429) (xy 314.201343 -72.024298) (xy 314.281541 -72.052055)
			(xy 314.358739 -72.08731) (xy 314.432235 -72.129743) (xy 314.501365 -72.178971) (xy 314.565503 -72.234546)
			(xy 314.624067 -72.295967) (xy 314.676528 -72.362676) (xy 314.72241 -72.43407) (xy 314.761298 -72.509502)
			(xy 314.79284 -72.58829) (xy 314.816749 -72.669718) (xy 314.83281 -72.753051) (xy 314.840877 -72.837533)
			(xy 314.841382 -72.879966) (xy 314.840877 -72.922399) (xy 315.599315 -72.922399) (xy 315.599315 -72.837533)
			(xy 315.607382 -72.753051) (xy 315.623443 -72.669718) (xy 315.647352 -72.58829) (xy 315.678894 -72.509502)
			(xy 315.717782 -72.43407) (xy 315.763664 -72.362676) (xy 315.816125 -72.295967) (xy 315.874689 -72.234546)
			(xy 315.938827 -72.178971) (xy 316.007957 -72.129743) (xy 316.081453 -72.08731) (xy 316.158651 -72.052055)
			(xy 316.238849 -72.024298) (xy 316.321323 -72.00429) (xy 316.405326 -71.992213) (xy 316.490096 -71.988175)
			(xy 316.574866 -71.992213) (xy 316.658869 -72.00429) (xy 316.741343 -72.024298) (xy 316.821541 -72.052055)
			(xy 316.898739 -72.08731) (xy 316.972235 -72.129743) (xy 317.041365 -72.178971) (xy 317.105503 -72.234546)
			(xy 317.164067 -72.295967) (xy 317.216528 -72.362676) (xy 317.26241 -72.43407) (xy 317.301298 -72.509502)
			(xy 317.33284 -72.58829) (xy 317.356749 -72.669718) (xy 317.37281 -72.753051) (xy 317.380877 -72.837533)
			(xy 317.381382 -72.879966) (xy 317.380877 -72.922399) (xy 318.139315 -72.922399) (xy 318.139315 -72.837533)
			(xy 318.147382 -72.753051) (xy 318.163443 -72.669718) (xy 318.187352 -72.58829) (xy 318.218894 -72.509502)
			(xy 318.257782 -72.43407) (xy 318.303664 -72.362676) (xy 318.356125 -72.295967) (xy 318.414689 -72.234546)
			(xy 318.478827 -72.178971) (xy 318.547957 -72.129743) (xy 318.621453 -72.08731) (xy 318.698651 -72.052055)
			(xy 318.778849 -72.024298) (xy 318.861323 -72.00429) (xy 318.945326 -71.992213) (xy 319.030096 -71.988175)
			(xy 319.114866 -71.992213) (xy 319.198869 -72.00429) (xy 319.281343 -72.024298) (xy 319.361541 -72.052055)
			(xy 319.438739 -72.08731) (xy 319.512235 -72.129743) (xy 319.581365 -72.178971) (xy 319.645503 -72.234546)
			(xy 319.704067 -72.295967) (xy 319.756528 -72.362676) (xy 319.80241 -72.43407) (xy 319.841298 -72.509502)
			(xy 319.87284 -72.58829) (xy 319.896749 -72.669718) (xy 319.91281 -72.753051) (xy 319.920877 -72.837533)
			(xy 319.921382 -72.879966) (xy 319.920877 -72.922399) (xy 319.91281 -73.006881) (xy 319.896749 -73.090214)
			(xy 319.87284 -73.171642) (xy 319.841298 -73.25043) (xy 319.80241 -73.325862) (xy 319.756528 -73.397256)
			(xy 319.704067 -73.463965) (xy 319.645503 -73.525386) (xy 319.581365 -73.580961) (xy 319.512235 -73.630189)
			(xy 319.438739 -73.672622) (xy 319.361541 -73.707877) (xy 319.281343 -73.735634) (xy 319.198869 -73.755642)
			(xy 319.114866 -73.767719) (xy 319.030096 -73.771758) (xy 318.945326 -73.767719) (xy 318.861323 -73.755642)
			(xy 318.778849 -73.735634) (xy 318.698651 -73.707877) (xy 318.621453 -73.672622) (xy 318.547957 -73.630189)
			(xy 318.478827 -73.580961) (xy 318.414689 -73.525386) (xy 318.356125 -73.463965) (xy 318.303664 -73.397256)
			(xy 318.257782 -73.325862) (xy 318.218894 -73.25043) (xy 318.187352 -73.171642) (xy 318.163443 -73.090214)
			(xy 318.147382 -73.006881) (xy 318.139315 -72.922399) (xy 317.380877 -72.922399) (xy 317.37281 -73.006881)
			(xy 317.356749 -73.090214) (xy 317.33284 -73.171642) (xy 317.301298 -73.25043) (xy 317.26241 -73.325862)
			(xy 317.216528 -73.397256) (xy 317.164067 -73.463965) (xy 317.105503 -73.525386) (xy 317.041365 -73.580961)
			(xy 316.972235 -73.630189) (xy 316.898739 -73.672622) (xy 316.821541 -73.707877) (xy 316.741343 -73.735634)
			(xy 316.658869 -73.755642) (xy 316.574866 -73.767719) (xy 316.490096 -73.771758) (xy 316.405326 -73.767719)
			(xy 316.321323 -73.755642) (xy 316.238849 -73.735634) (xy 316.158651 -73.707877) (xy 316.081453 -73.672622)
			(xy 316.007957 -73.630189) (xy 315.938827 -73.580961) (xy 315.874689 -73.525386) (xy 315.816125 -73.463965)
			(xy 315.763664 -73.397256) (xy 315.717782 -73.325862) (xy 315.678894 -73.25043) (xy 315.647352 -73.171642)
			(xy 315.623443 -73.090214) (xy 315.607382 -73.006881) (xy 315.599315 -72.922399) (xy 314.840877 -72.922399)
			(xy 314.83281 -73.006881) (xy 314.816749 -73.090214) (xy 314.79284 -73.171642) (xy 314.761298 -73.25043)
			(xy 314.72241 -73.325862) (xy 314.676528 -73.397256) (xy 314.624067 -73.463965) (xy 314.565503 -73.525386)
			(xy 314.501365 -73.580961) (xy 314.432235 -73.630189) (xy 314.358739 -73.672622) (xy 314.281541 -73.707877)
			(xy 314.201343 -73.735634) (xy 314.118869 -73.755642) (xy 314.034866 -73.767719) (xy 313.950096 -73.771758)
			(xy 313.865326 -73.767719) (xy 313.781323 -73.755642) (xy 313.698849 -73.735634) (xy 313.618651 -73.707877)
			(xy 313.541453 -73.672622) (xy 313.467957 -73.630189) (xy 313.398827 -73.580961) (xy 313.334689 -73.525386)
			(xy 313.276125 -73.463965) (xy 313.223664 -73.397256) (xy 313.177782 -73.325862) (xy 313.138894 -73.25043)
			(xy 313.107352 -73.171642) (xy 313.083443 -73.090214) (xy 313.067382 -73.006881) (xy 313.059315 -72.922399)
			(xy 312.808981 -72.922399) (xy 312.808881 -72.932936) (xy 312.800869 -73.038573) (xy 312.78489 -73.143301)
			(xy 312.761037 -73.246521) (xy 312.729446 -73.347641) (xy 312.690298 -73.446082) (xy 312.643817 -73.541281)
			(xy 312.590269 -73.632692) (xy 312.529962 -73.719791) (xy 312.463239 -73.80208) (xy 312.390485 -73.879087)
			(xy 312.312115 -73.950371) (xy 312.228578 -74.015524) (xy 312.140353 -74.074173) (xy 312.047945 -74.125981)
			(xy 311.951884 -74.170652) (xy 311.85272 -74.20793) (xy 311.75102 -74.237602) (xy 311.647367 -74.259498)
			(xy 311.542355 -74.273491) (xy 311.436586 -74.279503) (xy 311.330665 -74.277498) (xy 311.225199 -74.267488)
			(xy 311.120792 -74.249531) (xy 311.018042 -74.223729) (xy 310.917537 -74.19023) (xy 310.819854 -74.149226)
			(xy 310.725552 -74.100951) (xy 310.635171 -74.045683) (xy 310.549229 -73.983738) (xy 310.468217 -73.915471)
			(xy 310.392601 -73.841272) (xy 310.322813 -73.761567) (xy 310.259252 -73.676812) (xy 310.202284 -73.587493)
			(xy 310.152234 -73.494122) (xy 310.109388 -73.397232) (xy 310.073993 -73.29738) (xy 310.046251 -73.195136)
			(xy 310.026321 -73.091088) (xy 310.014317 -72.98583) (xy 310.010309 -72.879966) (xy 307.361844 -72.879966)
			(xy 307.361844 -73.10755) (xy 307.362278 -73.117615) (xy 307.37001 -73.136202) (xy 307.37683 -73.143618)
			(xy 309.103014 -74.869802) (xy 309.110414 -74.876646) (xy 309.129011 -74.884375) (xy 309.139082 -74.884788)
			(xy 321.365118 -74.884788) (xy 321.375187 -74.885214) (xy 321.393788 -74.892932) (xy 321.401186 -74.899774)
			(xy 322.61302 -76.111608) (xy 322.619874 -76.119003) (xy 322.627618 -76.137602) (xy 322.628006 -76.147676)
			(xy 322.628006 -122.152918) (xy 322.62758 -122.162987) (xy 322.619862 -122.181587) (xy 322.61302 -122.188986)
			(xy 320.509392 -124.292614) (xy 320.501997 -124.299468) (xy 320.483398 -124.307214) (xy 320.473324 -124.3076)
			(xy 302.415194 -124.3076) (xy 302.405124 -124.308024) (xy 302.386521 -124.31574) (xy 302.379126 -124.322586)
			(xy 300.2534 -126.448312) (xy 300.246556 -126.455711) (xy 300.238826 -126.474309) (xy 300.238414 -126.48438)
			(xy 300.238414 -131.769104) (xy 300.237991 -131.779174) (xy 300.230277 -131.797779) (xy 300.223428 -131.805172)
			(xy 298.083986 -133.944614) (xy 298.076591 -133.951468) (xy 298.057992 -133.95921) (xy 298.047918 -133.9596)
			(xy 280.056082 -133.9596) (xy 280.046013 -133.960027) (xy 280.027414 -133.967746) (xy 280.020014 -133.974586)
			(xy 278.906986 -135.087614) (xy 278.900132 -135.095009) (xy 278.89239 -135.113608) (xy 278.892 -135.123682)
			(xy 278.892 -144.962118) (xy 278.892427 -144.972187) (xy 278.900146 -144.990786) (xy 278.906986 -144.998186)
			(xy 279.461214 -145.552414) (xy 279.468609 -145.559268) (xy 279.487208 -145.56701) (xy 279.497282 -145.5674)
		)
		(stroke
			(width 0)
			(type solid)
		)
		(fill yes)
		(layer "In7.Cu")
		(net "GND")
	)
	(gr_poly
		(pts
			(xy 222.089472 -145.000726) (xy 222.099523 -145.000222) (xy 222.118086 -144.992502) (xy 222.12554 -144.98574)
			(xy 222.743014 -144.368266) (xy 222.749865 -144.36087) (xy 222.7576 -144.342271) (xy 222.758 -144.332198)
			(xy 222.758 -144.028668) (xy 222.757625 -144.019195) (xy 222.750759 -144.001538) (xy 222.737942 -143.987586)
			(xy 222.720929 -143.979251) (xy 222.711518 -143.978122) (xy 222.646862 -143.972174) (xy 222.51839 -143.953282)
			(xy 222.391334 -143.926472) (xy 222.266181 -143.891849) (xy 222.143412 -143.849543) (xy 222.023497 -143.799719)
			(xy 221.906897 -143.742566) (xy 221.794058 -143.678305) (xy 221.685415 -143.607181) (xy 221.581383 -143.529468)
			(xy 221.482361 -143.445463) (xy 221.38873 -143.35549) (xy 221.300849 -143.259892) (xy 221.219054 -143.159038)
			(xy 221.14366 -143.053313) (xy 221.074956 -142.943123) (xy 221.013205 -142.828891) (xy 220.958645 -142.711056)
			(xy 220.911484 -142.590069) (xy 220.871903 -142.466394) (xy 220.840055 -142.340506) (xy 220.816062 -142.212889)
			(xy 220.800015 -142.08403) (xy 220.791976 -141.954425) (xy 220.791976 -141.824571) (xy 220.800015 -141.694967)
			(xy 220.816062 -141.566108) (xy 220.840056 -141.43849) (xy 220.871904 -141.312603) (xy 220.911485 -141.188928)
			(xy 220.958646 -141.067941) (xy 221.013207 -140.950106) (xy 221.074958 -140.835874) (xy 221.143662 -140.725685)
			(xy 221.219056 -140.61996) (xy 221.300851 -140.519105) (xy 221.388732 -140.423508) (xy 221.482364 -140.333534)
			(xy 221.581385 -140.24953) (xy 221.685418 -140.171817) (xy 221.794061 -140.100693) (xy 221.9069 -140.036432)
			(xy 222.0235 -139.97928) (xy 222.143415 -139.929455) (xy 222.266184 -139.88715) (xy 222.391337 -139.852527)
			(xy 222.518393 -139.825718) (xy 222.646866 -139.806826) (xy 222.711518 -139.800838) (xy 222.720903 -139.799638)
			(xy 222.737867 -139.791285) (xy 222.750655 -139.777358) (xy 222.757533 -139.759745) (xy 222.758 -139.750292)
			(xy 222.758 -117.714522) (xy 222.75038 -117.695726) (xy 222.743014 -117.688614) (xy 222.228664 -117.174264)
			(xy 222.221552 -117.166898) (xy 222.202756 -117.159278) (xy 193.527426 -117.159278) (xy 193.513456 -117.16131)
			(xy 193.507106 -117.163088) (xy 193.50101 -117.166644) (xy 193.494904 -117.170145) (xy 193.481374 -117.174007)
			(xy 193.47434 -117.174264) (xy 38.092634 -117.174264) (xy 38.082571 -117.174701) (xy 38.06399 -117.182439)
			(xy 38.056566 -117.18925) (xy 37.546788 -117.698774) (xy 37.539944 -117.706172) (xy 37.532222 -117.724772)
			(xy 37.531802 -117.734842) (xy 37.531802 -121.209816) (xy 47.412921 -121.209816) (xy 47.416894 -121.089722)
			(xy 47.428795 -120.970154) (xy 47.448573 -120.851634) (xy 47.47614 -120.734679) (xy 47.511377 -120.619803)
			(xy 47.554129 -120.507506) (xy 47.604209 -120.398281) (xy 47.661398 -120.292604) (xy 47.725447 -120.190938)
			(xy 47.796075 -120.093727) (xy 47.872973 -120.001397) (xy 47.955805 -119.91435) (xy 48.044209 -119.832969)
			(xy 48.137798 -119.757607) (xy 48.236164 -119.688597) (xy 48.338875 -119.626238) (xy 48.445483 -119.570803)
			(xy 48.555522 -119.522536) (xy 48.66851 -119.481646) (xy 48.783953 -119.448314) (xy 48.901347 -119.422684)
			(xy 49.020178 -119.404869) (xy 49.139927 -119.394946) (xy 49.26007 -119.392959) (xy 49.380081 -119.398917)
			(xy 49.499437 -119.412794) (xy 49.617614 -119.434528) (xy 49.734096 -119.464026) (xy 49.848374 -119.501157)
			(xy 49.959949 -119.54576) (xy 50.068331 -119.597639) (xy 50.173048 -119.656568) (xy 50.273641 -119.722289)
			(xy 50.369671 -119.794514) (xy 50.460718 -119.872928) (xy 50.546383 -119.957188) (xy 50.626292 -120.046926)
			(xy 50.700095 -120.141748) (xy 50.76747 -120.241241) (xy 50.828122 -120.34497) (xy 50.881786 -120.45248)
			(xy 50.928228 -120.563301) (xy 50.967243 -120.67695) (xy 50.998663 -120.792929) (xy 51.022348 -120.91073)
			(xy 51.038196 -121.02984) (xy 51.046138 -121.149736) (xy 51.046634 -121.209816) (xy 55.032921 -121.209816)
			(xy 55.036894 -121.089722) (xy 55.048795 -120.970154) (xy 55.068573 -120.851634) (xy 55.09614 -120.734679)
			(xy 55.131377 -120.619803) (xy 55.174129 -120.507506) (xy 55.224209 -120.398281) (xy 55.281398 -120.292604)
			(xy 55.345447 -120.190938) (xy 55.416075 -120.093727) (xy 55.492973 -120.001397) (xy 55.575805 -119.91435)
			(xy 55.664209 -119.832969) (xy 55.757798 -119.757607) (xy 55.856164 -119.688597) (xy 55.958875 -119.626238)
			(xy 56.065483 -119.570803) (xy 56.175522 -119.522536) (xy 56.28851 -119.481646) (xy 56.403953 -119.448314)
			(xy 56.521347 -119.422684) (xy 56.640178 -119.404869) (xy 56.759927 -119.394946) (xy 56.88007 -119.392959)
			(xy 57.000081 -119.398917) (xy 57.119437 -119.412794) (xy 57.237614 -119.434528) (xy 57.354096 -119.464026)
			(xy 57.468374 -119.501157) (xy 57.579949 -119.54576) (xy 57.688331 -119.597639) (xy 57.793048 -119.656568)
			(xy 57.893641 -119.722289) (xy 57.989671 -119.794514) (xy 58.080718 -119.872928) (xy 58.166383 -119.957188)
			(xy 58.246292 -120.046926) (xy 58.320095 -120.141748) (xy 58.38747 -120.241241) (xy 58.448122 -120.34497)
			(xy 58.501786 -120.45248) (xy 58.548228 -120.563301) (xy 58.587243 -120.67695) (xy 58.618663 -120.792929)
			(xy 58.642348 -120.91073) (xy 58.658196 -121.02984) (xy 58.666138 -121.149736) (xy 58.666634 -121.209816)
			(xy 58.66621 -121.261212) (xy 63.161922 -121.261212) (xy 63.161922 -121.15842) (xy 63.169987 -121.055946)
			(xy 63.186067 -120.954421) (xy 63.210063 -120.85447) (xy 63.241828 -120.75671) (xy 63.281164 -120.661743)
			(xy 63.32783 -120.570156) (xy 63.381538 -120.482512) (xy 63.441957 -120.399352) (xy 63.508715 -120.321189)
			(xy 63.581399 -120.248505) (xy 63.659562 -120.181747) (xy 63.742722 -120.121328) (xy 63.830366 -120.06762)
			(xy 63.921953 -120.020954) (xy 64.01692 -119.981618) (xy 64.11468 -119.949853) (xy 64.214631 -119.925857)
			(xy 64.316156 -119.909777) (xy 64.41863 -119.901712) (xy 64.521422 -119.901712) (xy 64.623896 -119.909777)
			(xy 64.725421 -119.925857) (xy 64.825372 -119.949853) (xy 64.923132 -119.981618) (xy 65.018099 -120.020954)
			(xy 65.109686 -120.06762) (xy 65.19733 -120.121328) (xy 65.28049 -120.181747) (xy 65.358653 -120.248505)
			(xy 65.431337 -120.321189) (xy 65.498095 -120.399352) (xy 65.558514 -120.482512) (xy 65.612222 -120.570156)
			(xy 65.658888 -120.661743) (xy 65.698224 -120.75671) (xy 65.729989 -120.85447) (xy 65.753985 -120.954421)
			(xy 65.770065 -121.055946) (xy 65.77813 -121.15842) (xy 65.778634 -121.209816) (xy 87.412841 -121.209816)
			(xy 87.416814 -121.089722) (xy 87.428715 -120.970154) (xy 87.448493 -120.851634) (xy 87.47606 -120.734679)
			(xy 87.511297 -120.619803) (xy 87.554049 -120.507506) (xy 87.604129 -120.398281) (xy 87.661318 -120.292604)
			(xy 87.725367 -120.190938) (xy 87.795995 -120.093727) (xy 87.872893 -120.001397) (xy 87.955725 -119.91435)
			(xy 88.044129 -119.832969) (xy 88.137718 -119.757607) (xy 88.236084 -119.688597) (xy 88.338795 -119.626238)
			(xy 88.445403 -119.570803) (xy 88.555442 -119.522536) (xy 88.66843 -119.481646) (xy 88.783873 -119.448314)
			(xy 88.901267 -119.422684) (xy 89.020098 -119.404869) (xy 89.139847 -119.394946) (xy 89.25999 -119.392959)
			(xy 89.380001 -119.398917) (xy 89.499357 -119.412794) (xy 89.617534 -119.434528) (xy 89.734016 -119.464026)
			(xy 89.848294 -119.501157) (xy 89.959869 -119.54576) (xy 90.068251 -119.597639) (xy 90.172968 -119.656568)
			(xy 90.273561 -119.722289) (xy 90.369591 -119.794514) (xy 90.460638 -119.872928) (xy 90.546303 -119.957188)
			(xy 90.626212 -120.046926) (xy 90.700015 -120.141748) (xy 90.76739 -120.241241) (xy 90.828042 -120.34497)
			(xy 90.881706 -120.45248) (xy 90.928148 -120.563301) (xy 90.967163 -120.67695) (xy 90.998583 -120.792929)
			(xy 91.022268 -120.91073) (xy 91.038116 -121.02984) (xy 91.046058 -121.149736) (xy 91.046554 -121.209816)
			(xy 95.032841 -121.209816) (xy 95.036814 -121.089722) (xy 95.048715 -120.970154) (xy 95.068493 -120.851634)
			(xy 95.09606 -120.734679) (xy 95.131297 -120.619803) (xy 95.174049 -120.507506) (xy 95.224129 -120.398281)
			(xy 95.281318 -120.292604) (xy 95.345367 -120.190938) (xy 95.415995 -120.093727) (xy 95.492893 -120.001397)
			(xy 95.575725 -119.91435) (xy 95.664129 -119.832969) (xy 95.757718 -119.757607) (xy 95.856084 -119.688597)
			(xy 95.958795 -119.626238) (xy 96.065403 -119.570803) (xy 96.175442 -119.522536) (xy 96.28843 -119.481646)
			(xy 96.403873 -119.448314) (xy 96.521267 -119.422684) (xy 96.640098 -119.404869) (xy 96.759847 -119.394946)
			(xy 96.87999 -119.392959) (xy 97.000001 -119.398917) (xy 97.119357 -119.412794) (xy 97.237534 -119.434528)
			(xy 97.354016 -119.464026) (xy 97.468294 -119.501157) (xy 97.579869 -119.54576) (xy 97.688251 -119.597639)
			(xy 97.792968 -119.656568) (xy 97.893561 -119.722289) (xy 97.989591 -119.794514) (xy 98.080638 -119.872928)
			(xy 98.166303 -119.957188) (xy 98.246212 -120.046926) (xy 98.320015 -120.141748) (xy 98.38739 -120.241241)
			(xy 98.448042 -120.34497) (xy 98.501706 -120.45248) (xy 98.548148 -120.563301) (xy 98.587163 -120.67695)
			(xy 98.618583 -120.792929) (xy 98.642268 -120.91073) (xy 98.658116 -121.02984) (xy 98.666058 -121.149736)
			(xy 98.666554 -121.209816) (xy 98.66613 -121.261212) (xy 103.161842 -121.261212) (xy 103.161842 -121.15842)
			(xy 103.169907 -121.055946) (xy 103.185987 -120.954421) (xy 103.209983 -120.85447) (xy 103.241748 -120.75671)
			(xy 103.281084 -120.661743) (xy 103.32775 -120.570156) (xy 103.381458 -120.482512) (xy 103.441877 -120.399352)
			(xy 103.508635 -120.321189) (xy 103.581319 -120.248505) (xy 103.659482 -120.181747) (xy 103.742642 -120.121328)
			(xy 103.830286 -120.06762) (xy 103.921873 -120.020954) (xy 104.01684 -119.981618) (xy 104.1146 -119.949853)
			(xy 104.214551 -119.925857) (xy 104.316076 -119.909777) (xy 104.41855 -119.901712) (xy 104.521342 -119.901712)
			(xy 104.623816 -119.909777) (xy 104.725341 -119.925857) (xy 104.825292 -119.949853) (xy 104.923052 -119.981618)
			(xy 105.018019 -120.020954) (xy 105.109606 -120.06762) (xy 105.19725 -120.121328) (xy 105.28041 -120.181747)
			(xy 105.358573 -120.248505) (xy 105.431257 -120.321189) (xy 105.498015 -120.399352) (xy 105.558434 -120.482512)
			(xy 105.612142 -120.570156) (xy 105.658808 -120.661743) (xy 105.698144 -120.75671) (xy 105.729909 -120.85447)
			(xy 105.753905 -120.954421) (xy 105.769985 -121.055946) (xy 105.77805 -121.15842) (xy 105.778554 -121.209816)
			(xy 127.413015 -121.209816) (xy 127.416988 -121.089722) (xy 127.428889 -120.970154) (xy 127.448667 -120.851634)
			(xy 127.476234 -120.734679) (xy 127.511471 -120.619803) (xy 127.554223 -120.507506) (xy 127.604303 -120.398281)
			(xy 127.661492 -120.292604) (xy 127.725541 -120.190938) (xy 127.796169 -120.093727) (xy 127.873067 -120.001397)
			(xy 127.955899 -119.91435) (xy 128.044303 -119.832969) (xy 128.137892 -119.757607) (xy 128.236258 -119.688597)
			(xy 128.338969 -119.626238) (xy 128.445577 -119.570803) (xy 128.555616 -119.522536) (xy 128.668604 -119.481646)
			(xy 128.784047 -119.448314) (xy 128.901441 -119.422684) (xy 129.020272 -119.404869) (xy 129.140021 -119.394946)
			(xy 129.260164 -119.392959) (xy 129.380175 -119.398917) (xy 129.499531 -119.412794) (xy 129.617708 -119.434528)
			(xy 129.73419 -119.464026) (xy 129.848468 -119.501157) (xy 129.960043 -119.54576) (xy 130.068425 -119.597639)
			(xy 130.173142 -119.656568) (xy 130.273735 -119.722289) (xy 130.369765 -119.794514) (xy 130.460812 -119.872928)
			(xy 130.546477 -119.957188) (xy 130.626386 -120.046926) (xy 130.700189 -120.141748) (xy 130.767564 -120.241241)
			(xy 130.828216 -120.34497) (xy 130.88188 -120.45248) (xy 130.928322 -120.563301) (xy 130.967337 -120.67695)
			(xy 130.998757 -120.792929) (xy 131.022442 -120.91073) (xy 131.03829 -121.02984) (xy 131.046232 -121.149736)
			(xy 131.046728 -121.209816) (xy 135.033015 -121.209816) (xy 135.036988 -121.089722) (xy 135.048889 -120.970154)
			(xy 135.068667 -120.851634) (xy 135.096234 -120.734679) (xy 135.131471 -120.619803) (xy 135.174223 -120.507506)
			(xy 135.224303 -120.398281) (xy 135.281492 -120.292604) (xy 135.345541 -120.190938) (xy 135.416169 -120.093727)
			(xy 135.493067 -120.001397) (xy 135.575899 -119.91435) (xy 135.664303 -119.832969) (xy 135.757892 -119.757607)
			(xy 135.856258 -119.688597) (xy 135.958969 -119.626238) (xy 136.065577 -119.570803) (xy 136.175616 -119.522536)
			(xy 136.288604 -119.481646) (xy 136.404047 -119.448314) (xy 136.521441 -119.422684) (xy 136.640272 -119.404869)
			(xy 136.760021 -119.394946) (xy 136.880164 -119.392959) (xy 137.000175 -119.398917) (xy 137.119531 -119.412794)
			(xy 137.237708 -119.434528) (xy 137.35419 -119.464026) (xy 137.468468 -119.501157) (xy 137.580043 -119.54576)
			(xy 137.688425 -119.597639) (xy 137.793142 -119.656568) (xy 137.893735 -119.722289) (xy 137.989765 -119.794514)
			(xy 138.080812 -119.872928) (xy 138.166477 -119.957188) (xy 138.246386 -120.046926) (xy 138.320189 -120.141748)
			(xy 138.387564 -120.241241) (xy 138.448216 -120.34497) (xy 138.50188 -120.45248) (xy 138.548322 -120.563301)
			(xy 138.587337 -120.67695) (xy 138.618757 -120.792929) (xy 138.642442 -120.91073) (xy 138.65829 -121.02984)
			(xy 138.666232 -121.149736) (xy 138.666728 -121.209816) (xy 138.666304 -121.261212) (xy 143.162016 -121.261212)
			(xy 143.162016 -121.15842) (xy 143.170081 -121.055946) (xy 143.186161 -120.954421) (xy 143.210157 -120.85447)
			(xy 143.241922 -120.75671) (xy 143.281258 -120.661743) (xy 143.327924 -120.570156) (xy 143.381632 -120.482512)
			(xy 143.442051 -120.399352) (xy 143.508809 -120.321189) (xy 143.581493 -120.248505) (xy 143.659656 -120.181747)
			(xy 143.742816 -120.121328) (xy 143.83046 -120.06762) (xy 143.922047 -120.020954) (xy 144.017014 -119.981618)
			(xy 144.114774 -119.949853) (xy 144.214725 -119.925857) (xy 144.31625 -119.909777) (xy 144.418724 -119.901712)
			(xy 144.521516 -119.901712) (xy 144.62399 -119.909777) (xy 144.725515 -119.925857) (xy 144.825466 -119.949853)
			(xy 144.923226 -119.981618) (xy 145.018193 -120.020954) (xy 145.10978 -120.06762) (xy 145.197424 -120.121328)
			(xy 145.280584 -120.181747) (xy 145.358747 -120.248505) (xy 145.431431 -120.321189) (xy 145.498189 -120.399352)
			(xy 145.558608 -120.482512) (xy 145.612316 -120.570156) (xy 145.658982 -120.661743) (xy 145.698318 -120.75671)
			(xy 145.730083 -120.85447) (xy 145.754079 -120.954421) (xy 145.770159 -121.055946) (xy 145.778224 -121.15842)
			(xy 145.778728 -121.209816) (xy 167.413189 -121.209816) (xy 167.417162 -121.089722) (xy 167.429063 -120.970154)
			(xy 167.448841 -120.851634) (xy 167.476408 -120.734679) (xy 167.511645 -120.619803) (xy 167.554397 -120.507506)
			(xy 167.604477 -120.398281) (xy 167.661666 -120.292604) (xy 167.725715 -120.190938) (xy 167.796343 -120.093727)
			(xy 167.873241 -120.001397) (xy 167.956073 -119.91435) (xy 168.044477 -119.832969) (xy 168.138066 -119.757607)
			(xy 168.236432 -119.688597) (xy 168.339143 -119.626238) (xy 168.445751 -119.570803) (xy 168.55579 -119.522536)
			(xy 168.668778 -119.481646) (xy 168.784221 -119.448314) (xy 168.901615 -119.422684) (xy 169.020446 -119.404869)
			(xy 169.140195 -119.394946) (xy 169.260338 -119.392959) (xy 169.380349 -119.398917) (xy 169.499705 -119.412794)
			(xy 169.617882 -119.434528) (xy 169.734364 -119.464026) (xy 169.848642 -119.501157) (xy 169.960217 -119.54576)
			(xy 170.068599 -119.597639) (xy 170.173316 -119.656568) (xy 170.273909 -119.722289) (xy 170.369939 -119.794514)
			(xy 170.460986 -119.872928) (xy 170.546651 -119.957188) (xy 170.62656 -120.046926) (xy 170.700363 -120.141748)
			(xy 170.767738 -120.241241) (xy 170.82839 -120.34497) (xy 170.882054 -120.45248) (xy 170.928496 -120.563301)
			(xy 170.967511 -120.67695) (xy 170.998931 -120.792929) (xy 171.022616 -120.91073) (xy 171.038464 -121.02984)
			(xy 171.046406 -121.149736) (xy 171.046902 -121.209816) (xy 175.033189 -121.209816) (xy 175.037162 -121.089722)
			(xy 175.049063 -120.970154) (xy 175.068841 -120.851634) (xy 175.096408 -120.734679) (xy 175.131645 -120.619803)
			(xy 175.174397 -120.507506) (xy 175.224477 -120.398281) (xy 175.281666 -120.292604) (xy 175.345715 -120.190938)
			(xy 175.416343 -120.093727) (xy 175.493241 -120.001397) (xy 175.576073 -119.91435) (xy 175.664477 -119.832969)
			(xy 175.758066 -119.757607) (xy 175.856432 -119.688597) (xy 175.959143 -119.626238) (xy 176.065751 -119.570803)
			(xy 176.17579 -119.522536) (xy 176.288778 -119.481646) (xy 176.404221 -119.448314) (xy 176.521615 -119.422684)
			(xy 176.640446 -119.404869) (xy 176.760195 -119.394946) (xy 176.880338 -119.392959) (xy 177.000349 -119.398917)
			(xy 177.119705 -119.412794) (xy 177.237882 -119.434528) (xy 177.354364 -119.464026) (xy 177.468642 -119.501157)
			(xy 177.580217 -119.54576) (xy 177.688599 -119.597639) (xy 177.793316 -119.656568) (xy 177.893909 -119.722289)
			(xy 177.989939 -119.794514) (xy 178.080986 -119.872928) (xy 178.166651 -119.957188) (xy 178.24656 -120.046926)
			(xy 178.320363 -120.141748) (xy 178.387738 -120.241241) (xy 178.44839 -120.34497) (xy 178.502054 -120.45248)
			(xy 178.548496 -120.563301) (xy 178.587511 -120.67695) (xy 178.618931 -120.792929) (xy 178.642616 -120.91073)
			(xy 178.658464 -121.02984) (xy 178.666406 -121.149736) (xy 178.666902 -121.209816) (xy 178.666478 -121.261212)
			(xy 183.16219 -121.261212) (xy 183.16219 -121.15842) (xy 183.170255 -121.055946) (xy 183.186335 -120.954421)
			(xy 183.210331 -120.85447) (xy 183.242096 -120.75671) (xy 183.281432 -120.661743) (xy 183.328098 -120.570156)
			(xy 183.381806 -120.482512) (xy 183.442225 -120.399352) (xy 183.508983 -120.321189) (xy 183.581667 -120.248505)
			(xy 183.65983 -120.181747) (xy 183.74299 -120.121328) (xy 183.830634 -120.06762) (xy 183.922221 -120.020954)
			(xy 184.017188 -119.981618) (xy 184.114948 -119.949853) (xy 184.214899 -119.925857) (xy 184.316424 -119.909777)
			(xy 184.418898 -119.901712) (xy 184.52169 -119.901712) (xy 184.624164 -119.909777) (xy 184.725689 -119.925857)
			(xy 184.82564 -119.949853) (xy 184.9234 -119.981618) (xy 185.018367 -120.020954) (xy 185.109954 -120.06762)
			(xy 185.197598 -120.121328) (xy 185.280758 -120.181747) (xy 185.358921 -120.248505) (xy 185.431605 -120.321189)
			(xy 185.498363 -120.399352) (xy 185.558782 -120.482512) (xy 185.61249 -120.570156) (xy 185.659156 -120.661743)
			(xy 185.698492 -120.75671) (xy 185.730257 -120.85447) (xy 185.754253 -120.954421) (xy 185.770333 -121.055946)
			(xy 185.778398 -121.15842) (xy 185.778902 -121.209816) (xy 185.778398 -121.261212) (xy 185.770333 -121.363686)
			(xy 185.754253 -121.465211) (xy 185.730257 -121.565162) (xy 185.698492 -121.662922) (xy 185.659156 -121.757889)
			(xy 185.61249 -121.849476) (xy 185.558782 -121.93712) (xy 185.498363 -122.02028) (xy 185.431605 -122.098443)
			(xy 185.358921 -122.171127) (xy 185.280758 -122.237885) (xy 185.197598 -122.298304) (xy 185.109954 -122.352012)
			(xy 185.018367 -122.398678) (xy 184.9234 -122.438014) (xy 184.82564 -122.469779) (xy 184.725689 -122.493775)
			(xy 184.624164 -122.509855) (xy 184.52169 -122.51792) (xy 184.418898 -122.51792) (xy 184.316424 -122.509855)
			(xy 184.214899 -122.493775) (xy 184.114948 -122.469779) (xy 184.017188 -122.438014) (xy 183.922221 -122.398678)
			(xy 183.830634 -122.352012) (xy 183.74299 -122.298304) (xy 183.65983 -122.237885) (xy 183.581667 -122.171127)
			(xy 183.508983 -122.098443) (xy 183.442225 -122.02028) (xy 183.381806 -121.93712) (xy 183.328098 -121.849476)
			(xy 183.281432 -121.757889) (xy 183.242096 -121.662922) (xy 183.210331 -121.565162) (xy 183.186335 -121.465211)
			(xy 183.170255 -121.363686) (xy 183.16219 -121.261212) (xy 178.666478 -121.261212) (xy 178.666406 -121.269896)
			(xy 178.658464 -121.389792) (xy 178.642616 -121.508902) (xy 178.618931 -121.626703) (xy 178.587511 -121.742682)
			(xy 178.548496 -121.856331) (xy 178.502054 -121.967152) (xy 178.44839 -122.074662) (xy 178.387738 -122.178391)
			(xy 178.320363 -122.277884) (xy 178.24656 -122.372706) (xy 178.166651 -122.462444) (xy 178.080986 -122.546704)
			(xy 177.989939 -122.625118) (xy 177.893909 -122.697343) (xy 177.793316 -122.763064) (xy 177.688599 -122.821993)
			(xy 177.580217 -122.873872) (xy 177.468642 -122.918475) (xy 177.354364 -122.955606) (xy 177.237882 -122.985104)
			(xy 177.119705 -123.006838) (xy 177.000349 -123.020715) (xy 176.880338 -123.026673) (xy 176.760195 -123.024686)
			(xy 176.640446 -123.014763) (xy 176.521615 -122.996948) (xy 176.404221 -122.971318) (xy 176.288778 -122.937986)
			(xy 176.17579 -122.897096) (xy 176.065751 -122.848829) (xy 175.959143 -122.793394) (xy 175.856432 -122.731035)
			(xy 175.758066 -122.662025) (xy 175.664477 -122.586663) (xy 175.576073 -122.505282) (xy 175.493241 -122.418235)
			(xy 175.416343 -122.325905) (xy 175.345715 -122.228694) (xy 175.281666 -122.127028) (xy 175.224477 -122.021351)
			(xy 175.174397 -121.912126) (xy 175.131645 -121.799829) (xy 175.096408 -121.684953) (xy 175.068841 -121.567998)
			(xy 175.049063 -121.449478) (xy 175.037162 -121.32991) (xy 175.033189 -121.209816) (xy 171.046902 -121.209816)
			(xy 171.046406 -121.269896) (xy 171.038464 -121.389792) (xy 171.022616 -121.508902) (xy 170.998931 -121.626703)
			(xy 170.967511 -121.742682) (xy 170.928496 -121.856331) (xy 170.882054 -121.967152) (xy 170.82839 -122.074662)
			(xy 170.767738 -122.178391) (xy 170.700363 -122.277884) (xy 170.62656 -122.372706) (xy 170.546651 -122.462444)
			(xy 170.460986 -122.546704) (xy 170.369939 -122.625118) (xy 170.273909 -122.697343) (xy 170.173316 -122.763064)
			(xy 170.068599 -122.821993) (xy 169.960217 -122.873872) (xy 169.848642 -122.918475) (xy 169.734364 -122.955606)
			(xy 169.617882 -122.985104) (xy 169.499705 -123.006838) (xy 169.380349 -123.020715) (xy 169.260338 -123.026673)
			(xy 169.140195 -123.024686) (xy 169.020446 -123.014763) (xy 168.901615 -122.996948) (xy 168.784221 -122.971318)
			(xy 168.668778 -122.937986) (xy 168.55579 -122.897096) (xy 168.445751 -122.848829) (xy 168.339143 -122.793394)
			(xy 168.236432 -122.731035) (xy 168.138066 -122.662025) (xy 168.044477 -122.586663) (xy 167.956073 -122.505282)
			(xy 167.873241 -122.418235) (xy 167.796343 -122.325905) (xy 167.725715 -122.228694) (xy 167.661666 -122.127028)
			(xy 167.604477 -122.021351) (xy 167.554397 -121.912126) (xy 167.511645 -121.799829) (xy 167.476408 -121.684953)
			(xy 167.448841 -121.567998) (xy 167.429063 -121.449478) (xy 167.417162 -121.32991) (xy 167.413189 -121.209816)
			(xy 145.778728 -121.209816) (xy 145.778224 -121.261212) (xy 145.770159 -121.363686) (xy 145.754079 -121.465211)
			(xy 145.730083 -121.565162) (xy 145.698318 -121.662922) (xy 145.658982 -121.757889) (xy 145.612316 -121.849476)
			(xy 145.558608 -121.93712) (xy 145.498189 -122.02028) (xy 145.431431 -122.098443) (xy 145.358747 -122.171127)
			(xy 145.280584 -122.237885) (xy 145.197424 -122.298304) (xy 145.10978 -122.352012) (xy 145.018193 -122.398678)
			(xy 144.923226 -122.438014) (xy 144.825466 -122.469779) (xy 144.725515 -122.493775) (xy 144.62399 -122.509855)
			(xy 144.521516 -122.51792) (xy 144.418724 -122.51792) (xy 144.31625 -122.509855) (xy 144.214725 -122.493775)
			(xy 144.114774 -122.469779) (xy 144.017014 -122.438014) (xy 143.922047 -122.398678) (xy 143.83046 -122.352012)
			(xy 143.742816 -122.298304) (xy 143.659656 -122.237885) (xy 143.581493 -122.171127) (xy 143.508809 -122.098443)
			(xy 143.442051 -122.02028) (xy 143.381632 -121.93712) (xy 143.327924 -121.849476) (xy 143.281258 -121.757889)
			(xy 143.241922 -121.662922) (xy 143.210157 -121.565162) (xy 143.186161 -121.465211) (xy 143.170081 -121.363686)
			(xy 143.162016 -121.261212) (xy 138.666304 -121.261212) (xy 138.666232 -121.269896) (xy 138.65829 -121.389792)
			(xy 138.642442 -121.508902) (xy 138.618757 -121.626703) (xy 138.587337 -121.742682) (xy 138.548322 -121.856331)
			(xy 138.50188 -121.967152) (xy 138.448216 -122.074662) (xy 138.387564 -122.178391) (xy 138.320189 -122.277884)
			(xy 138.246386 -122.372706) (xy 138.166477 -122.462444) (xy 138.080812 -122.546704) (xy 137.989765 -122.625118)
			(xy 137.893735 -122.697343) (xy 137.793142 -122.763064) (xy 137.688425 -122.821993) (xy 137.580043 -122.873872)
			(xy 137.468468 -122.918475) (xy 137.35419 -122.955606) (xy 137.237708 -122.985104) (xy 137.119531 -123.006838)
			(xy 137.000175 -123.020715) (xy 136.880164 -123.026673) (xy 136.760021 -123.024686) (xy 136.640272 -123.014763)
			(xy 136.521441 -122.996948) (xy 136.404047 -122.971318) (xy 136.288604 -122.937986) (xy 136.175616 -122.897096)
			(xy 136.065577 -122.848829) (xy 135.958969 -122.793394) (xy 135.856258 -122.731035) (xy 135.757892 -122.662025)
			(xy 135.664303 -122.586663) (xy 135.575899 -122.505282) (xy 135.493067 -122.418235) (xy 135.416169 -122.325905)
			(xy 135.345541 -122.228694) (xy 135.281492 -122.127028) (xy 135.224303 -122.021351) (xy 135.174223 -121.912126)
			(xy 135.131471 -121.799829) (xy 135.096234 -121.684953) (xy 135.068667 -121.567998) (xy 135.048889 -121.449478)
			(xy 135.036988 -121.32991) (xy 135.033015 -121.209816) (xy 131.046728 -121.209816) (xy 131.046232 -121.269896)
			(xy 131.03829 -121.389792) (xy 131.022442 -121.508902) (xy 130.998757 -121.626703) (xy 130.967337 -121.742682)
			(xy 130.928322 -121.856331) (xy 130.88188 -121.967152) (xy 130.828216 -122.074662) (xy 130.767564 -122.178391)
			(xy 130.700189 -122.277884) (xy 130.626386 -122.372706) (xy 130.546477 -122.462444) (xy 130.460812 -122.546704)
			(xy 130.369765 -122.625118) (xy 130.273735 -122.697343) (xy 130.173142 -122.763064) (xy 130.068425 -122.821993)
			(xy 129.960043 -122.873872) (xy 129.848468 -122.918475) (xy 129.73419 -122.955606) (xy 129.617708 -122.985104)
			(xy 129.499531 -123.006838) (xy 129.380175 -123.020715) (xy 129.260164 -123.026673) (xy 129.140021 -123.024686)
			(xy 129.020272 -123.014763) (xy 128.901441 -122.996948) (xy 128.784047 -122.971318) (xy 128.668604 -122.937986)
			(xy 128.555616 -122.897096) (xy 128.445577 -122.848829) (xy 128.338969 -122.793394) (xy 128.236258 -122.731035)
			(xy 128.137892 -122.662025) (xy 128.044303 -122.586663) (xy 127.955899 -122.505282) (xy 127.873067 -122.418235)
			(xy 127.796169 -122.325905) (xy 127.725541 -122.228694) (xy 127.661492 -122.127028) (xy 127.604303 -122.021351)
			(xy 127.554223 -121.912126) (xy 127.511471 -121.799829) (xy 127.476234 -121.684953) (xy 127.448667 -121.567998)
			(xy 127.428889 -121.449478) (xy 127.416988 -121.32991) (xy 127.413015 -121.209816) (xy 105.778554 -121.209816)
			(xy 105.77805 -121.261212) (xy 105.769985 -121.363686) (xy 105.753905 -121.465211) (xy 105.729909 -121.565162)
			(xy 105.698144 -121.662922) (xy 105.658808 -121.757889) (xy 105.612142 -121.849476) (xy 105.558434 -121.93712)
			(xy 105.498015 -122.02028) (xy 105.431257 -122.098443) (xy 105.358573 -122.171127) (xy 105.28041 -122.237885)
			(xy 105.19725 -122.298304) (xy 105.109606 -122.352012) (xy 105.018019 -122.398678) (xy 104.923052 -122.438014)
			(xy 104.825292 -122.469779) (xy 104.725341 -122.493775) (xy 104.623816 -122.509855) (xy 104.521342 -122.51792)
			(xy 104.41855 -122.51792) (xy 104.316076 -122.509855) (xy 104.214551 -122.493775) (xy 104.1146 -122.469779)
			(xy 104.01684 -122.438014) (xy 103.921873 -122.398678) (xy 103.830286 -122.352012) (xy 103.742642 -122.298304)
			(xy 103.659482 -122.237885) (xy 103.581319 -122.171127) (xy 103.508635 -122.098443) (xy 103.441877 -122.02028)
			(xy 103.381458 -121.93712) (xy 103.32775 -121.849476) (xy 103.281084 -121.757889) (xy 103.241748 -121.662922)
			(xy 103.209983 -121.565162) (xy 103.185987 -121.465211) (xy 103.169907 -121.363686) (xy 103.161842 -121.261212)
			(xy 98.66613 -121.261212) (xy 98.666058 -121.269896) (xy 98.658116 -121.389792) (xy 98.642268 -121.508902)
			(xy 98.618583 -121.626703) (xy 98.587163 -121.742682) (xy 98.548148 -121.856331) (xy 98.501706 -121.967152)
			(xy 98.448042 -122.074662) (xy 98.38739 -122.178391) (xy 98.320015 -122.277884) (xy 98.246212 -122.372706)
			(xy 98.166303 -122.462444) (xy 98.080638 -122.546704) (xy 97.989591 -122.625118) (xy 97.893561 -122.697343)
			(xy 97.792968 -122.763064) (xy 97.688251 -122.821993) (xy 97.579869 -122.873872) (xy 97.468294 -122.918475)
			(xy 97.354016 -122.955606) (xy 97.237534 -122.985104) (xy 97.119357 -123.006838) (xy 97.000001 -123.020715)
			(xy 96.87999 -123.026673) (xy 96.759847 -123.024686) (xy 96.640098 -123.014763) (xy 96.521267 -122.996948)
			(xy 96.403873 -122.971318) (xy 96.28843 -122.937986) (xy 96.175442 -122.897096) (xy 96.065403 -122.848829)
			(xy 95.958795 -122.793394) (xy 95.856084 -122.731035) (xy 95.757718 -122.662025) (xy 95.664129 -122.586663)
			(xy 95.575725 -122.505282) (xy 95.492893 -122.418235) (xy 95.415995 -122.325905) (xy 95.345367 -122.228694)
			(xy 95.281318 -122.127028) (xy 95.224129 -122.021351) (xy 95.174049 -121.912126) (xy 95.131297 -121.799829)
			(xy 95.09606 -121.684953) (xy 95.068493 -121.567998) (xy 95.048715 -121.449478) (xy 95.036814 -121.32991)
			(xy 95.032841 -121.209816) (xy 91.046554 -121.209816) (xy 91.046058 -121.269896) (xy 91.038116 -121.389792)
			(xy 91.022268 -121.508902) (xy 90.998583 -121.626703) (xy 90.967163 -121.742682) (xy 90.928148 -121.856331)
			(xy 90.881706 -121.967152) (xy 90.828042 -122.074662) (xy 90.76739 -122.178391) (xy 90.700015 -122.277884)
			(xy 90.626212 -122.372706) (xy 90.546303 -122.462444) (xy 90.460638 -122.546704) (xy 90.369591 -122.625118)
			(xy 90.273561 -122.697343) (xy 90.172968 -122.763064) (xy 90.068251 -122.821993) (xy 89.959869 -122.873872)
			(xy 89.848294 -122.918475) (xy 89.734016 -122.955606) (xy 89.617534 -122.985104) (xy 89.499357 -123.006838)
			(xy 89.380001 -123.020715) (xy 89.25999 -123.026673) (xy 89.139847 -123.024686) (xy 89.020098 -123.014763)
			(xy 88.901267 -122.996948) (xy 88.783873 -122.971318) (xy 88.66843 -122.937986) (xy 88.555442 -122.897096)
			(xy 88.445403 -122.848829) (xy 88.338795 -122.793394) (xy 88.236084 -122.731035) (xy 88.137718 -122.662025)
			(xy 88.044129 -122.586663) (xy 87.955725 -122.505282) (xy 87.872893 -122.418235) (xy 87.795995 -122.325905)
			(xy 87.725367 -122.228694) (xy 87.661318 -122.127028) (xy 87.604129 -122.021351) (xy 87.554049 -121.912126)
			(xy 87.511297 -121.799829) (xy 87.47606 -121.684953) (xy 87.448493 -121.567998) (xy 87.428715 -121.449478)
			(xy 87.416814 -121.32991) (xy 87.412841 -121.209816) (xy 65.778634 -121.209816) (xy 65.77813 -121.261212)
			(xy 65.770065 -121.363686) (xy 65.753985 -121.465211) (xy 65.729989 -121.565162) (xy 65.698224 -121.662922)
			(xy 65.658888 -121.757889) (xy 65.612222 -121.849476) (xy 65.558514 -121.93712) (xy 65.498095 -122.02028)
			(xy 65.431337 -122.098443) (xy 65.358653 -122.171127) (xy 65.28049 -122.237885) (xy 65.19733 -122.298304)
			(xy 65.109686 -122.352012) (xy 65.018099 -122.398678) (xy 64.923132 -122.438014) (xy 64.825372 -122.469779)
			(xy 64.725421 -122.493775) (xy 64.623896 -122.509855) (xy 64.521422 -122.51792) (xy 64.41863 -122.51792)
			(xy 64.316156 -122.509855) (xy 64.214631 -122.493775) (xy 64.11468 -122.469779) (xy 64.01692 -122.438014)
			(xy 63.921953 -122.398678) (xy 63.830366 -122.352012) (xy 63.742722 -122.298304) (xy 63.659562 -122.237885)
			(xy 63.581399 -122.171127) (xy 63.508715 -122.098443) (xy 63.441957 -122.02028) (xy 63.381538 -121.93712)
			(xy 63.32783 -121.849476) (xy 63.281164 -121.757889) (xy 63.241828 -121.662922) (xy 63.210063 -121.565162)
			(xy 63.186067 -121.465211) (xy 63.169987 -121.363686) (xy 63.161922 -121.261212) (xy 58.66621 -121.261212)
			(xy 58.666138 -121.269896) (xy 58.658196 -121.389792) (xy 58.642348 -121.508902) (xy 58.618663 -121.626703)
			(xy 58.587243 -121.742682) (xy 58.548228 -121.856331) (xy 58.501786 -121.967152) (xy 58.448122 -122.074662)
			(xy 58.38747 -122.178391) (xy 58.320095 -122.277884) (xy 58.246292 -122.372706) (xy 58.166383 -122.462444)
			(xy 58.080718 -122.546704) (xy 57.989671 -122.625118) (xy 57.893641 -122.697343) (xy 57.793048 -122.763064)
			(xy 57.688331 -122.821993) (xy 57.579949 -122.873872) (xy 57.468374 -122.918475) (xy 57.354096 -122.955606)
			(xy 57.237614 -122.985104) (xy 57.119437 -123.006838) (xy 57.000081 -123.020715) (xy 56.88007 -123.026673)
			(xy 56.759927 -123.024686) (xy 56.640178 -123.014763) (xy 56.521347 -122.996948) (xy 56.403953 -122.971318)
			(xy 56.28851 -122.937986) (xy 56.175522 -122.897096) (xy 56.065483 -122.848829) (xy 55.958875 -122.793394)
			(xy 55.856164 -122.731035) (xy 55.757798 -122.662025) (xy 55.664209 -122.586663) (xy 55.575805 -122.505282)
			(xy 55.492973 -122.418235) (xy 55.416075 -122.325905) (xy 55.345447 -122.228694) (xy 55.281398 -122.127028)
			(xy 55.224209 -122.021351) (xy 55.174129 -121.912126) (xy 55.131377 -121.799829) (xy 55.09614 -121.684953)
			(xy 55.068573 -121.567998) (xy 55.048795 -121.449478) (xy 55.036894 -121.32991) (xy 55.032921 -121.209816)
			(xy 51.046634 -121.209816) (xy 51.046138 -121.269896) (xy 51.038196 -121.389792) (xy 51.022348 -121.508902)
			(xy 50.998663 -121.626703) (xy 50.967243 -121.742682) (xy 50.928228 -121.856331) (xy 50.881786 -121.967152)
			(xy 50.828122 -122.074662) (xy 50.76747 -122.178391) (xy 50.700095 -122.277884) (xy 50.626292 -122.372706)
			(xy 50.546383 -122.462444) (xy 50.460718 -122.546704) (xy 50.369671 -122.625118) (xy 50.273641 -122.697343)
			(xy 50.173048 -122.763064) (xy 50.068331 -122.821993) (xy 49.959949 -122.873872) (xy 49.848374 -122.918475)
			(xy 49.734096 -122.955606) (xy 49.617614 -122.985104) (xy 49.499437 -123.006838) (xy 49.380081 -123.020715)
			(xy 49.26007 -123.026673) (xy 49.139927 -123.024686) (xy 49.020178 -123.014763) (xy 48.901347 -122.996948)
			(xy 48.783953 -122.971318) (xy 48.66851 -122.937986) (xy 48.555522 -122.897096) (xy 48.445483 -122.848829)
			(xy 48.338875 -122.793394) (xy 48.236164 -122.731035) (xy 48.137798 -122.662025) (xy 48.044209 -122.586663)
			(xy 47.955805 -122.505282) (xy 47.872973 -122.418235) (xy 47.796075 -122.325905) (xy 47.725447 -122.228694)
			(xy 47.661398 -122.127028) (xy 47.604209 -122.021351) (xy 47.554129 -121.912126) (xy 47.511377 -121.799829)
			(xy 47.47614 -121.684953) (xy 47.448573 -121.567998) (xy 47.428795 -121.449478) (xy 47.416894 -121.32991)
			(xy 47.412921 -121.209816) (xy 37.531802 -121.209816) (xy 37.531802 -126.492) (xy 44.966872 -126.492)
			(xy 44.970902 -126.407397) (xy 44.982956 -126.32356) (xy 45.002925 -126.241249) (xy 45.030627 -126.161209)
			(xy 45.065812 -126.084164) (xy 45.108162 -126.010813) (xy 45.157292 -125.941819) (xy 45.212758 -125.877808)
			(xy 45.274058 -125.81936) (xy 45.340636 -125.767002) (xy 45.411889 -125.721211) (xy 45.487173 -125.6824)
			(xy 45.565805 -125.650921) (xy 45.647073 -125.627059) (xy 45.730241 -125.61103) (xy 45.814557 -125.60298)
			(xy 45.856906 -125.602492) (xy 45.857414 -125.602492) (xy 45.903746 -125.603096) (xy 45.995904 -125.612768)
			(xy 46.086558 -125.631964) (xy 46.174727 -125.660477) (xy 46.217332 -125.678692) (xy 46.227272 -125.682512)
			(xy 46.24854 -125.682512) (xy 46.25848 -125.678692) (xy 46.301082 -125.660468) (xy 46.38925 -125.631951)
			(xy 46.479906 -125.612759) (xy 46.572066 -125.6031) (xy 46.618398 -125.602492) (xy 46.618906 -125.602492)
			(xy 46.661254 -125.602996) (xy 46.745567 -125.611047) (xy 46.828733 -125.627077) (xy 46.909999 -125.650939)
			(xy 46.988629 -125.682418) (xy 47.06391 -125.721229) (xy 47.135161 -125.767019) (xy 47.201737 -125.819376)
			(xy 47.263034 -125.877823) (xy 47.318499 -125.941833) (xy 47.367627 -126.010825) (xy 47.409975 -126.084174)
			(xy 47.44516 -126.161217) (xy 47.472861 -126.241256) (xy 47.492829 -126.323565) (xy 47.504882 -126.407399)
			(xy 47.508913 -126.492) (xy 57.158872 -126.492) (xy 57.162902 -126.407397) (xy 57.174956 -126.32356)
			(xy 57.194925 -126.241249) (xy 57.222627 -126.161209) (xy 57.257812 -126.084164) (xy 57.300162 -126.010813)
			(xy 57.349292 -125.941819) (xy 57.404758 -125.877808) (xy 57.466058 -125.81936) (xy 57.532636 -125.767002)
			(xy 57.603889 -125.721211) (xy 57.679173 -125.6824) (xy 57.757805 -125.650921) (xy 57.839073 -125.627059)
			(xy 57.922241 -125.61103) (xy 58.006557 -125.60298) (xy 58.048906 -125.602492) (xy 58.049414 -125.602492)
			(xy 58.095746 -125.603096) (xy 58.187904 -125.612768) (xy 58.278558 -125.631964) (xy 58.366727 -125.660477)
			(xy 58.409332 -125.678692) (xy 58.419272 -125.682512) (xy 58.44054 -125.682512) (xy 58.45048 -125.678692)
			(xy 58.493082 -125.660468) (xy 58.58125 -125.631951) (xy 58.671906 -125.612759) (xy 58.764066 -125.6031)
			(xy 58.810398 -125.602492) (xy 58.810906 -125.602492) (xy 58.853254 -125.602996) (xy 58.937567 -125.611047)
			(xy 59.020733 -125.627077) (xy 59.101999 -125.650939) (xy 59.180629 -125.682418) (xy 59.25591 -125.721229)
			(xy 59.327161 -125.767019) (xy 59.393737 -125.819376) (xy 59.455034 -125.877823) (xy 59.510499 -125.941833)
			(xy 59.559627 -126.010825) (xy 59.601975 -126.084174) (xy 59.63716 -126.161217) (xy 59.664861 -126.241256)
			(xy 59.684829 -126.323565) (xy 59.696882 -126.407399) (xy 59.700913 -126.492) (xy 69.350872 -126.492)
			(xy 69.354902 -126.407397) (xy 69.366956 -126.32356) (xy 69.386925 -126.241249) (xy 69.414627 -126.161209)
			(xy 69.449812 -126.084164) (xy 69.492162 -126.010813) (xy 69.541292 -125.941819) (xy 69.596758 -125.877808)
			(xy 69.658058 -125.81936) (xy 69.724636 -125.767002) (xy 69.795889 -125.721211) (xy 69.871173 -125.6824)
			(xy 69.949805 -125.650921) (xy 70.031073 -125.627059) (xy 70.114241 -125.61103) (xy 70.198557 -125.60298)
			(xy 70.240906 -125.602492) (xy 70.241414 -125.602492) (xy 70.287746 -125.603096) (xy 70.379904 -125.612768)
			(xy 70.470558 -125.631964) (xy 70.558727 -125.660477) (xy 70.601332 -125.678692) (xy 70.611272 -125.682512)
			(xy 70.63254 -125.682512) (xy 70.64248 -125.678692) (xy 70.685082 -125.660468) (xy 70.77325 -125.631951)
			(xy 70.863906 -125.612759) (xy 70.956066 -125.6031) (xy 71.002398 -125.602492) (xy 71.002906 -125.602492)
			(xy 71.045254 -125.602996) (xy 71.129567 -125.611047) (xy 71.212733 -125.627077) (xy 71.293999 -125.650939)
			(xy 71.372629 -125.682418) (xy 71.44791 -125.721229) (xy 71.519161 -125.767019) (xy 71.585737 -125.819376)
			(xy 71.647034 -125.877823) (xy 71.702499 -125.941833) (xy 71.751627 -126.010825) (xy 71.793975 -126.084174)
			(xy 71.82916 -126.161217) (xy 71.856861 -126.241256) (xy 71.876829 -126.323565) (xy 71.888882 -126.407399)
			(xy 71.892913 -126.492) (xy 84.966772 -126.492) (xy 84.970802 -126.407396) (xy 84.982857 -126.323558)
			(xy 85.002826 -126.241246) (xy 85.030529 -126.161204) (xy 85.065715 -126.084159) (xy 85.108066 -126.010807)
			(xy 85.157198 -125.941813) (xy 85.212665 -125.877801) (xy 85.273966 -125.819352) (xy 85.340546 -125.766995)
			(xy 85.411801 -125.721204) (xy 85.487086 -125.682394) (xy 85.56572 -125.650916) (xy 85.646989 -125.627055)
			(xy 85.730159 -125.611028) (xy 85.814476 -125.602979) (xy 85.856826 -125.602492) (xy 85.857334 -125.602492)
			(xy 85.903665 -125.603124) (xy 85.995822 -125.612788) (xy 86.086476 -125.631976) (xy 86.174646 -125.66048)
			(xy 86.217252 -125.678692) (xy 86.227192 -125.682512) (xy 86.24846 -125.682512) (xy 86.2584 -125.678692)
			(xy 86.300999 -125.660461) (xy 86.389168 -125.631946) (xy 86.479825 -125.612756) (xy 86.571985 -125.603099)
			(xy 86.618318 -125.602492) (xy 86.618826 -125.602492) (xy 86.661174 -125.602997) (xy 86.745485 -125.61105)
			(xy 86.82865 -125.627081) (xy 86.909914 -125.650944) (xy 86.988542 -125.682424) (xy 87.063821 -125.721235)
			(xy 87.135071 -125.767026) (xy 87.201645 -125.819383) (xy 87.262941 -125.87783) (xy 87.318404 -125.941839)
			(xy 87.367531 -126.010831) (xy 87.409878 -126.08418) (xy 87.445061 -126.161222) (xy 87.472762 -126.241259)
			(xy 87.492729 -126.323567) (xy 87.504783 -126.407401) (xy 87.508813 -126.492) (xy 97.158772 -126.492)
			(xy 97.162802 -126.407396) (xy 97.174857 -126.323558) (xy 97.194826 -126.241246) (xy 97.222529 -126.161204)
			(xy 97.257715 -126.084159) (xy 97.300066 -126.010807) (xy 97.349198 -125.941813) (xy 97.404665 -125.877801)
			(xy 97.465966 -125.819352) (xy 97.532546 -125.766995) (xy 97.603801 -125.721204) (xy 97.679086 -125.682394)
			(xy 97.75772 -125.650916) (xy 97.838989 -125.627055) (xy 97.922159 -125.611028) (xy 98.006476 -125.602979)
			(xy 98.048826 -125.602492) (xy 98.049334 -125.602492) (xy 98.095665 -125.603124) (xy 98.187822 -125.612788)
			(xy 98.278476 -125.631976) (xy 98.366646 -125.66048) (xy 98.409252 -125.678692) (xy 98.419192 -125.682512)
			(xy 98.44046 -125.682512) (xy 98.4504 -125.678692) (xy 98.492999 -125.660461) (xy 98.581168 -125.631946)
			(xy 98.671825 -125.612756) (xy 98.763985 -125.603099) (xy 98.810318 -125.602492) (xy 98.810826 -125.602492)
			(xy 98.853174 -125.602997) (xy 98.937485 -125.61105) (xy 99.02065 -125.627081) (xy 99.101914 -125.650944)
			(xy 99.180542 -125.682424) (xy 99.255821 -125.721235) (xy 99.327071 -125.767026) (xy 99.393645 -125.819383)
			(xy 99.454941 -125.87783) (xy 99.510404 -125.941839) (xy 99.559531 -126.010831) (xy 99.601878 -126.08418)
			(xy 99.637061 -126.161222) (xy 99.664762 -126.241259) (xy 99.684729 -126.323567) (xy 99.696783 -126.407401)
			(xy 99.700813 -126.492) (xy 109.350772 -126.492) (xy 109.354802 -126.407396) (xy 109.366857 -126.323558)
			(xy 109.386826 -126.241246) (xy 109.414529 -126.161204) (xy 109.449715 -126.084159) (xy 109.492066 -126.010807)
			(xy 109.541198 -125.941813) (xy 109.596665 -125.877801) (xy 109.657966 -125.819352) (xy 109.724546 -125.766995)
			(xy 109.795801 -125.721204) (xy 109.871086 -125.682394) (xy 109.94972 -125.650916) (xy 110.030989 -125.627055)
			(xy 110.114159 -125.611028) (xy 110.198476 -125.602979) (xy 110.240826 -125.602492) (xy 110.241334 -125.602492)
			(xy 110.287665 -125.603124) (xy 110.379822 -125.612788) (xy 110.470476 -125.631976) (xy 110.558646 -125.66048)
			(xy 110.601252 -125.678692) (xy 110.611192 -125.682512) (xy 110.63246 -125.682512) (xy 110.6424 -125.678692)
			(xy 110.684999 -125.660461) (xy 110.773168 -125.631946) (xy 110.863825 -125.612756) (xy 110.955985 -125.603099)
			(xy 111.002318 -125.602492) (xy 111.002826 -125.602492) (xy 111.045174 -125.602997) (xy 111.129485 -125.61105)
			(xy 111.21265 -125.627081) (xy 111.293914 -125.650944) (xy 111.372542 -125.682424) (xy 111.447821 -125.721235)
			(xy 111.519071 -125.767026) (xy 111.585645 -125.819383) (xy 111.646941 -125.87783) (xy 111.702404 -125.941839)
			(xy 111.751531 -126.010831) (xy 111.793878 -126.08418) (xy 111.829061 -126.161222) (xy 111.856762 -126.241259)
			(xy 111.876729 -126.323567) (xy 111.888783 -126.407401) (xy 111.892813 -126.492) (xy 124.966988 -126.492)
			(xy 124.971018 -126.407399) (xy 124.983071 -126.323564) (xy 125.003039 -126.241255) (xy 125.030741 -126.161216)
			(xy 125.065925 -126.084173) (xy 125.108274 -126.010823) (xy 125.157403 -125.941831) (xy 125.212868 -125.877821)
			(xy 125.274166 -125.819373) (xy 125.340742 -125.767017) (xy 125.411994 -125.721227) (xy 125.487275 -125.682416)
			(xy 125.565905 -125.650937) (xy 125.647172 -125.627076) (xy 125.730338 -125.611047) (xy 125.814652 -125.602996)
			(xy 125.857 -125.602492) (xy 125.857508 -125.602492) (xy 125.90384 -125.603098) (xy 125.995998 -125.612769)
			(xy 126.086652 -125.631965) (xy 126.174821 -125.660477) (xy 126.217426 -125.678692) (xy 126.227366 -125.682512)
			(xy 126.248634 -125.682512) (xy 126.258574 -125.678692) (xy 126.301177 -125.66047) (xy 126.389344 -125.631952)
			(xy 126.48 -125.61276) (xy 126.57216 -125.6031) (xy 126.618492 -125.602492) (xy 126.619 -125.602492)
			(xy 126.661348 -125.602996) (xy 126.745662 -125.611047) (xy 126.828828 -125.627076) (xy 126.910095 -125.650937)
			(xy 126.988725 -125.682416) (xy 127.064006 -125.721227) (xy 127.135258 -125.767017) (xy 127.201834 -125.819373)
			(xy 127.263132 -125.877821) (xy 127.318597 -125.941831) (xy 127.367726 -126.010823) (xy 127.410075 -126.084173)
			(xy 127.445259 -126.161216) (xy 127.472961 -126.241255) (xy 127.492929 -126.323564) (xy 127.504982 -126.407399)
			(xy 127.509013 -126.492) (xy 137.158988 -126.492) (xy 137.163018 -126.407399) (xy 137.175071 -126.323564)
			(xy 137.195039 -126.241255) (xy 137.222741 -126.161216) (xy 137.257925 -126.084173) (xy 137.300274 -126.010823)
			(xy 137.349403 -125.941831) (xy 137.404868 -125.877821) (xy 137.466166 -125.819373) (xy 137.532742 -125.767017)
			(xy 137.603994 -125.721227) (xy 137.679275 -125.682416) (xy 137.757905 -125.650937) (xy 137.839172 -125.627076)
			(xy 137.922338 -125.611047) (xy 138.006652 -125.602996) (xy 138.049 -125.602492) (xy 138.049508 -125.602492)
			(xy 138.09584 -125.603098) (xy 138.187998 -125.612769) (xy 138.278652 -125.631965) (xy 138.366821 -125.660477)
			(xy 138.409426 -125.678692) (xy 138.419366 -125.682512) (xy 138.440634 -125.682512) (xy 138.450574 -125.678692)
			(xy 138.493177 -125.66047) (xy 138.581344 -125.631952) (xy 138.672 -125.61276) (xy 138.76416 -125.6031)
			(xy 138.810492 -125.602492) (xy 138.811 -125.602492) (xy 138.853348 -125.602996) (xy 138.937662 -125.611047)
			(xy 139.020828 -125.627076) (xy 139.102095 -125.650937) (xy 139.180725 -125.682416) (xy 139.256006 -125.721227)
			(xy 139.327258 -125.767017) (xy 139.393834 -125.819373) (xy 139.455132 -125.877821) (xy 139.510597 -125.941831)
			(xy 139.559726 -126.010823) (xy 139.602075 -126.084173) (xy 139.637259 -126.161216) (xy 139.664961 -126.241255)
			(xy 139.684929 -126.323564) (xy 139.696982 -126.407399) (xy 139.701013 -126.492) (xy 149.350988 -126.492)
			(xy 149.355018 -126.407399) (xy 149.367071 -126.323564) (xy 149.387039 -126.241255) (xy 149.414741 -126.161216)
			(xy 149.449925 -126.084173) (xy 149.492274 -126.010823) (xy 149.541403 -125.941831) (xy 149.596868 -125.877821)
			(xy 149.658166 -125.819373) (xy 149.724742 -125.767017) (xy 149.795994 -125.721227) (xy 149.871275 -125.682416)
			(xy 149.949905 -125.650937) (xy 150.031172 -125.627076) (xy 150.114338 -125.611047) (xy 150.198652 -125.602996)
			(xy 150.241 -125.602492) (xy 150.241508 -125.602492) (xy 150.28784 -125.603098) (xy 150.379998 -125.612769)
			(xy 150.470652 -125.631965) (xy 150.558821 -125.660477) (xy 150.601426 -125.678692) (xy 150.611366 -125.682512)
			(xy 150.632634 -125.682512) (xy 150.642574 -125.678692) (xy 150.685177 -125.66047) (xy 150.773344 -125.631952)
			(xy 150.864 -125.61276) (xy 150.95616 -125.6031) (xy 151.002492 -125.602492) (xy 151.003 -125.602492)
			(xy 151.045348 -125.602996) (xy 151.129662 -125.611047) (xy 151.212828 -125.627076) (xy 151.294095 -125.650937)
			(xy 151.372725 -125.682416) (xy 151.448006 -125.721227) (xy 151.519258 -125.767017) (xy 151.585834 -125.819373)
			(xy 151.647132 -125.877821) (xy 151.702597 -125.941831) (xy 151.751726 -126.010823) (xy 151.794075 -126.084173)
			(xy 151.829259 -126.161216) (xy 151.856961 -126.241255) (xy 151.876929 -126.323564) (xy 151.888982 -126.407399)
			(xy 151.893013 -126.492) (xy 164.967187 -126.492) (xy 164.971217 -126.407401) (xy 164.983271 -126.323567)
			(xy 165.003238 -126.241259) (xy 165.030939 -126.161222) (xy 165.066122 -126.08418) (xy 165.108469 -126.010831)
			(xy 165.157596 -125.941839) (xy 165.213059 -125.87783) (xy 165.274355 -125.819383) (xy 165.340929 -125.767026)
			(xy 165.412179 -125.721235) (xy 165.487458 -125.682424) (xy 165.566086 -125.650944) (xy 165.64735 -125.627081)
			(xy 165.730515 -125.61105) (xy 165.814826 -125.602997) (xy 165.857174 -125.602492) (xy 165.857682 -125.602492)
			(xy 165.904014 -125.603107) (xy 165.996171 -125.612776) (xy 166.086825 -125.631969) (xy 166.174994 -125.660478)
			(xy 166.2176 -125.678692) (xy 166.22754 -125.682512) (xy 166.248808 -125.682512) (xy 166.258748 -125.678692)
			(xy 166.301354 -125.660479) (xy 166.389521 -125.631959) (xy 166.480175 -125.612764) (xy 166.572334 -125.603101)
			(xy 166.618666 -125.602492) (xy 166.619174 -125.602492) (xy 166.661524 -125.602979) (xy 166.745841 -125.611028)
			(xy 166.829011 -125.627055) (xy 166.91028 -125.650916) (xy 166.988914 -125.682394) (xy 167.064199 -125.721204)
			(xy 167.135454 -125.766995) (xy 167.202034 -125.819352) (xy 167.263335 -125.877801) (xy 167.318802 -125.941813)
			(xy 167.367934 -126.010807) (xy 167.410285 -126.084159) (xy 167.445471 -126.161204) (xy 167.473174 -126.241246)
			(xy 167.493143 -126.323558) (xy 167.505198 -126.407396) (xy 167.509228 -126.492) (xy 177.159187 -126.492)
			(xy 177.163217 -126.407401) (xy 177.175271 -126.323567) (xy 177.195238 -126.241259) (xy 177.222939 -126.161222)
			(xy 177.258122 -126.08418) (xy 177.300469 -126.010831) (xy 177.349596 -125.941839) (xy 177.405059 -125.87783)
			(xy 177.466355 -125.819383) (xy 177.532929 -125.767026) (xy 177.604179 -125.721235) (xy 177.679458 -125.682424)
			(xy 177.758086 -125.650944) (xy 177.83935 -125.627081) (xy 177.922515 -125.61105) (xy 178.006826 -125.602997)
			(xy 178.049174 -125.602492) (xy 178.049682 -125.602492) (xy 178.096014 -125.603107) (xy 178.188171 -125.612776)
			(xy 178.278825 -125.631969) (xy 178.366994 -125.660478) (xy 178.4096 -125.678692) (xy 178.41954 -125.682512)
			(xy 178.440808 -125.682512) (xy 178.450748 -125.678692) (xy 178.493354 -125.660479) (xy 178.581521 -125.631959)
			(xy 178.672175 -125.612764) (xy 178.764334 -125.603101) (xy 178.810666 -125.602492) (xy 178.811174 -125.602492)
			(xy 178.853524 -125.602979) (xy 178.937841 -125.611028) (xy 179.021011 -125.627055) (xy 179.10228 -125.650916)
			(xy 179.180914 -125.682394) (xy 179.256199 -125.721204) (xy 179.327454 -125.766995) (xy 179.394034 -125.819352)
			(xy 179.455335 -125.877801) (xy 179.510802 -125.941813) (xy 179.559934 -126.010807) (xy 179.602285 -126.084159)
			(xy 179.637471 -126.161204) (xy 179.665174 -126.241246) (xy 179.685143 -126.323558) (xy 179.697198 -126.407396)
			(xy 179.701228 -126.492) (xy 189.351187 -126.492) (xy 189.355217 -126.407401) (xy 189.367271 -126.323567)
			(xy 189.387238 -126.241259) (xy 189.414939 -126.161222) (xy 189.450122 -126.08418) (xy 189.492469 -126.010831)
			(xy 189.541596 -125.941839) (xy 189.597059 -125.87783) (xy 189.658355 -125.819383) (xy 189.724929 -125.767026)
			(xy 189.796179 -125.721235) (xy 189.871458 -125.682424) (xy 189.950086 -125.650944) (xy 190.03135 -125.627081)
			(xy 190.114515 -125.61105) (xy 190.198826 -125.602997) (xy 190.241174 -125.602492) (xy 190.241682 -125.602492)
			(xy 190.288014 -125.603107) (xy 190.380171 -125.612776) (xy 190.470825 -125.631969) (xy 190.558994 -125.660478)
			(xy 190.6016 -125.678692) (xy 190.61154 -125.682512) (xy 190.632808 -125.682512) (xy 190.642748 -125.678692)
			(xy 190.685354 -125.660479) (xy 190.773521 -125.631959) (xy 190.864175 -125.612764) (xy 190.956334 -125.603101)
			(xy 191.002666 -125.602492) (xy 191.003174 -125.602492) (xy 191.045524 -125.602979) (xy 191.129841 -125.611028)
			(xy 191.213011 -125.627055) (xy 191.29428 -125.650916) (xy 191.372914 -125.682394) (xy 191.448199 -125.721204)
			(xy 191.519454 -125.766995) (xy 191.586034 -125.819352) (xy 191.647335 -125.877801) (xy 191.702802 -125.941813)
			(xy 191.751934 -126.010807) (xy 191.794285 -126.084159) (xy 191.829471 -126.161204) (xy 191.857174 -126.241246)
			(xy 191.877143 -126.323558) (xy 191.889198 -126.407396) (xy 191.893228 -126.492) (xy 191.889198 -126.576604)
			(xy 191.877143 -126.660442) (xy 191.857174 -126.742754) (xy 191.829471 -126.822796) (xy 191.794285 -126.899841)
			(xy 191.751934 -126.973193) (xy 191.702802 -127.042187) (xy 191.647335 -127.106199) (xy 191.586034 -127.164648)
			(xy 191.519454 -127.217005) (xy 191.448199 -127.262796) (xy 191.372914 -127.301606) (xy 191.29428 -127.333084)
			(xy 191.213011 -127.356945) (xy 191.129841 -127.372972) (xy 191.045524 -127.381021) (xy 191.003174 -127.381508)
			(xy 191.002666 -127.381508) (xy 190.956335 -127.380876) (xy 190.864178 -127.371212) (xy 190.773524 -127.352024)
			(xy 190.685354 -127.32352) (xy 190.642748 -127.305308) (xy 190.632808 -127.301488) (xy 190.61154 -127.301488)
			(xy 190.6016 -127.305308) (xy 190.559001 -127.323539) (xy 190.470832 -127.352054) (xy 190.380175 -127.371244)
			(xy 190.288015 -127.380901) (xy 190.241682 -127.381508) (xy 190.241174 -127.381508) (xy 190.198826 -127.381003)
			(xy 190.114515 -127.37295) (xy 190.03135 -127.356919) (xy 189.950086 -127.333056) (xy 189.871458 -127.301576)
			(xy 189.796179 -127.262765) (xy 189.724929 -127.216974) (xy 189.658355 -127.164617) (xy 189.597059 -127.10617)
			(xy 189.541596 -127.042161) (xy 189.492469 -126.973169) (xy 189.450122 -126.89982) (xy 189.414939 -126.822778)
			(xy 189.387238 -126.742741) (xy 189.367271 -126.660433) (xy 189.355217 -126.576599) (xy 189.351187 -126.492)
			(xy 179.701228 -126.492) (xy 179.697198 -126.576604) (xy 179.685143 -126.660442) (xy 179.665174 -126.742754)
			(xy 179.637471 -126.822796) (xy 179.602285 -126.899841) (xy 179.559934 -126.973193) (xy 179.510802 -127.042187)
			(xy 179.455335 -127.106199) (xy 179.394034 -127.164648) (xy 179.327454 -127.217005) (xy 179.256199 -127.262796)
			(xy 179.180914 -127.301606) (xy 179.10228 -127.333084) (xy 179.021011 -127.356945) (xy 178.937841 -127.372972)
			(xy 178.853524 -127.381021) (xy 178.811174 -127.381508) (xy 178.810666 -127.381508) (xy 178.764335 -127.380876)
			(xy 178.672178 -127.371212) (xy 178.581524 -127.352024) (xy 178.493354 -127.32352) (xy 178.450748 -127.305308)
			(xy 178.440808 -127.301488) (xy 178.41954 -127.301488) (xy 178.4096 -127.305308) (xy 178.367001 -127.323539)
			(xy 178.278832 -127.352054) (xy 178.188175 -127.371244) (xy 178.096015 -127.380901) (xy 178.049682 -127.381508)
			(xy 178.049174 -127.381508) (xy 178.006826 -127.381003) (xy 177.922515 -127.37295) (xy 177.83935 -127.356919)
			(xy 177.758086 -127.333056) (xy 177.679458 -127.301576) (xy 177.604179 -127.262765) (xy 177.532929 -127.216974)
			(xy 177.466355 -127.164617) (xy 177.405059 -127.10617) (xy 177.349596 -127.042161) (xy 177.300469 -126.973169)
			(xy 177.258122 -126.89982) (xy 177.222939 -126.822778) (xy 177.195238 -126.742741) (xy 177.175271 -126.660433)
			(xy 177.163217 -126.576599) (xy 177.159187 -126.492) (xy 167.509228 -126.492) (xy 167.505198 -126.576604)
			(xy 167.493143 -126.660442) (xy 167.473174 -126.742754) (xy 167.445471 -126.822796) (xy 167.410285 -126.899841)
			(xy 167.367934 -126.973193) (xy 167.318802 -127.042187) (xy 167.263335 -127.106199) (xy 167.202034 -127.164648)
			(xy 167.135454 -127.217005) (xy 167.064199 -127.262796) (xy 166.988914 -127.301606) (xy 166.91028 -127.333084)
			(xy 166.829011 -127.356945) (xy 166.745841 -127.372972) (xy 166.661524 -127.381021) (xy 166.619174 -127.381508)
			(xy 166.618666 -127.381508) (xy 166.572335 -127.380876) (xy 166.480178 -127.371212) (xy 166.389524 -127.352024)
			(xy 166.301354 -127.32352) (xy 166.258748 -127.305308) (xy 166.248808 -127.301488) (xy 166.22754 -127.301488)
			(xy 166.2176 -127.305308) (xy 166.175001 -127.323539) (xy 166.086832 -127.352054) (xy 165.996175 -127.371244)
			(xy 165.904015 -127.380901) (xy 165.857682 -127.381508) (xy 165.857174 -127.381508) (xy 165.814826 -127.381003)
			(xy 165.730515 -127.37295) (xy 165.64735 -127.356919) (xy 165.566086 -127.333056) (xy 165.487458 -127.301576)
			(xy 165.412179 -127.262765) (xy 165.340929 -127.216974) (xy 165.274355 -127.164617) (xy 165.213059 -127.10617)
			(xy 165.157596 -127.042161) (xy 165.108469 -126.973169) (xy 165.066122 -126.89982) (xy 165.030939 -126.822778)
			(xy 165.003238 -126.742741) (xy 164.983271 -126.660433) (xy 164.971217 -126.576599) (xy 164.967187 -126.492)
			(xy 151.893013 -126.492) (xy 151.888982 -126.576601) (xy 151.876929 -126.660436) (xy 151.856961 -126.742745)
			(xy 151.829259 -126.822784) (xy 151.794075 -126.899827) (xy 151.751726 -126.973177) (xy 151.702597 -127.042169)
			(xy 151.647132 -127.106179) (xy 151.585834 -127.164627) (xy 151.519258 -127.216983) (xy 151.448006 -127.262773)
			(xy 151.372725 -127.301584) (xy 151.294095 -127.333063) (xy 151.212828 -127.356924) (xy 151.129662 -127.372953)
			(xy 151.045348 -127.381004) (xy 151.003 -127.381508) (xy 151.002492 -127.381508) (xy 150.95616 -127.380902)
			(xy 150.864002 -127.371231) (xy 150.773348 -127.352035) (xy 150.685179 -127.323523) (xy 150.642574 -127.305308)
			(xy 150.632634 -127.301488) (xy 150.611366 -127.301488) (xy 150.601426 -127.305308) (xy 150.558823 -127.32353)
			(xy 150.470656 -127.352048) (xy 150.38 -127.37124) (xy 150.28784 -127.3809) (xy 150.241508 -127.381508)
			(xy 150.241 -127.381508) (xy 150.198652 -127.381004) (xy 150.114338 -127.372953) (xy 150.031172 -127.356924)
			(xy 149.949905 -127.333063) (xy 149.871275 -127.301584) (xy 149.795994 -127.262773) (xy 149.724742 -127.216983)
			(xy 149.658166 -127.164627) (xy 149.596868 -127.106179) (xy 149.541403 -127.042169) (xy 149.492274 -126.973177)
			(xy 149.449925 -126.899827) (xy 149.414741 -126.822784) (xy 149.387039 -126.742745) (xy 149.367071 -126.660436)
			(xy 149.355018 -126.576601) (xy 149.350988 -126.492) (xy 139.701013 -126.492) (xy 139.696982 -126.576601)
			(xy 139.684929 -126.660436) (xy 139.664961 -126.742745) (xy 139.637259 -126.822784) (xy 139.602075 -126.899827)
			(xy 139.559726 -126.973177) (xy 139.510597 -127.042169) (xy 139.455132 -127.106179) (xy 139.393834 -127.164627)
			(xy 139.327258 -127.216983) (xy 139.256006 -127.262773) (xy 139.180725 -127.301584) (xy 139.102095 -127.333063)
			(xy 139.020828 -127.356924) (xy 138.937662 -127.372953) (xy 138.853348 -127.381004) (xy 138.811 -127.381508)
			(xy 138.810492 -127.381508) (xy 138.76416 -127.380902) (xy 138.672002 -127.371231) (xy 138.581348 -127.352035)
			(xy 138.493179 -127.323523) (xy 138.450574 -127.305308) (xy 138.440634 -127.301488) (xy 138.419366 -127.301488)
			(xy 138.409426 -127.305308) (xy 138.366823 -127.32353) (xy 138.278656 -127.352048) (xy 138.188 -127.37124)
			(xy 138.09584 -127.3809) (xy 138.049508 -127.381508) (xy 138.049 -127.381508) (xy 138.006652 -127.381004)
			(xy 137.922338 -127.372953) (xy 137.839172 -127.356924) (xy 137.757905 -127.333063) (xy 137.679275 -127.301584)
			(xy 137.603994 -127.262773) (xy 137.532742 -127.216983) (xy 137.466166 -127.164627) (xy 137.404868 -127.106179)
			(xy 137.349403 -127.042169) (xy 137.300274 -126.973177) (xy 137.257925 -126.899827) (xy 137.222741 -126.822784)
			(xy 137.195039 -126.742745) (xy 137.175071 -126.660436) (xy 137.163018 -126.576601) (xy 137.158988 -126.492)
			(xy 127.509013 -126.492) (xy 127.504982 -126.576601) (xy 127.492929 -126.660436) (xy 127.472961 -126.742745)
			(xy 127.445259 -126.822784) (xy 127.410075 -126.899827) (xy 127.367726 -126.973177) (xy 127.318597 -127.042169)
			(xy 127.263132 -127.106179) (xy 127.201834 -127.164627) (xy 127.135258 -127.216983) (xy 127.064006 -127.262773)
			(xy 126.988725 -127.301584) (xy 126.910095 -127.333063) (xy 126.828828 -127.356924) (xy 126.745662 -127.372953)
			(xy 126.661348 -127.381004) (xy 126.619 -127.381508) (xy 126.618492 -127.381508) (xy 126.57216 -127.380902)
			(xy 126.480002 -127.371231) (xy 126.389348 -127.352035) (xy 126.301179 -127.323523) (xy 126.258574 -127.305308)
			(xy 126.248634 -127.301488) (xy 126.227366 -127.301488) (xy 126.217426 -127.305308) (xy 126.174823 -127.32353)
			(xy 126.086656 -127.352048) (xy 125.996 -127.37124) (xy 125.90384 -127.3809) (xy 125.857508 -127.381508)
			(xy 125.857 -127.381508) (xy 125.814652 -127.381004) (xy 125.730338 -127.372953) (xy 125.647172 -127.356924)
			(xy 125.565905 -127.333063) (xy 125.487275 -127.301584) (xy 125.411994 -127.262773) (xy 125.340742 -127.216983)
			(xy 125.274166 -127.164627) (xy 125.212868 -127.106179) (xy 125.157403 -127.042169) (xy 125.108274 -126.973177)
			(xy 125.065925 -126.899827) (xy 125.030741 -126.822784) (xy 125.003039 -126.742745) (xy 124.983071 -126.660436)
			(xy 124.971018 -126.576601) (xy 124.966988 -126.492) (xy 111.892813 -126.492) (xy 111.888783 -126.576599)
			(xy 111.876729 -126.660433) (xy 111.856762 -126.742741) (xy 111.829061 -126.822778) (xy 111.793878 -126.89982)
			(xy 111.751531 -126.973169) (xy 111.702404 -127.042161) (xy 111.646941 -127.10617) (xy 111.585645 -127.164617)
			(xy 111.519071 -127.216974) (xy 111.447821 -127.262765) (xy 111.372542 -127.301576) (xy 111.293914 -127.333056)
			(xy 111.21265 -127.356919) (xy 111.129485 -127.37295) (xy 111.045174 -127.381003) (xy 111.002826 -127.381508)
			(xy 111.002318 -127.381508) (xy 110.955986 -127.380893) (xy 110.863829 -127.371224) (xy 110.773175 -127.352031)
			(xy 110.685006 -127.323522) (xy 110.6424 -127.305308) (xy 110.63246 -127.301488) (xy 110.611192 -127.301488)
			(xy 110.601252 -127.305308) (xy 110.558646 -127.323521) (xy 110.470479 -127.352041) (xy 110.379825 -127.371236)
			(xy 110.287666 -127.380899) (xy 110.241334 -127.381508) (xy 110.240826 -127.381508) (xy 110.198476 -127.381021)
			(xy 110.114159 -127.372972) (xy 110.030989 -127.356945) (xy 109.94972 -127.333084) (xy 109.871086 -127.301606)
			(xy 109.795801 -127.262796) (xy 109.724546 -127.217005) (xy 109.657966 -127.164648) (xy 109.596665 -127.106199)
			(xy 109.541198 -127.042187) (xy 109.492066 -126.973193) (xy 109.449715 -126.899841) (xy 109.414529 -126.822796)
			(xy 109.386826 -126.742754) (xy 109.366857 -126.660442) (xy 109.354802 -126.576604) (xy 109.350772 -126.492)
			(xy 99.700813 -126.492) (xy 99.696783 -126.576599) (xy 99.684729 -126.660433) (xy 99.664762 -126.742741)
			(xy 99.637061 -126.822778) (xy 99.601878 -126.89982) (xy 99.559531 -126.973169) (xy 99.510404 -127.042161)
			(xy 99.454941 -127.10617) (xy 99.393645 -127.164617) (xy 99.327071 -127.216974) (xy 99.255821 -127.262765)
			(xy 99.180542 -127.301576) (xy 99.101914 -127.333056) (xy 99.02065 -127.356919) (xy 98.937485 -127.37295)
			(xy 98.853174 -127.381003) (xy 98.810826 -127.381508) (xy 98.810318 -127.381508) (xy 98.763986 -127.380893)
			(xy 98.671829 -127.371224) (xy 98.581175 -127.352031) (xy 98.493006 -127.323522) (xy 98.4504 -127.305308)
			(xy 98.44046 -127.301488) (xy 98.419192 -127.301488) (xy 98.409252 -127.305308) (xy 98.366646 -127.323521)
			(xy 98.278479 -127.352041) (xy 98.187825 -127.371236) (xy 98.095666 -127.380899) (xy 98.049334 -127.381508)
			(xy 98.048826 -127.381508) (xy 98.006476 -127.381021) (xy 97.922159 -127.372972) (xy 97.838989 -127.356945)
			(xy 97.75772 -127.333084) (xy 97.679086 -127.301606) (xy 97.603801 -127.262796) (xy 97.532546 -127.217005)
			(xy 97.465966 -127.164648) (xy 97.404665 -127.106199) (xy 97.349198 -127.042187) (xy 97.300066 -126.973193)
			(xy 97.257715 -126.899841) (xy 97.222529 -126.822796) (xy 97.194826 -126.742754) (xy 97.174857 -126.660442)
			(xy 97.162802 -126.576604) (xy 97.158772 -126.492) (xy 87.508813 -126.492) (xy 87.504783 -126.576599)
			(xy 87.492729 -126.660433) (xy 87.472762 -126.742741) (xy 87.445061 -126.822778) (xy 87.409878 -126.89982)
			(xy 87.367531 -126.973169) (xy 87.318404 -127.042161) (xy 87.262941 -127.10617) (xy 87.201645 -127.164617)
			(xy 87.135071 -127.216974) (xy 87.063821 -127.262765) (xy 86.988542 -127.301576) (xy 86.909914 -127.333056)
			(xy 86.82865 -127.356919) (xy 86.745485 -127.37295) (xy 86.661174 -127.381003) (xy 86.618826 -127.381508)
			(xy 86.618318 -127.381508) (xy 86.571986 -127.380893) (xy 86.479829 -127.371224) (xy 86.389175 -127.352031)
			(xy 86.301006 -127.323522) (xy 86.2584 -127.305308) (xy 86.24846 -127.301488) (xy 86.227192 -127.301488)
			(xy 86.217252 -127.305308) (xy 86.174646 -127.323521) (xy 86.086479 -127.352041) (xy 85.995825 -127.371236)
			(xy 85.903666 -127.380899) (xy 85.857334 -127.381508) (xy 85.856826 -127.381508) (xy 85.814476 -127.381021)
			(xy 85.730159 -127.372972) (xy 85.646989 -127.356945) (xy 85.56572 -127.333084) (xy 85.487086 -127.301606)
			(xy 85.411801 -127.262796) (xy 85.340546 -127.217005) (xy 85.273966 -127.164648) (xy 85.212665 -127.106199)
			(xy 85.157198 -127.042187) (xy 85.108066 -126.973193) (xy 85.065715 -126.899841) (xy 85.030529 -126.822796)
			(xy 85.002826 -126.742754) (xy 84.982857 -126.660442) (xy 84.970802 -126.576604) (xy 84.966772 -126.492)
			(xy 71.892913 -126.492) (xy 71.888882 -126.576601) (xy 71.876829 -126.660435) (xy 71.856861 -126.742744)
			(xy 71.82916 -126.822783) (xy 71.793975 -126.899826) (xy 71.751627 -126.973175) (xy 71.702499 -127.042167)
			(xy 71.647034 -127.106177) (xy 71.585737 -127.164624) (xy 71.519161 -127.216981) (xy 71.44791 -127.262771)
			(xy 71.372629 -127.301582) (xy 71.293999 -127.333061) (xy 71.212733 -127.356923) (xy 71.129567 -127.372953)
			(xy 71.045254 -127.381004) (xy 71.002906 -127.381508) (xy 71.002398 -127.381508) (xy 70.956066 -127.3809)
			(xy 70.863908 -127.371229) (xy 70.773254 -127.352034) (xy 70.685085 -127.323523) (xy 70.64248 -127.305308)
			(xy 70.63254 -127.301488) (xy 70.611272 -127.301488) (xy 70.601332 -127.305308) (xy 70.558728 -127.323528)
			(xy 70.470561 -127.352046) (xy 70.379906 -127.371239) (xy 70.287746 -127.3809) (xy 70.241414 -127.381508)
			(xy 70.240906 -127.381508) (xy 70.198557 -127.38102) (xy 70.114241 -127.37297) (xy 70.031073 -127.356941)
			(xy 69.949805 -127.333079) (xy 69.871173 -127.3016) (xy 69.795889 -127.262789) (xy 69.724636 -127.216998)
			(xy 69.658058 -127.16464) (xy 69.596758 -127.106192) (xy 69.541292 -127.042181) (xy 69.492162 -126.973187)
			(xy 69.449812 -126.899836) (xy 69.414627 -126.822791) (xy 69.386925 -126.742751) (xy 69.366956 -126.66044)
			(xy 69.354902 -126.576603) (xy 69.350872 -126.492) (xy 59.700913 -126.492) (xy 59.696882 -126.576601)
			(xy 59.684829 -126.660435) (xy 59.664861 -126.742744) (xy 59.63716 -126.822783) (xy 59.601975 -126.899826)
			(xy 59.559627 -126.973175) (xy 59.510499 -127.042167) (xy 59.455034 -127.106177) (xy 59.393737 -127.164624)
			(xy 59.327161 -127.216981) (xy 59.25591 -127.262771) (xy 59.180629 -127.301582) (xy 59.101999 -127.333061)
			(xy 59.020733 -127.356923) (xy 58.937567 -127.372953) (xy 58.853254 -127.381004) (xy 58.810906 -127.381508)
			(xy 58.810398 -127.381508) (xy 58.764066 -127.3809) (xy 58.671908 -127.371229) (xy 58.581254 -127.352034)
			(xy 58.493085 -127.323523) (xy 58.45048 -127.305308) (xy 58.44054 -127.301488) (xy 58.419272 -127.301488)
			(xy 58.409332 -127.305308) (xy 58.366728 -127.323528) (xy 58.278561 -127.352046) (xy 58.187906 -127.371239)
			(xy 58.095746 -127.3809) (xy 58.049414 -127.381508) (xy 58.048906 -127.381508) (xy 58.006557 -127.38102)
			(xy 57.922241 -127.37297) (xy 57.839073 -127.356941) (xy 57.757805 -127.333079) (xy 57.679173 -127.3016)
			(xy 57.603889 -127.262789) (xy 57.532636 -127.216998) (xy 57.466058 -127.16464) (xy 57.404758 -127.106192)
			(xy 57.349292 -127.042181) (xy 57.300162 -126.973187) (xy 57.257812 -126.899836) (xy 57.222627 -126.822791)
			(xy 57.194925 -126.742751) (xy 57.174956 -126.66044) (xy 57.162902 -126.576603) (xy 57.158872 -126.492)
			(xy 47.508913 -126.492) (xy 47.504882 -126.576601) (xy 47.492829 -126.660435) (xy 47.472861 -126.742744)
			(xy 47.44516 -126.822783) (xy 47.409975 -126.899826) (xy 47.367627 -126.973175) (xy 47.318499 -127.042167)
			(xy 47.263034 -127.106177) (xy 47.201737 -127.164624) (xy 47.135161 -127.216981) (xy 47.06391 -127.262771)
			(xy 46.988629 -127.301582) (xy 46.909999 -127.333061) (xy 46.828733 -127.356923) (xy 46.745567 -127.372953)
			(xy 46.661254 -127.381004) (xy 46.618906 -127.381508) (xy 46.618398 -127.381508) (xy 46.572066 -127.3809)
			(xy 46.479908 -127.371229) (xy 46.389254 -127.352034) (xy 46.301085 -127.323523) (xy 46.25848 -127.305308)
			(xy 46.24854 -127.301488) (xy 46.227272 -127.301488) (xy 46.217332 -127.305308) (xy 46.174728 -127.323528)
			(xy 46.086561 -127.352046) (xy 45.995906 -127.371239) (xy 45.903746 -127.3809) (xy 45.857414 -127.381508)
			(xy 45.856906 -127.381508) (xy 45.814557 -127.38102) (xy 45.730241 -127.37297) (xy 45.647073 -127.356941)
			(xy 45.565805 -127.333079) (xy 45.487173 -127.3016) (xy 45.411889 -127.262789) (xy 45.340636 -127.216998)
			(xy 45.274058 -127.16464) (xy 45.212758 -127.106192) (xy 45.157292 -127.042181) (xy 45.108162 -126.973187)
			(xy 45.065812 -126.899836) (xy 45.030627 -126.822791) (xy 45.002925 -126.742751) (xy 44.982956 -126.66044)
			(xy 44.970902 -126.576603) (xy 44.966872 -126.492) (xy 37.531802 -126.492) (xy 37.531802 -131.572)
			(xy 44.966872 -131.572) (xy 44.970902 -131.487397) (xy 44.982956 -131.40356) (xy 45.002925 -131.321249)
			(xy 45.030627 -131.241209) (xy 45.065812 -131.164164) (xy 45.108162 -131.090813) (xy 45.157292 -131.021819)
			(xy 45.212758 -130.957808) (xy 45.274058 -130.89936) (xy 45.340636 -130.847002) (xy 45.411889 -130.801211)
			(xy 45.487173 -130.7624) (xy 45.565805 -130.730921) (xy 45.647073 -130.707059) (xy 45.730241 -130.69103)
			(xy 45.814557 -130.68298) (xy 45.856906 -130.682492) (xy 45.857414 -130.682492) (xy 45.903746 -130.683096)
			(xy 45.995904 -130.692768) (xy 46.086558 -130.711964) (xy 46.174727 -130.740477) (xy 46.217332 -130.758692)
			(xy 46.227272 -130.762512) (xy 46.24854 -130.762512) (xy 46.25848 -130.758692) (xy 46.301082 -130.740468)
			(xy 46.38925 -130.711951) (xy 46.479906 -130.692759) (xy 46.572066 -130.6831) (xy 46.618398 -130.682492)
			(xy 46.618906 -130.682492) (xy 46.661254 -130.682996) (xy 46.745567 -130.691047) (xy 46.828733 -130.707077)
			(xy 46.909999 -130.730939) (xy 46.988629 -130.762418) (xy 47.06391 -130.801229) (xy 47.135161 -130.847019)
			(xy 47.201737 -130.899376) (xy 47.263034 -130.957823) (xy 47.318499 -131.021833) (xy 47.367627 -131.090825)
			(xy 47.409975 -131.164174) (xy 47.44516 -131.241217) (xy 47.472861 -131.321256) (xy 47.492829 -131.403565)
			(xy 47.504882 -131.487399) (xy 47.508913 -131.572) (xy 57.158872 -131.572) (xy 57.162902 -131.487397)
			(xy 57.174956 -131.40356) (xy 57.194925 -131.321249) (xy 57.222627 -131.241209) (xy 57.257812 -131.164164)
			(xy 57.300162 -131.090813) (xy 57.349292 -131.021819) (xy 57.404758 -130.957808) (xy 57.466058 -130.89936)
			(xy 57.532636 -130.847002) (xy 57.603889 -130.801211) (xy 57.679173 -130.7624) (xy 57.757805 -130.730921)
			(xy 57.839073 -130.707059) (xy 57.922241 -130.69103) (xy 58.006557 -130.68298) (xy 58.048906 -130.682492)
			(xy 58.049414 -130.682492) (xy 58.095746 -130.683096) (xy 58.187904 -130.692768) (xy 58.278558 -130.711964)
			(xy 58.366727 -130.740477) (xy 58.409332 -130.758692) (xy 58.419272 -130.762512) (xy 58.44054 -130.762512)
			(xy 58.45048 -130.758692) (xy 58.493082 -130.740468) (xy 58.58125 -130.711951) (xy 58.671906 -130.692759)
			(xy 58.764066 -130.6831) (xy 58.810398 -130.682492) (xy 58.810906 -130.682492) (xy 58.853254 -130.682996)
			(xy 58.937567 -130.691047) (xy 59.020733 -130.707077) (xy 59.101999 -130.730939) (xy 59.180629 -130.762418)
			(xy 59.25591 -130.801229) (xy 59.327161 -130.847019) (xy 59.393737 -130.899376) (xy 59.455034 -130.957823)
			(xy 59.510499 -131.021833) (xy 59.559627 -131.090825) (xy 59.601975 -131.164174) (xy 59.63716 -131.241217)
			(xy 59.664861 -131.321256) (xy 59.684829 -131.403565) (xy 59.696882 -131.487399) (xy 59.700913 -131.572)
			(xy 69.350872 -131.572) (xy 69.354902 -131.487397) (xy 69.366956 -131.40356) (xy 69.386925 -131.321249)
			(xy 69.414627 -131.241209) (xy 69.449812 -131.164164) (xy 69.492162 -131.090813) (xy 69.541292 -131.021819)
			(xy 69.596758 -130.957808) (xy 69.658058 -130.89936) (xy 69.724636 -130.847002) (xy 69.795889 -130.801211)
			(xy 69.871173 -130.7624) (xy 69.949805 -130.730921) (xy 70.031073 -130.707059) (xy 70.114241 -130.69103)
			(xy 70.198557 -130.68298) (xy 70.240906 -130.682492) (xy 70.241414 -130.682492) (xy 70.287746 -130.683096)
			(xy 70.379904 -130.692768) (xy 70.470558 -130.711964) (xy 70.558727 -130.740477) (xy 70.601332 -130.758692)
			(xy 70.611272 -130.762512) (xy 70.63254 -130.762512) (xy 70.64248 -130.758692) (xy 70.685082 -130.740468)
			(xy 70.77325 -130.711951) (xy 70.863906 -130.692759) (xy 70.956066 -130.6831) (xy 71.002398 -130.682492)
			(xy 71.002906 -130.682492) (xy 71.045254 -130.682996) (xy 71.129567 -130.691047) (xy 71.212733 -130.707077)
			(xy 71.293999 -130.730939) (xy 71.372629 -130.762418) (xy 71.44791 -130.801229) (xy 71.519161 -130.847019)
			(xy 71.585737 -130.899376) (xy 71.647034 -130.957823) (xy 71.702499 -131.021833) (xy 71.751627 -131.090825)
			(xy 71.793975 -131.164174) (xy 71.82916 -131.241217) (xy 71.856861 -131.321256) (xy 71.876829 -131.403565)
			(xy 71.888882 -131.487399) (xy 71.892913 -131.572) (xy 84.966772 -131.572) (xy 84.970802 -131.487396)
			(xy 84.982857 -131.403558) (xy 85.002826 -131.321246) (xy 85.030529 -131.241204) (xy 85.065715 -131.164159)
			(xy 85.108066 -131.090807) (xy 85.157198 -131.021813) (xy 85.212665 -130.957801) (xy 85.273966 -130.899352)
			(xy 85.340546 -130.846995) (xy 85.411801 -130.801204) (xy 85.487086 -130.762394) (xy 85.56572 -130.730916)
			(xy 85.646989 -130.707055) (xy 85.730159 -130.691028) (xy 85.814476 -130.682979) (xy 85.856826 -130.682492)
			(xy 85.857334 -130.682492) (xy 85.903665 -130.683124) (xy 85.995822 -130.692788) (xy 86.086476 -130.711976)
			(xy 86.174646 -130.74048) (xy 86.217252 -130.758692) (xy 86.227192 -130.762512) (xy 86.24846 -130.762512)
			(xy 86.2584 -130.758692) (xy 86.300999 -130.740461) (xy 86.389168 -130.711946) (xy 86.479825 -130.692756)
			(xy 86.571985 -130.683099) (xy 86.618318 -130.682492) (xy 86.618826 -130.682492) (xy 86.661174 -130.682997)
			(xy 86.745485 -130.69105) (xy 86.82865 -130.707081) (xy 86.909914 -130.730944) (xy 86.988542 -130.762424)
			(xy 87.063821 -130.801235) (xy 87.135071 -130.847026) (xy 87.201645 -130.899383) (xy 87.262941 -130.95783)
			(xy 87.318404 -131.021839) (xy 87.367531 -131.090831) (xy 87.409878 -131.16418) (xy 87.445061 -131.241222)
			(xy 87.472762 -131.321259) (xy 87.492729 -131.403567) (xy 87.504783 -131.487401) (xy 87.508813 -131.572)
			(xy 97.158772 -131.572) (xy 97.162802 -131.487396) (xy 97.174857 -131.403558) (xy 97.194826 -131.321246)
			(xy 97.222529 -131.241204) (xy 97.257715 -131.164159) (xy 97.300066 -131.090807) (xy 97.349198 -131.021813)
			(xy 97.404665 -130.957801) (xy 97.465966 -130.899352) (xy 97.532546 -130.846995) (xy 97.603801 -130.801204)
			(xy 97.679086 -130.762394) (xy 97.75772 -130.730916) (xy 97.838989 -130.707055) (xy 97.922159 -130.691028)
			(xy 98.006476 -130.682979) (xy 98.048826 -130.682492) (xy 98.049334 -130.682492) (xy 98.095665 -130.683124)
			(xy 98.187822 -130.692788) (xy 98.278476 -130.711976) (xy 98.366646 -130.74048) (xy 98.409252 -130.758692)
			(xy 98.419192 -130.762512) (xy 98.44046 -130.762512) (xy 98.4504 -130.758692) (xy 98.492999 -130.740461)
			(xy 98.581168 -130.711946) (xy 98.671825 -130.692756) (xy 98.763985 -130.683099) (xy 98.810318 -130.682492)
			(xy 98.810826 -130.682492) (xy 98.853174 -130.682997) (xy 98.937485 -130.69105) (xy 99.02065 -130.707081)
			(xy 99.101914 -130.730944) (xy 99.180542 -130.762424) (xy 99.255821 -130.801235) (xy 99.327071 -130.847026)
			(xy 99.393645 -130.899383) (xy 99.454941 -130.95783) (xy 99.510404 -131.021839) (xy 99.559531 -131.090831)
			(xy 99.601878 -131.16418) (xy 99.637061 -131.241222) (xy 99.664762 -131.321259) (xy 99.684729 -131.403567)
			(xy 99.696783 -131.487401) (xy 99.700813 -131.572) (xy 109.350772 -131.572) (xy 109.354802 -131.487396)
			(xy 109.366857 -131.403558) (xy 109.386826 -131.321246) (xy 109.414529 -131.241204) (xy 109.449715 -131.164159)
			(xy 109.492066 -131.090807) (xy 109.541198 -131.021813) (xy 109.596665 -130.957801) (xy 109.657966 -130.899352)
			(xy 109.724546 -130.846995) (xy 109.795801 -130.801204) (xy 109.871086 -130.762394) (xy 109.94972 -130.730916)
			(xy 110.030989 -130.707055) (xy 110.114159 -130.691028) (xy 110.198476 -130.682979) (xy 110.240826 -130.682492)
			(xy 110.241334 -130.682492) (xy 110.287665 -130.683124) (xy 110.379822 -130.692788) (xy 110.470476 -130.711976)
			(xy 110.558646 -130.74048) (xy 110.601252 -130.758692) (xy 110.611192 -130.762512) (xy 110.63246 -130.762512)
			(xy 110.6424 -130.758692) (xy 110.684999 -130.740461) (xy 110.773168 -130.711946) (xy 110.863825 -130.692756)
			(xy 110.955985 -130.683099) (xy 111.002318 -130.682492) (xy 111.002826 -130.682492) (xy 111.045174 -130.682997)
			(xy 111.129485 -130.69105) (xy 111.21265 -130.707081) (xy 111.293914 -130.730944) (xy 111.372542 -130.762424)
			(xy 111.447821 -130.801235) (xy 111.519071 -130.847026) (xy 111.585645 -130.899383) (xy 111.646941 -130.95783)
			(xy 111.702404 -131.021839) (xy 111.751531 -131.090831) (xy 111.793878 -131.16418) (xy 111.829061 -131.241222)
			(xy 111.856762 -131.321259) (xy 111.876729 -131.403567) (xy 111.888783 -131.487401) (xy 111.892813 -131.572)
			(xy 124.966988 -131.572) (xy 124.971018 -131.487399) (xy 124.983071 -131.403564) (xy 125.003039 -131.321255)
			(xy 125.030741 -131.241216) (xy 125.065925 -131.164173) (xy 125.108274 -131.090823) (xy 125.157403 -131.021831)
			(xy 125.212868 -130.957821) (xy 125.274166 -130.899373) (xy 125.340742 -130.847017) (xy 125.411994 -130.801227)
			(xy 125.487275 -130.762416) (xy 125.565905 -130.730937) (xy 125.647172 -130.707076) (xy 125.730338 -130.691047)
			(xy 125.814652 -130.682996) (xy 125.857 -130.682492) (xy 125.857508 -130.682492) (xy 125.90384 -130.683098)
			(xy 125.995998 -130.692769) (xy 126.086652 -130.711965) (xy 126.174821 -130.740477) (xy 126.217426 -130.758692)
			(xy 126.227366 -130.762512) (xy 126.248634 -130.762512) (xy 126.258574 -130.758692) (xy 126.301177 -130.74047)
			(xy 126.389344 -130.711952) (xy 126.48 -130.69276) (xy 126.57216 -130.6831) (xy 126.618492 -130.682492)
			(xy 126.619 -130.682492) (xy 126.661348 -130.682996) (xy 126.745662 -130.691047) (xy 126.828828 -130.707076)
			(xy 126.910095 -130.730937) (xy 126.988725 -130.762416) (xy 127.064006 -130.801227) (xy 127.135258 -130.847017)
			(xy 127.201834 -130.899373) (xy 127.263132 -130.957821) (xy 127.318597 -131.021831) (xy 127.367726 -131.090823)
			(xy 127.410075 -131.164173) (xy 127.445259 -131.241216) (xy 127.472961 -131.321255) (xy 127.492929 -131.403564)
			(xy 127.504982 -131.487399) (xy 127.509013 -131.572) (xy 137.158988 -131.572) (xy 137.163018 -131.487399)
			(xy 137.175071 -131.403564) (xy 137.195039 -131.321255) (xy 137.222741 -131.241216) (xy 137.257925 -131.164173)
			(xy 137.300274 -131.090823) (xy 137.349403 -131.021831) (xy 137.404868 -130.957821) (xy 137.466166 -130.899373)
			(xy 137.532742 -130.847017) (xy 137.603994 -130.801227) (xy 137.679275 -130.762416) (xy 137.757905 -130.730937)
			(xy 137.839172 -130.707076) (xy 137.922338 -130.691047) (xy 138.006652 -130.682996) (xy 138.049 -130.682492)
			(xy 138.049508 -130.682492) (xy 138.09584 -130.683098) (xy 138.187998 -130.692769) (xy 138.278652 -130.711965)
			(xy 138.366821 -130.740477) (xy 138.409426 -130.758692) (xy 138.419366 -130.762512) (xy 138.440634 -130.762512)
			(xy 138.450574 -130.758692) (xy 138.493177 -130.74047) (xy 138.581344 -130.711952) (xy 138.672 -130.69276)
			(xy 138.76416 -130.6831) (xy 138.810492 -130.682492) (xy 138.811 -130.682492) (xy 138.853348 -130.682996)
			(xy 138.937662 -130.691047) (xy 139.020828 -130.707076) (xy 139.102095 -130.730937) (xy 139.180725 -130.762416)
			(xy 139.256006 -130.801227) (xy 139.327258 -130.847017) (xy 139.393834 -130.899373) (xy 139.455132 -130.957821)
			(xy 139.510597 -131.021831) (xy 139.559726 -131.090823) (xy 139.602075 -131.164173) (xy 139.637259 -131.241216)
			(xy 139.664961 -131.321255) (xy 139.684929 -131.403564) (xy 139.696982 -131.487399) (xy 139.701013 -131.572)
			(xy 149.350988 -131.572) (xy 149.355018 -131.487399) (xy 149.367071 -131.403564) (xy 149.387039 -131.321255)
			(xy 149.414741 -131.241216) (xy 149.449925 -131.164173) (xy 149.492274 -131.090823) (xy 149.541403 -131.021831)
			(xy 149.596868 -130.957821) (xy 149.658166 -130.899373) (xy 149.724742 -130.847017) (xy 149.795994 -130.801227)
			(xy 149.871275 -130.762416) (xy 149.949905 -130.730937) (xy 150.031172 -130.707076) (xy 150.114338 -130.691047)
			(xy 150.198652 -130.682996) (xy 150.241 -130.682492) (xy 150.241508 -130.682492) (xy 150.28784 -130.683098)
			(xy 150.379998 -130.692769) (xy 150.470652 -130.711965) (xy 150.558821 -130.740477) (xy 150.601426 -130.758692)
			(xy 150.611366 -130.762512) (xy 150.632634 -130.762512) (xy 150.642574 -130.758692) (xy 150.685177 -130.74047)
			(xy 150.773344 -130.711952) (xy 150.864 -130.69276) (xy 150.95616 -130.6831) (xy 151.002492 -130.682492)
			(xy 151.003 -130.682492) (xy 151.045348 -130.682996) (xy 151.129662 -130.691047) (xy 151.212828 -130.707076)
			(xy 151.294095 -130.730937) (xy 151.372725 -130.762416) (xy 151.448006 -130.801227) (xy 151.519258 -130.847017)
			(xy 151.585834 -130.899373) (xy 151.647132 -130.957821) (xy 151.702597 -131.021831) (xy 151.751726 -131.090823)
			(xy 151.794075 -131.164173) (xy 151.829259 -131.241216) (xy 151.856961 -131.321255) (xy 151.876929 -131.403564)
			(xy 151.888982 -131.487399) (xy 151.893013 -131.572) (xy 164.967187 -131.572) (xy 164.971217 -131.487401)
			(xy 164.983271 -131.403567) (xy 165.003238 -131.321259) (xy 165.030939 -131.241222) (xy 165.066122 -131.16418)
			(xy 165.108469 -131.090831) (xy 165.157596 -131.021839) (xy 165.213059 -130.95783) (xy 165.274355 -130.899383)
			(xy 165.340929 -130.847026) (xy 165.412179 -130.801235) (xy 165.487458 -130.762424) (xy 165.566086 -130.730944)
			(xy 165.64735 -130.707081) (xy 165.730515 -130.69105) (xy 165.814826 -130.682997) (xy 165.857174 -130.682492)
			(xy 165.857682 -130.682492) (xy 165.904014 -130.683107) (xy 165.996171 -130.692776) (xy 166.086825 -130.711969)
			(xy 166.174994 -130.740478) (xy 166.2176 -130.758692) (xy 166.22754 -130.762512) (xy 166.248808 -130.762512)
			(xy 166.258748 -130.758692) (xy 166.301354 -130.740479) (xy 166.389521 -130.711959) (xy 166.480175 -130.692764)
			(xy 166.572334 -130.683101) (xy 166.618666 -130.682492) (xy 166.619174 -130.682492) (xy 166.661524 -130.682979)
			(xy 166.745841 -130.691028) (xy 166.829011 -130.707055) (xy 166.91028 -130.730916) (xy 166.988914 -130.762394)
			(xy 167.064199 -130.801204) (xy 167.135454 -130.846995) (xy 167.202034 -130.899352) (xy 167.263335 -130.957801)
			(xy 167.318802 -131.021813) (xy 167.367934 -131.090807) (xy 167.410285 -131.164159) (xy 167.445471 -131.241204)
			(xy 167.473174 -131.321246) (xy 167.493143 -131.403558) (xy 167.505198 -131.487396) (xy 167.509228 -131.572)
			(xy 177.159187 -131.572) (xy 177.163217 -131.487401) (xy 177.175271 -131.403567) (xy 177.195238 -131.321259)
			(xy 177.222939 -131.241222) (xy 177.258122 -131.16418) (xy 177.300469 -131.090831) (xy 177.349596 -131.021839)
			(xy 177.405059 -130.95783) (xy 177.466355 -130.899383) (xy 177.532929 -130.847026) (xy 177.604179 -130.801235)
			(xy 177.679458 -130.762424) (xy 177.758086 -130.730944) (xy 177.83935 -130.707081) (xy 177.922515 -130.69105)
			(xy 178.006826 -130.682997) (xy 178.049174 -130.682492) (xy 178.049682 -130.682492) (xy 178.096014 -130.683107)
			(xy 178.188171 -130.692776) (xy 178.278825 -130.711969) (xy 178.366994 -130.740478) (xy 178.4096 -130.758692)
			(xy 178.41954 -130.762512) (xy 178.440808 -130.762512) (xy 178.450748 -130.758692) (xy 178.493354 -130.740479)
			(xy 178.581521 -130.711959) (xy 178.672175 -130.692764) (xy 178.764334 -130.683101) (xy 178.810666 -130.682492)
			(xy 178.811174 -130.682492) (xy 178.853524 -130.682979) (xy 178.937841 -130.691028) (xy 179.021011 -130.707055)
			(xy 179.10228 -130.730916) (xy 179.180914 -130.762394) (xy 179.256199 -130.801204) (xy 179.327454 -130.846995)
			(xy 179.394034 -130.899352) (xy 179.455335 -130.957801) (xy 179.510802 -131.021813) (xy 179.559934 -131.090807)
			(xy 179.602285 -131.164159) (xy 179.637471 -131.241204) (xy 179.665174 -131.321246) (xy 179.685143 -131.403558)
			(xy 179.697198 -131.487396) (xy 179.701228 -131.572) (xy 189.351187 -131.572) (xy 189.355217 -131.487401)
			(xy 189.367271 -131.403567) (xy 189.387238 -131.321259) (xy 189.414939 -131.241222) (xy 189.450122 -131.16418)
			(xy 189.492469 -131.090831) (xy 189.541596 -131.021839) (xy 189.597059 -130.95783) (xy 189.658355 -130.899383)
			(xy 189.724929 -130.847026) (xy 189.796179 -130.801235) (xy 189.871458 -130.762424) (xy 189.950086 -130.730944)
			(xy 190.03135 -130.707081) (xy 190.114515 -130.69105) (xy 190.198826 -130.682997) (xy 190.241174 -130.682492)
			(xy 190.241682 -130.682492) (xy 190.288014 -130.683107) (xy 190.380171 -130.692776) (xy 190.470825 -130.711969)
			(xy 190.558994 -130.740478) (xy 190.6016 -130.758692) (xy 190.61154 -130.762512) (xy 190.632808 -130.762512)
			(xy 190.642748 -130.758692) (xy 190.685354 -130.740479) (xy 190.773521 -130.711959) (xy 190.864175 -130.692764)
			(xy 190.956334 -130.683101) (xy 191.002666 -130.682492) (xy 191.003174 -130.682492) (xy 191.045524 -130.682979)
			(xy 191.129841 -130.691028) (xy 191.213011 -130.707055) (xy 191.29428 -130.730916) (xy 191.372914 -130.762394)
			(xy 191.448199 -130.801204) (xy 191.519454 -130.846995) (xy 191.586034 -130.899352) (xy 191.647335 -130.957801)
			(xy 191.702802 -131.021813) (xy 191.751934 -131.090807) (xy 191.794285 -131.164159) (xy 191.829471 -131.241204)
			(xy 191.857174 -131.321246) (xy 191.877143 -131.403558) (xy 191.889198 -131.487396) (xy 191.893228 -131.572)
			(xy 191.889198 -131.656604) (xy 191.877143 -131.740442) (xy 191.857174 -131.822754) (xy 191.829471 -131.902796)
			(xy 191.794285 -131.979841) (xy 191.751934 -132.053193) (xy 191.702802 -132.122187) (xy 191.647335 -132.186199)
			(xy 191.586034 -132.244648) (xy 191.519454 -132.297005) (xy 191.448199 -132.342796) (xy 191.372914 -132.381606)
			(xy 191.29428 -132.413084) (xy 191.213011 -132.436945) (xy 191.129841 -132.452972) (xy 191.045524 -132.461021)
			(xy 191.003174 -132.461508) (xy 191.002666 -132.461508) (xy 190.956335 -132.460876) (xy 190.864178 -132.451212)
			(xy 190.773524 -132.432024) (xy 190.685354 -132.40352) (xy 190.642748 -132.385308) (xy 190.632808 -132.381488)
			(xy 190.61154 -132.381488) (xy 190.6016 -132.385308) (xy 190.559001 -132.403539) (xy 190.470832 -132.432054)
			(xy 190.380175 -132.451244) (xy 190.288015 -132.460901) (xy 190.241682 -132.461508) (xy 190.241174 -132.461508)
			(xy 190.198826 -132.461003) (xy 190.114515 -132.45295) (xy 190.03135 -132.436919) (xy 189.950086 -132.413056)
			(xy 189.871458 -132.381576) (xy 189.796179 -132.342765) (xy 189.724929 -132.296974) (xy 189.658355 -132.244617)
			(xy 189.597059 -132.18617) (xy 189.541596 -132.122161) (xy 189.492469 -132.053169) (xy 189.450122 -131.97982)
			(xy 189.414939 -131.902778) (xy 189.387238 -131.822741) (xy 189.367271 -131.740433) (xy 189.355217 -131.656599)
			(xy 189.351187 -131.572) (xy 179.701228 -131.572) (xy 179.697198 -131.656604) (xy 179.685143 -131.740442)
			(xy 179.665174 -131.822754) (xy 179.637471 -131.902796) (xy 179.602285 -131.979841) (xy 179.559934 -132.053193)
			(xy 179.510802 -132.122187) (xy 179.455335 -132.186199) (xy 179.394034 -132.244648) (xy 179.327454 -132.297005)
			(xy 179.256199 -132.342796) (xy 179.180914 -132.381606) (xy 179.10228 -132.413084) (xy 179.021011 -132.436945)
			(xy 178.937841 -132.452972) (xy 178.853524 -132.461021) (xy 178.811174 -132.461508) (xy 178.810666 -132.461508)
			(xy 178.764335 -132.460876) (xy 178.672178 -132.451212) (xy 178.581524 -132.432024) (xy 178.493354 -132.40352)
			(xy 178.450748 -132.385308) (xy 178.440808 -132.381488) (xy 178.41954 -132.381488) (xy 178.4096 -132.385308)
			(xy 178.367001 -132.403539) (xy 178.278832 -132.432054) (xy 178.188175 -132.451244) (xy 178.096015 -132.460901)
			(xy 178.049682 -132.461508) (xy 178.049174 -132.461508) (xy 178.006826 -132.461003) (xy 177.922515 -132.45295)
			(xy 177.83935 -132.436919) (xy 177.758086 -132.413056) (xy 177.679458 -132.381576) (xy 177.604179 -132.342765)
			(xy 177.532929 -132.296974) (xy 177.466355 -132.244617) (xy 177.405059 -132.18617) (xy 177.349596 -132.122161)
			(xy 177.300469 -132.053169) (xy 177.258122 -131.97982) (xy 177.222939 -131.902778) (xy 177.195238 -131.822741)
			(xy 177.175271 -131.740433) (xy 177.163217 -131.656599) (xy 177.159187 -131.572) (xy 167.509228 -131.572)
			(xy 167.505198 -131.656604) (xy 167.493143 -131.740442) (xy 167.473174 -131.822754) (xy 167.445471 -131.902796)
			(xy 167.410285 -131.979841) (xy 167.367934 -132.053193) (xy 167.318802 -132.122187) (xy 167.263335 -132.186199)
			(xy 167.202034 -132.244648) (xy 167.135454 -132.297005) (xy 167.064199 -132.342796) (xy 166.988914 -132.381606)
			(xy 166.91028 -132.413084) (xy 166.829011 -132.436945) (xy 166.745841 -132.452972) (xy 166.661524 -132.461021)
			(xy 166.619174 -132.461508) (xy 166.618666 -132.461508) (xy 166.572335 -132.460876) (xy 166.480178 -132.451212)
			(xy 166.389524 -132.432024) (xy 166.301354 -132.40352) (xy 166.258748 -132.385308) (xy 166.248808 -132.381488)
			(xy 166.22754 -132.381488) (xy 166.2176 -132.385308) (xy 166.175001 -132.403539) (xy 166.086832 -132.432054)
			(xy 165.996175 -132.451244) (xy 165.904015 -132.460901) (xy 165.857682 -132.461508) (xy 165.857174 -132.461508)
			(xy 165.814826 -132.461003) (xy 165.730515 -132.45295) (xy 165.64735 -132.436919) (xy 165.566086 -132.413056)
			(xy 165.487458 -132.381576) (xy 165.412179 -132.342765) (xy 165.340929 -132.296974) (xy 165.274355 -132.244617)
			(xy 165.213059 -132.18617) (xy 165.157596 -132.122161) (xy 165.108469 -132.053169) (xy 165.066122 -131.97982)
			(xy 165.030939 -131.902778) (xy 165.003238 -131.822741) (xy 164.983271 -131.740433) (xy 164.971217 -131.656599)
			(xy 164.967187 -131.572) (xy 151.893013 -131.572) (xy 151.888982 -131.656601) (xy 151.876929 -131.740436)
			(xy 151.856961 -131.822745) (xy 151.829259 -131.902784) (xy 151.794075 -131.979827) (xy 151.751726 -132.053177)
			(xy 151.702597 -132.122169) (xy 151.647132 -132.186179) (xy 151.585834 -132.244627) (xy 151.519258 -132.296983)
			(xy 151.448006 -132.342773) (xy 151.372725 -132.381584) (xy 151.294095 -132.413063) (xy 151.212828 -132.436924)
			(xy 151.129662 -132.452953) (xy 151.045348 -132.461004) (xy 151.003 -132.461508) (xy 151.002492 -132.461508)
			(xy 150.95616 -132.460902) (xy 150.864002 -132.451231) (xy 150.773348 -132.432035) (xy 150.685179 -132.403523)
			(xy 150.642574 -132.385308) (xy 150.632634 -132.381488) (xy 150.611366 -132.381488) (xy 150.601426 -132.385308)
			(xy 150.558823 -132.40353) (xy 150.470656 -132.432048) (xy 150.38 -132.45124) (xy 150.28784 -132.4609)
			(xy 150.241508 -132.461508) (xy 150.241 -132.461508) (xy 150.198652 -132.461004) (xy 150.114338 -132.452953)
			(xy 150.031172 -132.436924) (xy 149.949905 -132.413063) (xy 149.871275 -132.381584) (xy 149.795994 -132.342773)
			(xy 149.724742 -132.296983) (xy 149.658166 -132.244627) (xy 149.596868 -132.186179) (xy 149.541403 -132.122169)
			(xy 149.492274 -132.053177) (xy 149.449925 -131.979827) (xy 149.414741 -131.902784) (xy 149.387039 -131.822745)
			(xy 149.367071 -131.740436) (xy 149.355018 -131.656601) (xy 149.350988 -131.572) (xy 139.701013 -131.572)
			(xy 139.696982 -131.656601) (xy 139.684929 -131.740436) (xy 139.664961 -131.822745) (xy 139.637259 -131.902784)
			(xy 139.602075 -131.979827) (xy 139.559726 -132.053177) (xy 139.510597 -132.122169) (xy 139.455132 -132.186179)
			(xy 139.393834 -132.244627) (xy 139.327258 -132.296983) (xy 139.256006 -132.342773) (xy 139.180725 -132.381584)
			(xy 139.102095 -132.413063) (xy 139.020828 -132.436924) (xy 138.937662 -132.452953) (xy 138.853348 -132.461004)
			(xy 138.811 -132.461508) (xy 138.810492 -132.461508) (xy 138.76416 -132.460902) (xy 138.672002 -132.451231)
			(xy 138.581348 -132.432035) (xy 138.493179 -132.403523) (xy 138.450574 -132.385308) (xy 138.440634 -132.381488)
			(xy 138.419366 -132.381488) (xy 138.409426 -132.385308) (xy 138.366823 -132.40353) (xy 138.278656 -132.432048)
			(xy 138.188 -132.45124) (xy 138.09584 -132.4609) (xy 138.049508 -132.461508) (xy 138.049 -132.461508)
			(xy 138.006652 -132.461004) (xy 137.922338 -132.452953) (xy 137.839172 -132.436924) (xy 137.757905 -132.413063)
			(xy 137.679275 -132.381584) (xy 137.603994 -132.342773) (xy 137.532742 -132.296983) (xy 137.466166 -132.244627)
			(xy 137.404868 -132.186179) (xy 137.349403 -132.122169) (xy 137.300274 -132.053177) (xy 137.257925 -131.979827)
			(xy 137.222741 -131.902784) (xy 137.195039 -131.822745) (xy 137.175071 -131.740436) (xy 137.163018 -131.656601)
			(xy 137.158988 -131.572) (xy 127.509013 -131.572) (xy 127.504982 -131.656601) (xy 127.492929 -131.740436)
			(xy 127.472961 -131.822745) (xy 127.445259 -131.902784) (xy 127.410075 -131.979827) (xy 127.367726 -132.053177)
			(xy 127.318597 -132.122169) (xy 127.263132 -132.186179) (xy 127.201834 -132.244627) (xy 127.135258 -132.296983)
			(xy 127.064006 -132.342773) (xy 126.988725 -132.381584) (xy 126.910095 -132.413063) (xy 126.828828 -132.436924)
			(xy 126.745662 -132.452953) (xy 126.661348 -132.461004) (xy 126.619 -132.461508) (xy 126.618492 -132.461508)
			(xy 126.57216 -132.460902) (xy 126.480002 -132.451231) (xy 126.389348 -132.432035) (xy 126.301179 -132.403523)
			(xy 126.258574 -132.385308) (xy 126.248634 -132.381488) (xy 126.227366 -132.381488) (xy 126.217426 -132.385308)
			(xy 126.174823 -132.40353) (xy 126.086656 -132.432048) (xy 125.996 -132.45124) (xy 125.90384 -132.4609)
			(xy 125.857508 -132.461508) (xy 125.857 -132.461508) (xy 125.814652 -132.461004) (xy 125.730338 -132.452953)
			(xy 125.647172 -132.436924) (xy 125.565905 -132.413063) (xy 125.487275 -132.381584) (xy 125.411994 -132.342773)
			(xy 125.340742 -132.296983) (xy 125.274166 -132.244627) (xy 125.212868 -132.186179) (xy 125.157403 -132.122169)
			(xy 125.108274 -132.053177) (xy 125.065925 -131.979827) (xy 125.030741 -131.902784) (xy 125.003039 -131.822745)
			(xy 124.983071 -131.740436) (xy 124.971018 -131.656601) (xy 124.966988 -131.572) (xy 111.892813 -131.572)
			(xy 111.888783 -131.656599) (xy 111.876729 -131.740433) (xy 111.856762 -131.822741) (xy 111.829061 -131.902778)
			(xy 111.793878 -131.97982) (xy 111.751531 -132.053169) (xy 111.702404 -132.122161) (xy 111.646941 -132.18617)
			(xy 111.585645 -132.244617) (xy 111.519071 -132.296974) (xy 111.447821 -132.342765) (xy 111.372542 -132.381576)
			(xy 111.293914 -132.413056) (xy 111.21265 -132.436919) (xy 111.129485 -132.45295) (xy 111.045174 -132.461003)
			(xy 111.002826 -132.461508) (xy 111.002318 -132.461508) (xy 110.955986 -132.460893) (xy 110.863829 -132.451224)
			(xy 110.773175 -132.432031) (xy 110.685006 -132.403522) (xy 110.6424 -132.385308) (xy 110.63246 -132.381488)
			(xy 110.611192 -132.381488) (xy 110.601252 -132.385308) (xy 110.558646 -132.403521) (xy 110.470479 -132.432041)
			(xy 110.379825 -132.451236) (xy 110.287666 -132.460899) (xy 110.241334 -132.461508) (xy 110.240826 -132.461508)
			(xy 110.198476 -132.461021) (xy 110.114159 -132.452972) (xy 110.030989 -132.436945) (xy 109.94972 -132.413084)
			(xy 109.871086 -132.381606) (xy 109.795801 -132.342796) (xy 109.724546 -132.297005) (xy 109.657966 -132.244648)
			(xy 109.596665 -132.186199) (xy 109.541198 -132.122187) (xy 109.492066 -132.053193) (xy 109.449715 -131.979841)
			(xy 109.414529 -131.902796) (xy 109.386826 -131.822754) (xy 109.366857 -131.740442) (xy 109.354802 -131.656604)
			(xy 109.350772 -131.572) (xy 99.700813 -131.572) (xy 99.696783 -131.656599) (xy 99.684729 -131.740433)
			(xy 99.664762 -131.822741) (xy 99.637061 -131.902778) (xy 99.601878 -131.97982) (xy 99.559531 -132.053169)
			(xy 99.510404 -132.122161) (xy 99.454941 -132.18617) (xy 99.393645 -132.244617) (xy 99.327071 -132.296974)
			(xy 99.255821 -132.342765) (xy 99.180542 -132.381576) (xy 99.101914 -132.413056) (xy 99.02065 -132.436919)
			(xy 98.937485 -132.45295) (xy 98.853174 -132.461003) (xy 98.810826 -132.461508) (xy 98.810318 -132.461508)
			(xy 98.763986 -132.460893) (xy 98.671829 -132.451224) (xy 98.581175 -132.432031) (xy 98.493006 -132.403522)
			(xy 98.4504 -132.385308) (xy 98.44046 -132.381488) (xy 98.419192 -132.381488) (xy 98.409252 -132.385308)
			(xy 98.366646 -132.403521) (xy 98.278479 -132.432041) (xy 98.187825 -132.451236) (xy 98.095666 -132.460899)
			(xy 98.049334 -132.461508) (xy 98.048826 -132.461508) (xy 98.006476 -132.461021) (xy 97.922159 -132.452972)
			(xy 97.838989 -132.436945) (xy 97.75772 -132.413084) (xy 97.679086 -132.381606) (xy 97.603801 -132.342796)
			(xy 97.532546 -132.297005) (xy 97.465966 -132.244648) (xy 97.404665 -132.186199) (xy 97.349198 -132.122187)
			(xy 97.300066 -132.053193) (xy 97.257715 -131.979841) (xy 97.222529 -131.902796) (xy 97.194826 -131.822754)
			(xy 97.174857 -131.740442) (xy 97.162802 -131.656604) (xy 97.158772 -131.572) (xy 87.508813 -131.572)
			(xy 87.504783 -131.656599) (xy 87.492729 -131.740433) (xy 87.472762 -131.822741) (xy 87.445061 -131.902778)
			(xy 87.409878 -131.97982) (xy 87.367531 -132.053169) (xy 87.318404 -132.122161) (xy 87.262941 -132.18617)
			(xy 87.201645 -132.244617) (xy 87.135071 -132.296974) (xy 87.063821 -132.342765) (xy 86.988542 -132.381576)
			(xy 86.909914 -132.413056) (xy 86.82865 -132.436919) (xy 86.745485 -132.45295) (xy 86.661174 -132.461003)
			(xy 86.618826 -132.461508) (xy 86.618318 -132.461508) (xy 86.571986 -132.460893) (xy 86.479829 -132.451224)
			(xy 86.389175 -132.432031) (xy 86.301006 -132.403522) (xy 86.2584 -132.385308) (xy 86.24846 -132.381488)
			(xy 86.227192 -132.381488) (xy 86.217252 -132.385308) (xy 86.174646 -132.403521) (xy 86.086479 -132.432041)
			(xy 85.995825 -132.451236) (xy 85.903666 -132.460899) (xy 85.857334 -132.461508) (xy 85.856826 -132.461508)
			(xy 85.814476 -132.461021) (xy 85.730159 -132.452972) (xy 85.646989 -132.436945) (xy 85.56572 -132.413084)
			(xy 85.487086 -132.381606) (xy 85.411801 -132.342796) (xy 85.340546 -132.297005) (xy 85.273966 -132.244648)
			(xy 85.212665 -132.186199) (xy 85.157198 -132.122187) (xy 85.108066 -132.053193) (xy 85.065715 -131.979841)
			(xy 85.030529 -131.902796) (xy 85.002826 -131.822754) (xy 84.982857 -131.740442) (xy 84.970802 -131.656604)
			(xy 84.966772 -131.572) (xy 71.892913 -131.572) (xy 71.888882 -131.656601) (xy 71.876829 -131.740435)
			(xy 71.856861 -131.822744) (xy 71.82916 -131.902783) (xy 71.793975 -131.979826) (xy 71.751627 -132.053175)
			(xy 71.702499 -132.122167) (xy 71.647034 -132.186177) (xy 71.585737 -132.244624) (xy 71.519161 -132.296981)
			(xy 71.44791 -132.342771) (xy 71.372629 -132.381582) (xy 71.293999 -132.413061) (xy 71.212733 -132.436923)
			(xy 71.129567 -132.452953) (xy 71.045254 -132.461004) (xy 71.002906 -132.461508) (xy 71.002398 -132.461508)
			(xy 70.956066 -132.4609) (xy 70.863908 -132.451229) (xy 70.773254 -132.432034) (xy 70.685085 -132.403523)
			(xy 70.64248 -132.385308) (xy 70.63254 -132.381488) (xy 70.611272 -132.381488) (xy 70.601332 -132.385308)
			(xy 70.558728 -132.403528) (xy 70.470561 -132.432046) (xy 70.379906 -132.451239) (xy 70.287746 -132.4609)
			(xy 70.241414 -132.461508) (xy 70.240906 -132.461508) (xy 70.198557 -132.46102) (xy 70.114241 -132.45297)
			(xy 70.031073 -132.436941) (xy 69.949805 -132.413079) (xy 69.871173 -132.3816) (xy 69.795889 -132.342789)
			(xy 69.724636 -132.296998) (xy 69.658058 -132.24464) (xy 69.596758 -132.186192) (xy 69.541292 -132.122181)
			(xy 69.492162 -132.053187) (xy 69.449812 -131.979836) (xy 69.414627 -131.902791) (xy 69.386925 -131.822751)
			(xy 69.366956 -131.74044) (xy 69.354902 -131.656603) (xy 69.350872 -131.572) (xy 59.700913 -131.572)
			(xy 59.696882 -131.656601) (xy 59.684829 -131.740435) (xy 59.664861 -131.822744) (xy 59.63716 -131.902783)
			(xy 59.601975 -131.979826) (xy 59.559627 -132.053175) (xy 59.510499 -132.122167) (xy 59.455034 -132.186177)
			(xy 59.393737 -132.244624) (xy 59.327161 -132.296981) (xy 59.25591 -132.342771) (xy 59.180629 -132.381582)
			(xy 59.101999 -132.413061) (xy 59.020733 -132.436923) (xy 58.937567 -132.452953) (xy 58.853254 -132.461004)
			(xy 58.810906 -132.461508) (xy 58.810398 -132.461508) (xy 58.764066 -132.4609) (xy 58.671908 -132.451229)
			(xy 58.581254 -132.432034) (xy 58.493085 -132.403523) (xy 58.45048 -132.385308) (xy 58.44054 -132.381488)
			(xy 58.419272 -132.381488) (xy 58.409332 -132.385308) (xy 58.366728 -132.403528) (xy 58.278561 -132.432046)
			(xy 58.187906 -132.451239) (xy 58.095746 -132.4609) (xy 58.049414 -132.461508) (xy 58.048906 -132.461508)
			(xy 58.006557 -132.46102) (xy 57.922241 -132.45297) (xy 57.839073 -132.436941) (xy 57.757805 -132.413079)
			(xy 57.679173 -132.3816) (xy 57.603889 -132.342789) (xy 57.532636 -132.296998) (xy 57.466058 -132.24464)
			(xy 57.404758 -132.186192) (xy 57.349292 -132.122181) (xy 57.300162 -132.053187) (xy 57.257812 -131.979836)
			(xy 57.222627 -131.902791) (xy 57.194925 -131.822751) (xy 57.174956 -131.74044) (xy 57.162902 -131.656603)
			(xy 57.158872 -131.572) (xy 47.508913 -131.572) (xy 47.504882 -131.656601) (xy 47.492829 -131.740435)
			(xy 47.472861 -131.822744) (xy 47.44516 -131.902783) (xy 47.409975 -131.979826) (xy 47.367627 -132.053175)
			(xy 47.318499 -132.122167) (xy 47.263034 -132.186177) (xy 47.201737 -132.244624) (xy 47.135161 -132.296981)
			(xy 47.06391 -132.342771) (xy 46.988629 -132.381582) (xy 46.909999 -132.413061) (xy 46.828733 -132.436923)
			(xy 46.745567 -132.452953) (xy 46.661254 -132.461004) (xy 46.618906 -132.461508) (xy 46.618398 -132.461508)
			(xy 46.572066 -132.4609) (xy 46.479908 -132.451229) (xy 46.389254 -132.432034) (xy 46.301085 -132.403523)
			(xy 46.25848 -132.385308) (xy 46.24854 -132.381488) (xy 46.227272 -132.381488) (xy 46.217332 -132.385308)
			(xy 46.174728 -132.403528) (xy 46.086561 -132.432046) (xy 45.995906 -132.451239) (xy 45.903746 -132.4609)
			(xy 45.857414 -132.461508) (xy 45.856906 -132.461508) (xy 45.814557 -132.46102) (xy 45.730241 -132.45297)
			(xy 45.647073 -132.436941) (xy 45.565805 -132.413079) (xy 45.487173 -132.3816) (xy 45.411889 -132.342789)
			(xy 45.340636 -132.296998) (xy 45.274058 -132.24464) (xy 45.212758 -132.186192) (xy 45.157292 -132.122181)
			(xy 45.108162 -132.053187) (xy 45.065812 -131.979836) (xy 45.030627 -131.902791) (xy 45.002925 -131.822751)
			(xy 44.982956 -131.74044) (xy 44.970902 -131.656603) (xy 44.966872 -131.572) (xy 37.531802 -131.572)
			(xy 37.531802 -136.906) (xy 41.131495 -136.906) (xy 41.135517 -136.82028) (xy 41.147548 -136.735312)
			(xy 41.167484 -136.651845) (xy 41.195147 -136.570611) (xy 41.230296 -136.492325) (xy 41.272622 -136.417674)
			(xy 41.321751 -136.347315) (xy 41.377254 -136.281865) (xy 41.438641 -136.221901) (xy 41.505374 -136.167948)
			(xy 41.576866 -136.120481) (xy 41.652488 -136.079917) (xy 41.731577 -136.046613) (xy 41.813437 -136.020861)
			(xy 41.897348 -136.002888) (xy 41.982574 -135.992852) (xy 42.068366 -135.99084) (xy 42.153968 -135.996871)
			(xy 42.23863 -136.010891) (xy 42.321607 -136.032777) (xy 42.40217 -136.062338) (xy 42.47961 -136.099312)
			(xy 42.553249 -136.143376) (xy 42.622437 -136.194142) (xy 42.686568 -136.251163) (xy 42.745077 -136.313939)
			(xy 42.79745 -136.381919) (xy 42.843228 -136.454504) (xy 42.882008 -136.531056) (xy 42.913449 -136.610904)
			(xy 42.937275 -136.693345) (xy 42.953276 -136.777655) (xy 42.961311 -136.863093) (xy 42.961814 -136.906)
			(xy 42.961311 -136.948907) (xy 42.960341 -136.959223) (xy 45.624485 -136.959223) (xy 45.624485 -136.852777)
			(xy 45.63244 -136.746629) (xy 45.648305 -136.641372) (xy 45.671991 -136.537595) (xy 45.703367 -136.435879)
			(xy 45.742256 -136.336791) (xy 45.788441 -136.240887) (xy 45.841664 -136.148702) (xy 45.901627 -136.060753)
			(xy 45.967995 -135.97753) (xy 46.040396 -135.8995) (xy 46.118426 -135.827099) (xy 46.201649 -135.760731)
			(xy 46.289598 -135.700768) (xy 46.381783 -135.647545) (xy 46.477687 -135.60136) (xy 46.576775 -135.562471)
			(xy 46.678491 -135.531095) (xy 46.782268 -135.507409) (xy 46.887525 -135.491544) (xy 46.993673 -135.483589)
			(xy 47.100119 -135.483589) (xy 47.206267 -135.491544) (xy 47.311524 -135.507409) (xy 47.415301 -135.531095)
			(xy 47.517017 -135.562471) (xy 47.616105 -135.60136) (xy 47.712009 -135.647545) (xy 47.804194 -135.700768)
			(xy 47.892143 -135.760731) (xy 47.975366 -135.827099) (xy 48.053396 -135.8995) (xy 48.125797 -135.97753)
			(xy 48.192165 -136.060753) (xy 48.252128 -136.148702) (xy 48.305351 -136.240887) (xy 48.351536 -136.336791)
			(xy 48.390425 -136.435879) (xy 48.421801 -136.537595) (xy 48.445487 -136.641372) (xy 48.461352 -136.746629)
			(xy 48.469307 -136.852777) (xy 48.469804 -136.906) (xy 53.323495 -136.906) (xy 53.327517 -136.82028)
			(xy 53.339548 -136.735312) (xy 53.359484 -136.651845) (xy 53.387147 -136.570611) (xy 53.422296 -136.492325)
			(xy 53.464622 -136.417674) (xy 53.513751 -136.347315) (xy 53.569254 -136.281865) (xy 53.630641 -136.221901)
			(xy 53.697374 -136.167948) (xy 53.768866 -136.120481) (xy 53.844488 -136.079917) (xy 53.923577 -136.046613)
			(xy 54.005437 -136.020861) (xy 54.089348 -136.002888) (xy 54.174574 -135.992852) (xy 54.260366 -135.99084)
			(xy 54.345968 -135.996871) (xy 54.43063 -136.010891) (xy 54.513607 -136.032777) (xy 54.59417 -136.062338)
			(xy 54.67161 -136.099312) (xy 54.745249 -136.143376) (xy 54.814437 -136.194142) (xy 54.878568 -136.251163)
			(xy 54.937077 -136.313939) (xy 54.98945 -136.381919) (xy 55.035228 -136.454504) (xy 55.074008 -136.531056)
			(xy 55.105449 -136.610904) (xy 55.129275 -136.693345) (xy 55.145276 -136.777655) (xy 55.153311 -136.863093)
			(xy 55.153814 -136.906) (xy 55.153311 -136.948907) (xy 55.152341 -136.959223) (xy 57.816485 -136.959223)
			(xy 57.816485 -136.852777) (xy 57.82444 -136.746629) (xy 57.840305 -136.641372) (xy 57.863991 -136.537595)
			(xy 57.895367 -136.435879) (xy 57.934256 -136.336791) (xy 57.980441 -136.240887) (xy 58.033664 -136.148702)
			(xy 58.093627 -136.060753) (xy 58.159995 -135.97753) (xy 58.232396 -135.8995) (xy 58.310426 -135.827099)
			(xy 58.393649 -135.760731) (xy 58.481598 -135.700768) (xy 58.573783 -135.647545) (xy 58.669687 -135.60136)
			(xy 58.768775 -135.562471) (xy 58.870491 -135.531095) (xy 58.974268 -135.507409) (xy 59.079525 -135.491544)
			(xy 59.185673 -135.483589) (xy 59.292119 -135.483589) (xy 59.398267 -135.491544) (xy 59.503524 -135.507409)
			(xy 59.607301 -135.531095) (xy 59.709017 -135.562471) (xy 59.808105 -135.60136) (xy 59.904009 -135.647545)
			(xy 59.996194 -135.700768) (xy 60.084143 -135.760731) (xy 60.167366 -135.827099) (xy 60.245396 -135.8995)
			(xy 60.317797 -135.97753) (xy 60.384165 -136.060753) (xy 60.444128 -136.148702) (xy 60.497351 -136.240887)
			(xy 60.543536 -136.336791) (xy 60.582425 -136.435879) (xy 60.613801 -136.537595) (xy 60.637487 -136.641372)
			(xy 60.653352 -136.746629) (xy 60.661307 -136.852777) (xy 60.661804 -136.906) (xy 65.515495 -136.906)
			(xy 65.519517 -136.82028) (xy 65.531548 -136.735312) (xy 65.551484 -136.651845) (xy 65.579147 -136.570611)
			(xy 65.614296 -136.492325) (xy 65.656622 -136.417674) (xy 65.705751 -136.347315) (xy 65.761254 -136.281865)
			(xy 65.822641 -136.221901) (xy 65.889374 -136.167948) (xy 65.960866 -136.120481) (xy 66.036488 -136.079917)
			(xy 66.115577 -136.046613) (xy 66.197437 -136.020861) (xy 66.281348 -136.002888) (xy 66.366574 -135.992852)
			(xy 66.452366 -135.99084) (xy 66.537968 -135.996871) (xy 66.62263 -136.010891) (xy 66.705607 -136.032777)
			(xy 66.78617 -136.062338) (xy 66.86361 -136.099312) (xy 66.937249 -136.143376) (xy 67.006437 -136.194142)
			(xy 67.070568 -136.251163) (xy 67.129077 -136.313939) (xy 67.18145 -136.381919) (xy 67.227228 -136.454504)
			(xy 67.266008 -136.531056) (xy 67.297449 -136.610904) (xy 67.321275 -136.693345) (xy 67.337276 -136.777655)
			(xy 67.345311 -136.863093) (xy 67.345814 -136.906) (xy 67.345311 -136.948907) (xy 67.344341 -136.959223)
			(xy 70.008485 -136.959223) (xy 70.008485 -136.852777) (xy 70.01644 -136.746629) (xy 70.032305 -136.641372)
			(xy 70.055991 -136.537595) (xy 70.087367 -136.435879) (xy 70.126256 -136.336791) (xy 70.172441 -136.240887)
			(xy 70.225664 -136.148702) (xy 70.285627 -136.060753) (xy 70.351995 -135.97753) (xy 70.424396 -135.8995)
			(xy 70.502426 -135.827099) (xy 70.585649 -135.760731) (xy 70.673598 -135.700768) (xy 70.765783 -135.647545)
			(xy 70.861687 -135.60136) (xy 70.960775 -135.562471) (xy 71.062491 -135.531095) (xy 71.166268 -135.507409)
			(xy 71.271525 -135.491544) (xy 71.377673 -135.483589) (xy 71.484119 -135.483589) (xy 71.590267 -135.491544)
			(xy 71.695524 -135.507409) (xy 71.799301 -135.531095) (xy 71.901017 -135.562471) (xy 72.000105 -135.60136)
			(xy 72.096009 -135.647545) (xy 72.188194 -135.700768) (xy 72.276143 -135.760731) (xy 72.359366 -135.827099)
			(xy 72.437396 -135.8995) (xy 72.509797 -135.97753) (xy 72.576165 -136.060753) (xy 72.636128 -136.148702)
			(xy 72.689351 -136.240887) (xy 72.735536 -136.336791) (xy 72.774425 -136.435879) (xy 72.805801 -136.537595)
			(xy 72.829487 -136.641372) (xy 72.845352 -136.746629) (xy 72.853307 -136.852777) (xy 72.853804 -136.906)
			(xy 81.131415 -136.906) (xy 81.135437 -136.82028) (xy 81.147468 -136.735312) (xy 81.167404 -136.651845)
			(xy 81.195067 -136.570611) (xy 81.230216 -136.492325) (xy 81.272542 -136.417674) (xy 81.321671 -136.347315)
			(xy 81.377174 -136.281865) (xy 81.438561 -136.221901) (xy 81.505294 -136.167948) (xy 81.576786 -136.120481)
			(xy 81.652408 -136.079917) (xy 81.731497 -136.046613) (xy 81.813357 -136.020861) (xy 81.897268 -136.002888)
			(xy 81.982494 -135.992852) (xy 82.068286 -135.99084) (xy 82.153888 -135.996871) (xy 82.23855 -136.010891)
			(xy 82.321527 -136.032777) (xy 82.40209 -136.062338) (xy 82.47953 -136.099312) (xy 82.553169 -136.143376)
			(xy 82.622357 -136.194142) (xy 82.686488 -136.251163) (xy 82.744997 -136.313939) (xy 82.79737 -136.381919)
			(xy 82.843148 -136.454504) (xy 82.881928 -136.531056) (xy 82.913369 -136.610904) (xy 82.937195 -136.693345)
			(xy 82.953196 -136.777655) (xy 82.961231 -136.863093) (xy 82.961734 -136.906) (xy 82.961231 -136.948907)
			(xy 82.960261 -136.959223) (xy 85.624405 -136.959223) (xy 85.624405 -136.852777) (xy 85.63236 -136.746629)
			(xy 85.648225 -136.641372) (xy 85.671911 -136.537595) (xy 85.703287 -136.435879) (xy 85.742176 -136.336791)
			(xy 85.788361 -136.240887) (xy 85.841584 -136.148702) (xy 85.901547 -136.060753) (xy 85.967915 -135.97753)
			(xy 86.040316 -135.8995) (xy 86.118346 -135.827099) (xy 86.201569 -135.760731) (xy 86.289518 -135.700768)
			(xy 86.381703 -135.647545) (xy 86.477607 -135.60136) (xy 86.576695 -135.562471) (xy 86.678411 -135.531095)
			(xy 86.782188 -135.507409) (xy 86.887445 -135.491544) (xy 86.993593 -135.483589) (xy 87.100039 -135.483589)
			(xy 87.206187 -135.491544) (xy 87.311444 -135.507409) (xy 87.415221 -135.531095) (xy 87.516937 -135.562471)
			(xy 87.616025 -135.60136) (xy 87.711929 -135.647545) (xy 87.804114 -135.700768) (xy 87.892063 -135.760731)
			(xy 87.975286 -135.827099) (xy 88.053316 -135.8995) (xy 88.125717 -135.97753) (xy 88.192085 -136.060753)
			(xy 88.252048 -136.148702) (xy 88.305271 -136.240887) (xy 88.351456 -136.336791) (xy 88.390345 -136.435879)
			(xy 88.421721 -136.537595) (xy 88.445407 -136.641372) (xy 88.461272 -136.746629) (xy 88.469227 -136.852777)
			(xy 88.469724 -136.906) (xy 93.323415 -136.906) (xy 93.327437 -136.82028) (xy 93.339468 -136.735312)
			(xy 93.359404 -136.651845) (xy 93.387067 -136.570611) (xy 93.422216 -136.492325) (xy 93.464542 -136.417674)
			(xy 93.513671 -136.347315) (xy 93.569174 -136.281865) (xy 93.630561 -136.221901) (xy 93.697294 -136.167948)
			(xy 93.768786 -136.120481) (xy 93.844408 -136.079917) (xy 93.923497 -136.046613) (xy 94.005357 -136.020861)
			(xy 94.089268 -136.002888) (xy 94.174494 -135.992852) (xy 94.260286 -135.99084) (xy 94.345888 -135.996871)
			(xy 94.43055 -136.010891) (xy 94.513527 -136.032777) (xy 94.59409 -136.062338) (xy 94.67153 -136.099312)
			(xy 94.745169 -136.143376) (xy 94.814357 -136.194142) (xy 94.878488 -136.251163) (xy 94.936997 -136.313939)
			(xy 94.98937 -136.381919) (xy 95.035148 -136.454504) (xy 95.073928 -136.531056) (xy 95.105369 -136.610904)
			(xy 95.129195 -136.693345) (xy 95.145196 -136.777655) (xy 95.153231 -136.863093) (xy 95.153734 -136.906)
			(xy 95.153231 -136.948907) (xy 95.152261 -136.959223) (xy 97.816405 -136.959223) (xy 97.816405 -136.852777)
			(xy 97.82436 -136.746629) (xy 97.840225 -136.641372) (xy 97.863911 -136.537595) (xy 97.895287 -136.435879)
			(xy 97.934176 -136.336791) (xy 97.980361 -136.240887) (xy 98.033584 -136.148702) (xy 98.093547 -136.060753)
			(xy 98.159915 -135.97753) (xy 98.232316 -135.8995) (xy 98.310346 -135.827099) (xy 98.393569 -135.760731)
			(xy 98.481518 -135.700768) (xy 98.573703 -135.647545) (xy 98.669607 -135.60136) (xy 98.768695 -135.562471)
			(xy 98.870411 -135.531095) (xy 98.974188 -135.507409) (xy 99.079445 -135.491544) (xy 99.185593 -135.483589)
			(xy 99.292039 -135.483589) (xy 99.398187 -135.491544) (xy 99.503444 -135.507409) (xy 99.607221 -135.531095)
			(xy 99.708937 -135.562471) (xy 99.808025 -135.60136) (xy 99.903929 -135.647545) (xy 99.996114 -135.700768)
			(xy 100.084063 -135.760731) (xy 100.167286 -135.827099) (xy 100.245316 -135.8995) (xy 100.317717 -135.97753)
			(xy 100.384085 -136.060753) (xy 100.444048 -136.148702) (xy 100.497271 -136.240887) (xy 100.543456 -136.336791)
			(xy 100.582345 -136.435879) (xy 100.613721 -136.537595) (xy 100.637407 -136.641372) (xy 100.653272 -136.746629)
			(xy 100.661227 -136.852777) (xy 100.661724 -136.906) (xy 105.515415 -136.906) (xy 105.519437 -136.82028)
			(xy 105.531468 -136.735312) (xy 105.551404 -136.651845) (xy 105.579067 -136.570611) (xy 105.614216 -136.492325)
			(xy 105.656542 -136.417674) (xy 105.705671 -136.347315) (xy 105.761174 -136.281865) (xy 105.822561 -136.221901)
			(xy 105.889294 -136.167948) (xy 105.960786 -136.120481) (xy 106.036408 -136.079917) (xy 106.115497 -136.046613)
			(xy 106.197357 -136.020861) (xy 106.281268 -136.002888) (xy 106.366494 -135.992852) (xy 106.452286 -135.99084)
			(xy 106.537888 -135.996871) (xy 106.62255 -136.010891) (xy 106.705527 -136.032777) (xy 106.78609 -136.062338)
			(xy 106.86353 -136.099312) (xy 106.937169 -136.143376) (xy 107.006357 -136.194142) (xy 107.070488 -136.251163)
			(xy 107.128997 -136.313939) (xy 107.18137 -136.381919) (xy 107.227148 -136.454504) (xy 107.265928 -136.531056)
			(xy 107.297369 -136.610904) (xy 107.321195 -136.693345) (xy 107.337196 -136.777655) (xy 107.345231 -136.863093)
			(xy 107.345734 -136.906) (xy 107.345231 -136.948907) (xy 107.344261 -136.959223) (xy 110.008405 -136.959223)
			(xy 110.008405 -136.852777) (xy 110.01636 -136.746629) (xy 110.032225 -136.641372) (xy 110.055911 -136.537595)
			(xy 110.087287 -136.435879) (xy 110.126176 -136.336791) (xy 110.172361 -136.240887) (xy 110.225584 -136.148702)
			(xy 110.285547 -136.060753) (xy 110.351915 -135.97753) (xy 110.424316 -135.8995) (xy 110.502346 -135.827099)
			(xy 110.585569 -135.760731) (xy 110.673518 -135.700768) (xy 110.765703 -135.647545) (xy 110.861607 -135.60136)
			(xy 110.960695 -135.562471) (xy 111.062411 -135.531095) (xy 111.166188 -135.507409) (xy 111.271445 -135.491544)
			(xy 111.377593 -135.483589) (xy 111.484039 -135.483589) (xy 111.590187 -135.491544) (xy 111.695444 -135.507409)
			(xy 111.799221 -135.531095) (xy 111.900937 -135.562471) (xy 112.000025 -135.60136) (xy 112.095929 -135.647545)
			(xy 112.188114 -135.700768) (xy 112.276063 -135.760731) (xy 112.359286 -135.827099) (xy 112.437316 -135.8995)
			(xy 112.509717 -135.97753) (xy 112.576085 -136.060753) (xy 112.636048 -136.148702) (xy 112.689271 -136.240887)
			(xy 112.735456 -136.336791) (xy 112.774345 -136.435879) (xy 112.805721 -136.537595) (xy 112.829407 -136.641372)
			(xy 112.845272 -136.746629) (xy 112.853227 -136.852777) (xy 112.853724 -136.906) (xy 121.131589 -136.906)
			(xy 121.135611 -136.82028) (xy 121.147642 -136.735312) (xy 121.167578 -136.651845) (xy 121.195241 -136.570611)
			(xy 121.23039 -136.492325) (xy 121.272716 -136.417674) (xy 121.321845 -136.347315) (xy 121.377348 -136.281865)
			(xy 121.438735 -136.221901) (xy 121.505468 -136.167948) (xy 121.57696 -136.120481) (xy 121.652582 -136.079917)
			(xy 121.731671 -136.046613) (xy 121.813531 -136.020861) (xy 121.897442 -136.002888) (xy 121.982668 -135.992852)
			(xy 122.06846 -135.99084) (xy 122.154062 -135.996871) (xy 122.238724 -136.010891) (xy 122.321701 -136.032777)
			(xy 122.402264 -136.062338) (xy 122.479704 -136.099312) (xy 122.553343 -136.143376) (xy 122.622531 -136.194142)
			(xy 122.686662 -136.251163) (xy 122.745171 -136.313939) (xy 122.797544 -136.381919) (xy 122.843322 -136.454504)
			(xy 122.882102 -136.531056) (xy 122.913543 -136.610904) (xy 122.937369 -136.693345) (xy 122.95337 -136.777655)
			(xy 122.961405 -136.863093) (xy 122.961908 -136.906) (xy 122.961405 -136.948907) (xy 122.960435 -136.959223)
			(xy 125.624579 -136.959223) (xy 125.624579 -136.852777) (xy 125.632534 -136.746629) (xy 125.648399 -136.641372)
			(xy 125.672085 -136.537595) (xy 125.703461 -136.435879) (xy 125.74235 -136.336791) (xy 125.788535 -136.240887)
			(xy 125.841758 -136.148702) (xy 125.901721 -136.060753) (xy 125.968089 -135.97753) (xy 126.04049 -135.8995)
			(xy 126.11852 -135.827099) (xy 126.201743 -135.760731) (xy 126.289692 -135.700768) (xy 126.381877 -135.647545)
			(xy 126.477781 -135.60136) (xy 126.576869 -135.562471) (xy 126.678585 -135.531095) (xy 126.782362 -135.507409)
			(xy 126.887619 -135.491544) (xy 126.993767 -135.483589) (xy 127.100213 -135.483589) (xy 127.206361 -135.491544)
			(xy 127.311618 -135.507409) (xy 127.415395 -135.531095) (xy 127.517111 -135.562471) (xy 127.616199 -135.60136)
			(xy 127.712103 -135.647545) (xy 127.804288 -135.700768) (xy 127.892237 -135.760731) (xy 127.97546 -135.827099)
			(xy 128.05349 -135.8995) (xy 128.125891 -135.97753) (xy 128.192259 -136.060753) (xy 128.252222 -136.148702)
			(xy 128.305445 -136.240887) (xy 128.35163 -136.336791) (xy 128.390519 -136.435879) (xy 128.421895 -136.537595)
			(xy 128.445581 -136.641372) (xy 128.461446 -136.746629) (xy 128.469401 -136.852777) (xy 128.469898 -136.906)
			(xy 133.323589 -136.906) (xy 133.327611 -136.82028) (xy 133.339642 -136.735312) (xy 133.359578 -136.651845)
			(xy 133.387241 -136.570611) (xy 133.42239 -136.492325) (xy 133.464716 -136.417674) (xy 133.513845 -136.347315)
			(xy 133.569348 -136.281865) (xy 133.630735 -136.221901) (xy 133.697468 -136.167948) (xy 133.76896 -136.120481)
			(xy 133.844582 -136.079917) (xy 133.923671 -136.046613) (xy 134.005531 -136.020861) (xy 134.089442 -136.002888)
			(xy 134.174668 -135.992852) (xy 134.26046 -135.99084) (xy 134.346062 -135.996871) (xy 134.430724 -136.010891)
			(xy 134.513701 -136.032777) (xy 134.594264 -136.062338) (xy 134.671704 -136.099312) (xy 134.745343 -136.143376)
			(xy 134.814531 -136.194142) (xy 134.878662 -136.251163) (xy 134.937171 -136.313939) (xy 134.989544 -136.381919)
			(xy 135.035322 -136.454504) (xy 135.074102 -136.531056) (xy 135.105543 -136.610904) (xy 135.129369 -136.693345)
			(xy 135.14537 -136.777655) (xy 135.153405 -136.863093) (xy 135.153908 -136.906) (xy 135.153405 -136.948907)
			(xy 135.152435 -136.959223) (xy 137.816579 -136.959223) (xy 137.816579 -136.852777) (xy 137.824534 -136.746629)
			(xy 137.840399 -136.641372) (xy 137.864085 -136.537595) (xy 137.895461 -136.435879) (xy 137.93435 -136.336791)
			(xy 137.980535 -136.240887) (xy 138.033758 -136.148702) (xy 138.093721 -136.060753) (xy 138.160089 -135.97753)
			(xy 138.23249 -135.8995) (xy 138.31052 -135.827099) (xy 138.393743 -135.760731) (xy 138.481692 -135.700768)
			(xy 138.573877 -135.647545) (xy 138.669781 -135.60136) (xy 138.768869 -135.562471) (xy 138.870585 -135.531095)
			(xy 138.974362 -135.507409) (xy 139.079619 -135.491544) (xy 139.185767 -135.483589) (xy 139.292213 -135.483589)
			(xy 139.398361 -135.491544) (xy 139.503618 -135.507409) (xy 139.607395 -135.531095) (xy 139.709111 -135.562471)
			(xy 139.808199 -135.60136) (xy 139.904103 -135.647545) (xy 139.996288 -135.700768) (xy 140.084237 -135.760731)
			(xy 140.16746 -135.827099) (xy 140.24549 -135.8995) (xy 140.317891 -135.97753) (xy 140.384259 -136.060753)
			(xy 140.444222 -136.148702) (xy 140.497445 -136.240887) (xy 140.54363 -136.336791) (xy 140.582519 -136.435879)
			(xy 140.613895 -136.537595) (xy 140.637581 -136.641372) (xy 140.653446 -136.746629) (xy 140.661401 -136.852777)
			(xy 140.661898 -136.906) (xy 145.515589 -136.906) (xy 145.519611 -136.82028) (xy 145.531642 -136.735312)
			(xy 145.551578 -136.651845) (xy 145.579241 -136.570611) (xy 145.61439 -136.492325) (xy 145.656716 -136.417674)
			(xy 145.705845 -136.347315) (xy 145.761348 -136.281865) (xy 145.822735 -136.221901) (xy 145.889468 -136.167948)
			(xy 145.96096 -136.120481) (xy 146.036582 -136.079917) (xy 146.115671 -136.046613) (xy 146.197531 -136.020861)
			(xy 146.281442 -136.002888) (xy 146.366668 -135.992852) (xy 146.45246 -135.99084) (xy 146.538062 -135.996871)
			(xy 146.622724 -136.010891) (xy 146.705701 -136.032777) (xy 146.786264 -136.062338) (xy 146.863704 -136.099312)
			(xy 146.937343 -136.143376) (xy 147.006531 -136.194142) (xy 147.070662 -136.251163) (xy 147.129171 -136.313939)
			(xy 147.181544 -136.381919) (xy 147.227322 -136.454504) (xy 147.266102 -136.531056) (xy 147.297543 -136.610904)
			(xy 147.321369 -136.693345) (xy 147.33737 -136.777655) (xy 147.345405 -136.863093) (xy 147.345908 -136.906)
			(xy 147.345405 -136.948907) (xy 147.344435 -136.959223) (xy 150.008579 -136.959223) (xy 150.008579 -136.852777)
			(xy 150.016534 -136.746629) (xy 150.032399 -136.641372) (xy 150.056085 -136.537595) (xy 150.087461 -136.435879)
			(xy 150.12635 -136.336791) (xy 150.172535 -136.240887) (xy 150.225758 -136.148702) (xy 150.285721 -136.060753)
			(xy 150.352089 -135.97753) (xy 150.42449 -135.8995) (xy 150.50252 -135.827099) (xy 150.585743 -135.760731)
			(xy 150.673692 -135.700768) (xy 150.765877 -135.647545) (xy 150.861781 -135.60136) (xy 150.960869 -135.562471)
			(xy 151.062585 -135.531095) (xy 151.166362 -135.507409) (xy 151.271619 -135.491544) (xy 151.377767 -135.483589)
			(xy 151.484213 -135.483589) (xy 151.590361 -135.491544) (xy 151.695618 -135.507409) (xy 151.799395 -135.531095)
			(xy 151.901111 -135.562471) (xy 152.000199 -135.60136) (xy 152.096103 -135.647545) (xy 152.188288 -135.700768)
			(xy 152.276237 -135.760731) (xy 152.35946 -135.827099) (xy 152.43749 -135.8995) (xy 152.509891 -135.97753)
			(xy 152.576259 -136.060753) (xy 152.636222 -136.148702) (xy 152.689445 -136.240887) (xy 152.73563 -136.336791)
			(xy 152.774519 -136.435879) (xy 152.805895 -136.537595) (xy 152.829581 -136.641372) (xy 152.845446 -136.746629)
			(xy 152.853401 -136.852777) (xy 152.853898 -136.906) (xy 161.131763 -136.906) (xy 161.135785 -136.82028)
			(xy 161.147816 -136.735312) (xy 161.167752 -136.651845) (xy 161.195415 -136.570611) (xy 161.230564 -136.492325)
			(xy 161.27289 -136.417674) (xy 161.322019 -136.347315) (xy 161.377522 -136.281865) (xy 161.438909 -136.221901)
			(xy 161.505642 -136.167948) (xy 161.577134 -136.120481) (xy 161.652756 -136.079917) (xy 161.731845 -136.046613)
			(xy 161.813705 -136.020861) (xy 161.897616 -136.002888) (xy 161.982842 -135.992852) (xy 162.068634 -135.99084)
			(xy 162.154236 -135.996871) (xy 162.238898 -136.010891) (xy 162.321875 -136.032777) (xy 162.402438 -136.062338)
			(xy 162.479878 -136.099312) (xy 162.553517 -136.143376) (xy 162.622705 -136.194142) (xy 162.686836 -136.251163)
			(xy 162.745345 -136.313939) (xy 162.797718 -136.381919) (xy 162.843496 -136.454504) (xy 162.882276 -136.531056)
			(xy 162.913717 -136.610904) (xy 162.937543 -136.693345) (xy 162.953544 -136.777655) (xy 162.961579 -136.863093)
			(xy 162.962082 -136.906) (xy 162.961579 -136.948907) (xy 162.960609 -136.959223) (xy 165.624753 -136.959223)
			(xy 165.624753 -136.852777) (xy 165.632708 -136.746629) (xy 165.648573 -136.641372) (xy 165.672259 -136.537595)
			(xy 165.703635 -136.435879) (xy 165.742524 -136.336791) (xy 165.788709 -136.240887) (xy 165.841932 -136.148702)
			(xy 165.901895 -136.060753) (xy 165.968263 -135.97753) (xy 166.040664 -135.8995) (xy 166.118694 -135.827099)
			(xy 166.201917 -135.760731) (xy 166.289866 -135.700768) (xy 166.382051 -135.647545) (xy 166.477955 -135.60136)
			(xy 166.577043 -135.562471) (xy 166.678759 -135.531095) (xy 166.782536 -135.507409) (xy 166.887793 -135.491544)
			(xy 166.993941 -135.483589) (xy 167.100387 -135.483589) (xy 167.206535 -135.491544) (xy 167.311792 -135.507409)
			(xy 167.415569 -135.531095) (xy 167.517285 -135.562471) (xy 167.616373 -135.60136) (xy 167.712277 -135.647545)
			(xy 167.804462 -135.700768) (xy 167.892411 -135.760731) (xy 167.975634 -135.827099) (xy 168.053664 -135.8995)
			(xy 168.126065 -135.97753) (xy 168.192433 -136.060753) (xy 168.252396 -136.148702) (xy 168.305619 -136.240887)
			(xy 168.351804 -136.336791) (xy 168.390693 -136.435879) (xy 168.422069 -136.537595) (xy 168.445755 -136.641372)
			(xy 168.46162 -136.746629) (xy 168.469575 -136.852777) (xy 168.470072 -136.906) (xy 173.323763 -136.906)
			(xy 173.327785 -136.82028) (xy 173.339816 -136.735312) (xy 173.359752 -136.651845) (xy 173.387415 -136.570611)
			(xy 173.422564 -136.492325) (xy 173.46489 -136.417674) (xy 173.514019 -136.347315) (xy 173.569522 -136.281865)
			(xy 173.630909 -136.221901) (xy 173.697642 -136.167948) (xy 173.769134 -136.120481) (xy 173.844756 -136.079917)
			(xy 173.923845 -136.046613) (xy 174.005705 -136.020861) (xy 174.089616 -136.002888) (xy 174.174842 -135.992852)
			(xy 174.260634 -135.99084) (xy 174.346236 -135.996871) (xy 174.430898 -136.010891) (xy 174.513875 -136.032777)
			(xy 174.594438 -136.062338) (xy 174.671878 -136.099312) (xy 174.745517 -136.143376) (xy 174.814705 -136.194142)
			(xy 174.878836 -136.251163) (xy 174.937345 -136.313939) (xy 174.989718 -136.381919) (xy 175.035496 -136.454504)
			(xy 175.074276 -136.531056) (xy 175.105717 -136.610904) (xy 175.129543 -136.693345) (xy 175.145544 -136.777655)
			(xy 175.153579 -136.863093) (xy 175.154082 -136.906) (xy 175.153579 -136.948907) (xy 175.152609 -136.959223)
			(xy 177.816753 -136.959223) (xy 177.816753 -136.852777) (xy 177.824708 -136.746629) (xy 177.840573 -136.641372)
			(xy 177.864259 -136.537595) (xy 177.895635 -136.435879) (xy 177.934524 -136.336791) (xy 177.980709 -136.240887)
			(xy 178.033932 -136.148702) (xy 178.093895 -136.060753) (xy 178.160263 -135.97753) (xy 178.232664 -135.8995)
			(xy 178.310694 -135.827099) (xy 178.393917 -135.760731) (xy 178.481866 -135.700768) (xy 178.574051 -135.647545)
			(xy 178.669955 -135.60136) (xy 178.769043 -135.562471) (xy 178.870759 -135.531095) (xy 178.974536 -135.507409)
			(xy 179.079793 -135.491544) (xy 179.185941 -135.483589) (xy 179.292387 -135.483589) (xy 179.398535 -135.491544)
			(xy 179.503792 -135.507409) (xy 179.607569 -135.531095) (xy 179.709285 -135.562471) (xy 179.808373 -135.60136)
			(xy 179.904277 -135.647545) (xy 179.996462 -135.700768) (xy 180.084411 -135.760731) (xy 180.167634 -135.827099)
			(xy 180.245664 -135.8995) (xy 180.318065 -135.97753) (xy 180.384433 -136.060753) (xy 180.444396 -136.148702)
			(xy 180.497619 -136.240887) (xy 180.543804 -136.336791) (xy 180.582693 -136.435879) (xy 180.614069 -136.537595)
			(xy 180.637755 -136.641372) (xy 180.65362 -136.746629) (xy 180.661575 -136.852777) (xy 180.662072 -136.906)
			(xy 185.515763 -136.906) (xy 185.519785 -136.82028) (xy 185.531816 -136.735312) (xy 185.551752 -136.651845)
			(xy 185.579415 -136.570611) (xy 185.614564 -136.492325) (xy 185.65689 -136.417674) (xy 185.706019 -136.347315)
			(xy 185.761522 -136.281865) (xy 185.822909 -136.221901) (xy 185.889642 -136.167948) (xy 185.961134 -136.120481)
			(xy 186.036756 -136.079917) (xy 186.115845 -136.046613) (xy 186.197705 -136.020861) (xy 186.281616 -136.002888)
			(xy 186.366842 -135.992852) (xy 186.452634 -135.99084) (xy 186.538236 -135.996871) (xy 186.622898 -136.010891)
			(xy 186.705875 -136.032777) (xy 186.786438 -136.062338) (xy 186.863878 -136.099312) (xy 186.937517 -136.143376)
			(xy 187.006705 -136.194142) (xy 187.070836 -136.251163) (xy 187.129345 -136.313939) (xy 187.181718 -136.381919)
			(xy 187.227496 -136.454504) (xy 187.266276 -136.531056) (xy 187.297717 -136.610904) (xy 187.321543 -136.693345)
			(xy 187.337544 -136.777655) (xy 187.345579 -136.863093) (xy 187.346082 -136.906) (xy 187.345579 -136.948907)
			(xy 187.344609 -136.959223) (xy 190.008753 -136.959223) (xy 190.008753 -136.852777) (xy 190.016708 -136.746629)
			(xy 190.032573 -136.641372) (xy 190.056259 -136.537595) (xy 190.087635 -136.435879) (xy 190.126524 -136.336791)
			(xy 190.172709 -136.240887) (xy 190.225932 -136.148702) (xy 190.285895 -136.060753) (xy 190.352263 -135.97753)
			(xy 190.424664 -135.8995) (xy 190.502694 -135.827099) (xy 190.585917 -135.760731) (xy 190.673866 -135.700768)
			(xy 190.766051 -135.647545) (xy 190.861955 -135.60136) (xy 190.961043 -135.562471) (xy 191.062759 -135.531095)
			(xy 191.166536 -135.507409) (xy 191.271793 -135.491544) (xy 191.377941 -135.483589) (xy 191.484387 -135.483589)
			(xy 191.590535 -135.491544) (xy 191.695792 -135.507409) (xy 191.799569 -135.531095) (xy 191.901285 -135.562471)
			(xy 192.000373 -135.60136) (xy 192.096277 -135.647545) (xy 192.188462 -135.700768) (xy 192.276411 -135.760731)
			(xy 192.359634 -135.827099) (xy 192.437664 -135.8995) (xy 192.510065 -135.97753) (xy 192.576433 -136.060753)
			(xy 192.636396 -136.148702) (xy 192.689619 -136.240887) (xy 192.735804 -136.336791) (xy 192.774693 -136.435879)
			(xy 192.806069 -136.537595) (xy 192.829755 -136.641372) (xy 192.84562 -136.746629) (xy 192.853575 -136.852777)
			(xy 192.854072 -136.906) (xy 192.853575 -136.959223) (xy 192.84562 -137.065371) (xy 192.829755 -137.170628)
			(xy 192.806069 -137.274405) (xy 192.774693 -137.376121) (xy 192.735804 -137.475209) (xy 192.689619 -137.571113)
			(xy 192.636396 -137.663298) (xy 192.576433 -137.751247) (xy 192.510065 -137.83447) (xy 192.437664 -137.9125)
			(xy 192.359634 -137.984901) (xy 192.276411 -138.051269) (xy 192.188462 -138.111232) (xy 192.096277 -138.164455)
			(xy 192.000373 -138.21064) (xy 191.901285 -138.249529) (xy 191.799569 -138.280905) (xy 191.695792 -138.304591)
			(xy 191.590535 -138.320456) (xy 191.484387 -138.328411) (xy 191.377941 -138.328411) (xy 191.271793 -138.320456)
			(xy 191.166536 -138.304591) (xy 191.062759 -138.280905) (xy 190.961043 -138.249529) (xy 190.861955 -138.21064)
			(xy 190.766051 -138.164455) (xy 190.673866 -138.111232) (xy 190.585917 -138.051269) (xy 190.502694 -137.984901)
			(xy 190.424664 -137.9125) (xy 190.352263 -137.83447) (xy 190.285895 -137.751247) (xy 190.225932 -137.663298)
			(xy 190.172709 -137.571113) (xy 190.126524 -137.475209) (xy 190.087635 -137.376121) (xy 190.056259 -137.274405)
			(xy 190.032573 -137.170628) (xy 190.016708 -137.065371) (xy 190.008753 -136.959223) (xy 187.344609 -136.959223)
			(xy 187.337544 -137.034345) (xy 187.321543 -137.118655) (xy 187.297717 -137.201096) (xy 187.266276 -137.280944)
			(xy 187.227496 -137.357496) (xy 187.181718 -137.430081) (xy 187.129345 -137.498061) (xy 187.070836 -137.560837)
			(xy 187.006705 -137.617858) (xy 186.937517 -137.668624) (xy 186.863878 -137.712688) (xy 186.786438 -137.749662)
			(xy 186.705875 -137.779223) (xy 186.622898 -137.801109) (xy 186.538236 -137.815129) (xy 186.452634 -137.82116)
			(xy 186.366842 -137.819148) (xy 186.281616 -137.809112) (xy 186.197705 -137.791139) (xy 186.115845 -137.765387)
			(xy 186.036756 -137.732083) (xy 185.961134 -137.691519) (xy 185.889642 -137.644052) (xy 185.822909 -137.590099)
			(xy 185.761522 -137.530135) (xy 185.706019 -137.464685) (xy 185.65689 -137.394326) (xy 185.614564 -137.319675)
			(xy 185.579415 -137.241389) (xy 185.551752 -137.160155) (xy 185.531816 -137.076688) (xy 185.519785 -136.99172)
			(xy 185.515763 -136.906) (xy 180.662072 -136.906) (xy 180.661575 -136.959223) (xy 180.65362 -137.065371)
			(xy 180.637755 -137.170628) (xy 180.614069 -137.274405) (xy 180.582693 -137.376121) (xy 180.543804 -137.475209)
			(xy 180.497619 -137.571113) (xy 180.444396 -137.663298) (xy 180.384433 -137.751247) (xy 180.318065 -137.83447)
			(xy 180.245664 -137.9125) (xy 180.167634 -137.984901) (xy 180.084411 -138.051269) (xy 179.996462 -138.111232)
			(xy 179.904277 -138.164455) (xy 179.808373 -138.21064) (xy 179.709285 -138.249529) (xy 179.607569 -138.280905)
			(xy 179.503792 -138.304591) (xy 179.398535 -138.320456) (xy 179.292387 -138.328411) (xy 179.185941 -138.328411)
			(xy 179.079793 -138.320456) (xy 178.974536 -138.304591) (xy 178.870759 -138.280905) (xy 178.769043 -138.249529)
			(xy 178.669955 -138.21064) (xy 178.574051 -138.164455) (xy 178.481866 -138.111232) (xy 178.393917 -138.051269)
			(xy 178.310694 -137.984901) (xy 178.232664 -137.9125) (xy 178.160263 -137.83447) (xy 178.093895 -137.751247)
			(xy 178.033932 -137.663298) (xy 177.980709 -137.571113) (xy 177.934524 -137.475209) (xy 177.895635 -137.376121)
			(xy 177.864259 -137.274405) (xy 177.840573 -137.170628) (xy 177.824708 -137.065371) (xy 177.816753 -136.959223)
			(xy 175.152609 -136.959223) (xy 175.145544 -137.034345) (xy 175.129543 -137.118655) (xy 175.105717 -137.201096)
			(xy 175.074276 -137.280944) (xy 175.035496 -137.357496) (xy 174.989718 -137.430081) (xy 174.937345 -137.498061)
			(xy 174.878836 -137.560837) (xy 174.814705 -137.617858) (xy 174.745517 -137.668624) (xy 174.671878 -137.712688)
			(xy 174.594438 -137.749662) (xy 174.513875 -137.779223) (xy 174.430898 -137.801109) (xy 174.346236 -137.815129)
			(xy 174.260634 -137.82116) (xy 174.174842 -137.819148) (xy 174.089616 -137.809112) (xy 174.005705 -137.791139)
			(xy 173.923845 -137.765387) (xy 173.844756 -137.732083) (xy 173.769134 -137.691519) (xy 173.697642 -137.644052)
			(xy 173.630909 -137.590099) (xy 173.569522 -137.530135) (xy 173.514019 -137.464685) (xy 173.46489 -137.394326)
			(xy 173.422564 -137.319675) (xy 173.387415 -137.241389) (xy 173.359752 -137.160155) (xy 173.339816 -137.076688)
			(xy 173.327785 -136.99172) (xy 173.323763 -136.906) (xy 168.470072 -136.906) (xy 168.469575 -136.959223)
			(xy 168.46162 -137.065371) (xy 168.445755 -137.170628) (xy 168.422069 -137.274405) (xy 168.390693 -137.376121)
			(xy 168.351804 -137.475209) (xy 168.305619 -137.571113) (xy 168.252396 -137.663298) (xy 168.192433 -137.751247)
			(xy 168.126065 -137.83447) (xy 168.053664 -137.9125) (xy 167.975634 -137.984901) (xy 167.892411 -138.051269)
			(xy 167.804462 -138.111232) (xy 167.712277 -138.164455) (xy 167.616373 -138.21064) (xy 167.517285 -138.249529)
			(xy 167.415569 -138.280905) (xy 167.311792 -138.304591) (xy 167.206535 -138.320456) (xy 167.100387 -138.328411)
			(xy 166.993941 -138.328411) (xy 166.887793 -138.320456) (xy 166.782536 -138.304591) (xy 166.678759 -138.280905)
			(xy 166.577043 -138.249529) (xy 166.477955 -138.21064) (xy 166.382051 -138.164455) (xy 166.289866 -138.111232)
			(xy 166.201917 -138.051269) (xy 166.118694 -137.984901) (xy 166.040664 -137.9125) (xy 165.968263 -137.83447)
			(xy 165.901895 -137.751247) (xy 165.841932 -137.663298) (xy 165.788709 -137.571113) (xy 165.742524 -137.475209)
			(xy 165.703635 -137.376121) (xy 165.672259 -137.274405) (xy 165.648573 -137.170628) (xy 165.632708 -137.065371)
			(xy 165.624753 -136.959223) (xy 162.960609 -136.959223) (xy 162.953544 -137.034345) (xy 162.937543 -137.118655)
			(xy 162.913717 -137.201096) (xy 162.882276 -137.280944) (xy 162.843496 -137.357496) (xy 162.797718 -137.430081)
			(xy 162.745345 -137.498061) (xy 162.686836 -137.560837) (xy 162.622705 -137.617858) (xy 162.553517 -137.668624)
			(xy 162.479878 -137.712688) (xy 162.402438 -137.749662) (xy 162.321875 -137.779223) (xy 162.238898 -137.801109)
			(xy 162.154236 -137.815129) (xy 162.068634 -137.82116) (xy 161.982842 -137.819148) (xy 161.897616 -137.809112)
			(xy 161.813705 -137.791139) (xy 161.731845 -137.765387) (xy 161.652756 -137.732083) (xy 161.577134 -137.691519)
			(xy 161.505642 -137.644052) (xy 161.438909 -137.590099) (xy 161.377522 -137.530135) (xy 161.322019 -137.464685)
			(xy 161.27289 -137.394326) (xy 161.230564 -137.319675) (xy 161.195415 -137.241389) (xy 161.167752 -137.160155)
			(xy 161.147816 -137.076688) (xy 161.135785 -136.99172) (xy 161.131763 -136.906) (xy 152.853898 -136.906)
			(xy 152.853401 -136.959223) (xy 152.845446 -137.065371) (xy 152.829581 -137.170628) (xy 152.805895 -137.274405)
			(xy 152.774519 -137.376121) (xy 152.73563 -137.475209) (xy 152.689445 -137.571113) (xy 152.636222 -137.663298)
			(xy 152.576259 -137.751247) (xy 152.509891 -137.83447) (xy 152.43749 -137.9125) (xy 152.35946 -137.984901)
			(xy 152.276237 -138.051269) (xy 152.188288 -138.111232) (xy 152.096103 -138.164455) (xy 152.000199 -138.21064)
			(xy 151.901111 -138.249529) (xy 151.799395 -138.280905) (xy 151.695618 -138.304591) (xy 151.590361 -138.320456)
			(xy 151.484213 -138.328411) (xy 151.377767 -138.328411) (xy 151.271619 -138.320456) (xy 151.166362 -138.304591)
			(xy 151.062585 -138.280905) (xy 150.960869 -138.249529) (xy 150.861781 -138.21064) (xy 150.765877 -138.164455)
			(xy 150.673692 -138.111232) (xy 150.585743 -138.051269) (xy 150.50252 -137.984901) (xy 150.42449 -137.9125)
			(xy 150.352089 -137.83447) (xy 150.285721 -137.751247) (xy 150.225758 -137.663298) (xy 150.172535 -137.571113)
			(xy 150.12635 -137.475209) (xy 150.087461 -137.376121) (xy 150.056085 -137.274405) (xy 150.032399 -137.170628)
			(xy 150.016534 -137.065371) (xy 150.008579 -136.959223) (xy 147.344435 -136.959223) (xy 147.33737 -137.034345)
			(xy 147.321369 -137.118655) (xy 147.297543 -137.201096) (xy 147.266102 -137.280944) (xy 147.227322 -137.357496)
			(xy 147.181544 -137.430081) (xy 147.129171 -137.498061) (xy 147.070662 -137.560837) (xy 147.006531 -137.617858)
			(xy 146.937343 -137.668624) (xy 146.863704 -137.712688) (xy 146.786264 -137.749662) (xy 146.705701 -137.779223)
			(xy 146.622724 -137.801109) (xy 146.538062 -137.815129) (xy 146.45246 -137.82116) (xy 146.366668 -137.819148)
			(xy 146.281442 -137.809112) (xy 146.197531 -137.791139) (xy 146.115671 -137.765387) (xy 146.036582 -137.732083)
			(xy 145.96096 -137.691519) (xy 145.889468 -137.644052) (xy 145.822735 -137.590099) (xy 145.761348 -137.530135)
			(xy 145.705845 -137.464685) (xy 145.656716 -137.394326) (xy 145.61439 -137.319675) (xy 145.579241 -137.241389)
			(xy 145.551578 -137.160155) (xy 145.531642 -137.076688) (xy 145.519611 -136.99172) (xy 145.515589 -136.906)
			(xy 140.661898 -136.906) (xy 140.661401 -136.959223) (xy 140.653446 -137.065371) (xy 140.637581 -137.170628)
			(xy 140.613895 -137.274405) (xy 140.582519 -137.376121) (xy 140.54363 -137.475209) (xy 140.497445 -137.571113)
			(xy 140.444222 -137.663298) (xy 140.384259 -137.751247) (xy 140.317891 -137.83447) (xy 140.24549 -137.9125)
			(xy 140.16746 -137.984901) (xy 140.084237 -138.051269) (xy 139.996288 -138.111232) (xy 139.904103 -138.164455)
			(xy 139.808199 -138.21064) (xy 139.709111 -138.249529) (xy 139.607395 -138.280905) (xy 139.503618 -138.304591)
			(xy 139.398361 -138.320456) (xy 139.292213 -138.328411) (xy 139.185767 -138.328411) (xy 139.079619 -138.320456)
			(xy 138.974362 -138.304591) (xy 138.870585 -138.280905) (xy 138.768869 -138.249529) (xy 138.669781 -138.21064)
			(xy 138.573877 -138.164455) (xy 138.481692 -138.111232) (xy 138.393743 -138.051269) (xy 138.31052 -137.984901)
			(xy 138.23249 -137.9125) (xy 138.160089 -137.83447) (xy 138.093721 -137.751247) (xy 138.033758 -137.663298)
			(xy 137.980535 -137.571113) (xy 137.93435 -137.475209) (xy 137.895461 -137.376121) (xy 137.864085 -137.274405)
			(xy 137.840399 -137.170628) (xy 137.824534 -137.065371) (xy 137.816579 -136.959223) (xy 135.152435 -136.959223)
			(xy 135.14537 -137.034345) (xy 135.129369 -137.118655) (xy 135.105543 -137.201096) (xy 135.074102 -137.280944)
			(xy 135.035322 -137.357496) (xy 134.989544 -137.430081) (xy 134.937171 -137.498061) (xy 134.878662 -137.560837)
			(xy 134.814531 -137.617858) (xy 134.745343 -137.668624) (xy 134.671704 -137.712688) (xy 134.594264 -137.749662)
			(xy 134.513701 -137.779223) (xy 134.430724 -137.801109) (xy 134.346062 -137.815129) (xy 134.26046 -137.82116)
			(xy 134.174668 -137.819148) (xy 134.089442 -137.809112) (xy 134.005531 -137.791139) (xy 133.923671 -137.765387)
			(xy 133.844582 -137.732083) (xy 133.76896 -137.691519) (xy 133.697468 -137.644052) (xy 133.630735 -137.590099)
			(xy 133.569348 -137.530135) (xy 133.513845 -137.464685) (xy 133.464716 -137.394326) (xy 133.42239 -137.319675)
			(xy 133.387241 -137.241389) (xy 133.359578 -137.160155) (xy 133.339642 -137.076688) (xy 133.327611 -136.99172)
			(xy 133.323589 -136.906) (xy 128.469898 -136.906) (xy 128.469401 -136.959223) (xy 128.461446 -137.065371)
			(xy 128.445581 -137.170628) (xy 128.421895 -137.274405) (xy 128.390519 -137.376121) (xy 128.35163 -137.475209)
			(xy 128.305445 -137.571113) (xy 128.252222 -137.663298) (xy 128.192259 -137.751247) (xy 128.125891 -137.83447)
			(xy 128.05349 -137.9125) (xy 127.97546 -137.984901) (xy 127.892237 -138.051269) (xy 127.804288 -138.111232)
			(xy 127.712103 -138.164455) (xy 127.616199 -138.21064) (xy 127.517111 -138.249529) (xy 127.415395 -138.280905)
			(xy 127.311618 -138.304591) (xy 127.206361 -138.320456) (xy 127.100213 -138.328411) (xy 126.993767 -138.328411)
			(xy 126.887619 -138.320456) (xy 126.782362 -138.304591) (xy 126.678585 -138.280905) (xy 126.576869 -138.249529)
			(xy 126.477781 -138.21064) (xy 126.381877 -138.164455) (xy 126.289692 -138.111232) (xy 126.201743 -138.051269)
			(xy 126.11852 -137.984901) (xy 126.04049 -137.9125) (xy 125.968089 -137.83447) (xy 125.901721 -137.751247)
			(xy 125.841758 -137.663298) (xy 125.788535 -137.571113) (xy 125.74235 -137.475209) (xy 125.703461 -137.376121)
			(xy 125.672085 -137.274405) (xy 125.648399 -137.170628) (xy 125.632534 -137.065371) (xy 125.624579 -136.959223)
			(xy 122.960435 -136.959223) (xy 122.95337 -137.034345) (xy 122.937369 -137.118655) (xy 122.913543 -137.201096)
			(xy 122.882102 -137.280944) (xy 122.843322 -137.357496) (xy 122.797544 -137.430081) (xy 122.745171 -137.498061)
			(xy 122.686662 -137.560837) (xy 122.622531 -137.617858) (xy 122.553343 -137.668624) (xy 122.479704 -137.712688)
			(xy 122.402264 -137.749662) (xy 122.321701 -137.779223) (xy 122.238724 -137.801109) (xy 122.154062 -137.815129)
			(xy 122.06846 -137.82116) (xy 121.982668 -137.819148) (xy 121.897442 -137.809112) (xy 121.813531 -137.791139)
			(xy 121.731671 -137.765387) (xy 121.652582 -137.732083) (xy 121.57696 -137.691519) (xy 121.505468 -137.644052)
			(xy 121.438735 -137.590099) (xy 121.377348 -137.530135) (xy 121.321845 -137.464685) (xy 121.272716 -137.394326)
			(xy 121.23039 -137.319675) (xy 121.195241 -137.241389) (xy 121.167578 -137.160155) (xy 121.147642 -137.076688)
			(xy 121.135611 -136.99172) (xy 121.131589 -136.906) (xy 112.853724 -136.906) (xy 112.853227 -136.959223)
			(xy 112.845272 -137.065371) (xy 112.829407 -137.170628) (xy 112.805721 -137.274405) (xy 112.774345 -137.376121)
			(xy 112.735456 -137.475209) (xy 112.689271 -137.571113) (xy 112.636048 -137.663298) (xy 112.576085 -137.751247)
			(xy 112.509717 -137.83447) (xy 112.437316 -137.9125) (xy 112.359286 -137.984901) (xy 112.276063 -138.051269)
			(xy 112.188114 -138.111232) (xy 112.095929 -138.164455) (xy 112.000025 -138.21064) (xy 111.900937 -138.249529)
			(xy 111.799221 -138.280905) (xy 111.695444 -138.304591) (xy 111.590187 -138.320456) (xy 111.484039 -138.328411)
			(xy 111.377593 -138.328411) (xy 111.271445 -138.320456) (xy 111.166188 -138.304591) (xy 111.062411 -138.280905)
			(xy 110.960695 -138.249529) (xy 110.861607 -138.21064) (xy 110.765703 -138.164455) (xy 110.673518 -138.111232)
			(xy 110.585569 -138.051269) (xy 110.502346 -137.984901) (xy 110.424316 -137.9125) (xy 110.351915 -137.83447)
			(xy 110.285547 -137.751247) (xy 110.225584 -137.663298) (xy 110.172361 -137.571113) (xy 110.126176 -137.475209)
			(xy 110.087287 -137.376121) (xy 110.055911 -137.274405) (xy 110.032225 -137.170628) (xy 110.01636 -137.065371)
			(xy 110.008405 -136.959223) (xy 107.344261 -136.959223) (xy 107.337196 -137.034345) (xy 107.321195 -137.118655)
			(xy 107.297369 -137.201096) (xy 107.265928 -137.280944) (xy 107.227148 -137.357496) (xy 107.18137 -137.430081)
			(xy 107.128997 -137.498061) (xy 107.070488 -137.560837) (xy 107.006357 -137.617858) (xy 106.937169 -137.668624)
			(xy 106.86353 -137.712688) (xy 106.78609 -137.749662) (xy 106.705527 -137.779223) (xy 106.62255 -137.801109)
			(xy 106.537888 -137.815129) (xy 106.452286 -137.82116) (xy 106.366494 -137.819148) (xy 106.281268 -137.809112)
			(xy 106.197357 -137.791139) (xy 106.115497 -137.765387) (xy 106.036408 -137.732083) (xy 105.960786 -137.691519)
			(xy 105.889294 -137.644052) (xy 105.822561 -137.590099) (xy 105.761174 -137.530135) (xy 105.705671 -137.464685)
			(xy 105.656542 -137.394326) (xy 105.614216 -137.319675) (xy 105.579067 -137.241389) (xy 105.551404 -137.160155)
			(xy 105.531468 -137.076688) (xy 105.519437 -136.99172) (xy 105.515415 -136.906) (xy 100.661724 -136.906)
			(xy 100.661227 -136.959223) (xy 100.653272 -137.065371) (xy 100.637407 -137.170628) (xy 100.613721 -137.274405)
			(xy 100.582345 -137.376121) (xy 100.543456 -137.475209) (xy 100.497271 -137.571113) (xy 100.444048 -137.663298)
			(xy 100.384085 -137.751247) (xy 100.317717 -137.83447) (xy 100.245316 -137.9125) (xy 100.167286 -137.984901)
			(xy 100.084063 -138.051269) (xy 99.996114 -138.111232) (xy 99.903929 -138.164455) (xy 99.808025 -138.21064)
			(xy 99.708937 -138.249529) (xy 99.607221 -138.280905) (xy 99.503444 -138.304591) (xy 99.398187 -138.320456)
			(xy 99.292039 -138.328411) (xy 99.185593 -138.328411) (xy 99.079445 -138.320456) (xy 98.974188 -138.304591)
			(xy 98.870411 -138.280905) (xy 98.768695 -138.249529) (xy 98.669607 -138.21064) (xy 98.573703 -138.164455)
			(xy 98.481518 -138.111232) (xy 98.393569 -138.051269) (xy 98.310346 -137.984901) (xy 98.232316 -137.9125)
			(xy 98.159915 -137.83447) (xy 98.093547 -137.751247) (xy 98.033584 -137.663298) (xy 97.980361 -137.571113)
			(xy 97.934176 -137.475209) (xy 97.895287 -137.376121) (xy 97.863911 -137.274405) (xy 97.840225 -137.170628)
			(xy 97.82436 -137.065371) (xy 97.816405 -136.959223) (xy 95.152261 -136.959223) (xy 95.145196 -137.034345)
			(xy 95.129195 -137.118655) (xy 95.105369 -137.201096) (xy 95.073928 -137.280944) (xy 95.035148 -137.357496)
			(xy 94.98937 -137.430081) (xy 94.936997 -137.498061) (xy 94.878488 -137.560837) (xy 94.814357 -137.617858)
			(xy 94.745169 -137.668624) (xy 94.67153 -137.712688) (xy 94.59409 -137.749662) (xy 94.513527 -137.779223)
			(xy 94.43055 -137.801109) (xy 94.345888 -137.815129) (xy 94.260286 -137.82116) (xy 94.174494 -137.819148)
			(xy 94.089268 -137.809112) (xy 94.005357 -137.791139) (xy 93.923497 -137.765387) (xy 93.844408 -137.732083)
			(xy 93.768786 -137.691519) (xy 93.697294 -137.644052) (xy 93.630561 -137.590099) (xy 93.569174 -137.530135)
			(xy 93.513671 -137.464685) (xy 93.464542 -137.394326) (xy 93.422216 -137.319675) (xy 93.387067 -137.241389)
			(xy 93.359404 -137.160155) (xy 93.339468 -137.076688) (xy 93.327437 -136.99172) (xy 93.323415 -136.906)
			(xy 88.469724 -136.906) (xy 88.469227 -136.959223) (xy 88.461272 -137.065371) (xy 88.445407 -137.170628)
			(xy 88.421721 -137.274405) (xy 88.390345 -137.376121) (xy 88.351456 -137.475209) (xy 88.305271 -137.571113)
			(xy 88.252048 -137.663298) (xy 88.192085 -137.751247) (xy 88.125717 -137.83447) (xy 88.053316 -137.9125)
			(xy 87.975286 -137.984901) (xy 87.892063 -138.051269) (xy 87.804114 -138.111232) (xy 87.711929 -138.164455)
			(xy 87.616025 -138.21064) (xy 87.516937 -138.249529) (xy 87.415221 -138.280905) (xy 87.311444 -138.304591)
			(xy 87.206187 -138.320456) (xy 87.100039 -138.328411) (xy 86.993593 -138.328411) (xy 86.887445 -138.320456)
			(xy 86.782188 -138.304591) (xy 86.678411 -138.280905) (xy 86.576695 -138.249529) (xy 86.477607 -138.21064)
			(xy 86.381703 -138.164455) (xy 86.289518 -138.111232) (xy 86.201569 -138.051269) (xy 86.118346 -137.984901)
			(xy 86.040316 -137.9125) (xy 85.967915 -137.83447) (xy 85.901547 -137.751247) (xy 85.841584 -137.663298)
			(xy 85.788361 -137.571113) (xy 85.742176 -137.475209) (xy 85.703287 -137.376121) (xy 85.671911 -137.274405)
			(xy 85.648225 -137.170628) (xy 85.63236 -137.065371) (xy 85.624405 -136.959223) (xy 82.960261 -136.959223)
			(xy 82.953196 -137.034345) (xy 82.937195 -137.118655) (xy 82.913369 -137.201096) (xy 82.881928 -137.280944)
			(xy 82.843148 -137.357496) (xy 82.79737 -137.430081) (xy 82.744997 -137.498061) (xy 82.686488 -137.560837)
			(xy 82.622357 -137.617858) (xy 82.553169 -137.668624) (xy 82.47953 -137.712688) (xy 82.40209 -137.749662)
			(xy 82.321527 -137.779223) (xy 82.23855 -137.801109) (xy 82.153888 -137.815129) (xy 82.068286 -137.82116)
			(xy 81.982494 -137.819148) (xy 81.897268 -137.809112) (xy 81.813357 -137.791139) (xy 81.731497 -137.765387)
			(xy 81.652408 -137.732083) (xy 81.576786 -137.691519) (xy 81.505294 -137.644052) (xy 81.438561 -137.590099)
			(xy 81.377174 -137.530135) (xy 81.321671 -137.464685) (xy 81.272542 -137.394326) (xy 81.230216 -137.319675)
			(xy 81.195067 -137.241389) (xy 81.167404 -137.160155) (xy 81.147468 -137.076688) (xy 81.135437 -136.99172)
			(xy 81.131415 -136.906) (xy 72.853804 -136.906) (xy 72.853307 -136.959223) (xy 72.845352 -137.065371)
			(xy 72.829487 -137.170628) (xy 72.805801 -137.274405) (xy 72.774425 -137.376121) (xy 72.735536 -137.475209)
			(xy 72.689351 -137.571113) (xy 72.636128 -137.663298) (xy 72.576165 -137.751247) (xy 72.509797 -137.83447)
			(xy 72.437396 -137.9125) (xy 72.359366 -137.984901) (xy 72.276143 -138.051269) (xy 72.188194 -138.111232)
			(xy 72.096009 -138.164455) (xy 72.000105 -138.21064) (xy 71.901017 -138.249529) (xy 71.799301 -138.280905)
			(xy 71.695524 -138.304591) (xy 71.590267 -138.320456) (xy 71.484119 -138.328411) (xy 71.377673 -138.328411)
			(xy 71.271525 -138.320456) (xy 71.166268 -138.304591) (xy 71.062491 -138.280905) (xy 70.960775 -138.249529)
			(xy 70.861687 -138.21064) (xy 70.765783 -138.164455) (xy 70.673598 -138.111232) (xy 70.585649 -138.051269)
			(xy 70.502426 -137.984901) (xy 70.424396 -137.9125) (xy 70.351995 -137.83447) (xy 70.285627 -137.751247)
			(xy 70.225664 -137.663298) (xy 70.172441 -137.571113) (xy 70.126256 -137.475209) (xy 70.087367 -137.376121)
			(xy 70.055991 -137.274405) (xy 70.032305 -137.170628) (xy 70.01644 -137.065371) (xy 70.008485 -136.959223)
			(xy 67.344341 -136.959223) (xy 67.337276 -137.034345) (xy 67.321275 -137.118655) (xy 67.297449 -137.201096)
			(xy 67.266008 -137.280944) (xy 67.227228 -137.357496) (xy 67.18145 -137.430081) (xy 67.129077 -137.498061)
			(xy 67.070568 -137.560837) (xy 67.006437 -137.617858) (xy 66.937249 -137.668624) (xy 66.86361 -137.712688)
			(xy 66.78617 -137.749662) (xy 66.705607 -137.779223) (xy 66.62263 -137.801109) (xy 66.537968 -137.815129)
			(xy 66.452366 -137.82116) (xy 66.366574 -137.819148) (xy 66.281348 -137.809112) (xy 66.197437 -137.791139)
			(xy 66.115577 -137.765387) (xy 66.036488 -137.732083) (xy 65.960866 -137.691519) (xy 65.889374 -137.644052)
			(xy 65.822641 -137.590099) (xy 65.761254 -137.530135) (xy 65.705751 -137.464685) (xy 65.656622 -137.394326)
			(xy 65.614296 -137.319675) (xy 65.579147 -137.241389) (xy 65.551484 -137.160155) (xy 65.531548 -137.076688)
			(xy 65.519517 -136.99172) (xy 65.515495 -136.906) (xy 60.661804 -136.906) (xy 60.661307 -136.959223)
			(xy 60.653352 -137.065371) (xy 60.637487 -137.170628) (xy 60.613801 -137.274405) (xy 60.582425 -137.376121)
			(xy 60.543536 -137.475209) (xy 60.497351 -137.571113) (xy 60.444128 -137.663298) (xy 60.384165 -137.751247)
			(xy 60.317797 -137.83447) (xy 60.245396 -137.9125) (xy 60.167366 -137.984901) (xy 60.084143 -138.051269)
			(xy 59.996194 -138.111232) (xy 59.904009 -138.164455) (xy 59.808105 -138.21064) (xy 59.709017 -138.249529)
			(xy 59.607301 -138.280905) (xy 59.503524 -138.304591) (xy 59.398267 -138.320456) (xy 59.292119 -138.328411)
			(xy 59.185673 -138.328411) (xy 59.079525 -138.320456) (xy 58.974268 -138.304591) (xy 58.870491 -138.280905)
			(xy 58.768775 -138.249529) (xy 58.669687 -138.21064) (xy 58.573783 -138.164455) (xy 58.481598 -138.111232)
			(xy 58.393649 -138.051269) (xy 58.310426 -137.984901) (xy 58.232396 -137.9125) (xy 58.159995 -137.83447)
			(xy 58.093627 -137.751247) (xy 58.033664 -137.663298) (xy 57.980441 -137.571113) (xy 57.934256 -137.475209)
			(xy 57.895367 -137.376121) (xy 57.863991 -137.274405) (xy 57.840305 -137.170628) (xy 57.82444 -137.065371)
			(xy 57.816485 -136.959223) (xy 55.152341 -136.959223) (xy 55.145276 -137.034345) (xy 55.129275 -137.118655)
			(xy 55.105449 -137.201096) (xy 55.074008 -137.280944) (xy 55.035228 -137.357496) (xy 54.98945 -137.430081)
			(xy 54.937077 -137.498061) (xy 54.878568 -137.560837) (xy 54.814437 -137.617858) (xy 54.745249 -137.668624)
			(xy 54.67161 -137.712688) (xy 54.59417 -137.749662) (xy 54.513607 -137.779223) (xy 54.43063 -137.801109)
			(xy 54.345968 -137.815129) (xy 54.260366 -137.82116) (xy 54.174574 -137.819148) (xy 54.089348 -137.809112)
			(xy 54.005437 -137.791139) (xy 53.923577 -137.765387) (xy 53.844488 -137.732083) (xy 53.768866 -137.691519)
			(xy 53.697374 -137.644052) (xy 53.630641 -137.590099) (xy 53.569254 -137.530135) (xy 53.513751 -137.464685)
			(xy 53.464622 -137.394326) (xy 53.422296 -137.319675) (xy 53.387147 -137.241389) (xy 53.359484 -137.160155)
			(xy 53.339548 -137.076688) (xy 53.327517 -136.99172) (xy 53.323495 -136.906) (xy 48.469804 -136.906)
			(xy 48.469307 -136.959223) (xy 48.461352 -137.065371) (xy 48.445487 -137.170628) (xy 48.421801 -137.274405)
			(xy 48.390425 -137.376121) (xy 48.351536 -137.475209) (xy 48.305351 -137.571113) (xy 48.252128 -137.663298)
			(xy 48.192165 -137.751247) (xy 48.125797 -137.83447) (xy 48.053396 -137.9125) (xy 47.975366 -137.984901)
			(xy 47.892143 -138.051269) (xy 47.804194 -138.111232) (xy 47.712009 -138.164455) (xy 47.616105 -138.21064)
			(xy 47.517017 -138.249529) (xy 47.415301 -138.280905) (xy 47.311524 -138.304591) (xy 47.206267 -138.320456)
			(xy 47.100119 -138.328411) (xy 46.993673 -138.328411) (xy 46.887525 -138.320456) (xy 46.782268 -138.304591)
			(xy 46.678491 -138.280905) (xy 46.576775 -138.249529) (xy 46.477687 -138.21064) (xy 46.381783 -138.164455)
			(xy 46.289598 -138.111232) (xy 46.201649 -138.051269) (xy 46.118426 -137.984901) (xy 46.040396 -137.9125)
			(xy 45.967995 -137.83447) (xy 45.901627 -137.751247) (xy 45.841664 -137.663298) (xy 45.788441 -137.571113)
			(xy 45.742256 -137.475209) (xy 45.703367 -137.376121) (xy 45.671991 -137.274405) (xy 45.648305 -137.170628)
			(xy 45.63244 -137.065371) (xy 45.624485 -136.959223) (xy 42.960341 -136.959223) (xy 42.953276 -137.034345)
			(xy 42.937275 -137.118655) (xy 42.913449 -137.201096) (xy 42.882008 -137.280944) (xy 42.843228 -137.357496)
			(xy 42.79745 -137.430081) (xy 42.745077 -137.498061) (xy 42.686568 -137.560837) (xy 42.622437 -137.617858)
			(xy 42.553249 -137.668624) (xy 42.47961 -137.712688) (xy 42.40217 -137.749662) (xy 42.321607 -137.779223)
			(xy 42.23863 -137.801109) (xy 42.153968 -137.815129) (xy 42.068366 -137.82116) (xy 41.982574 -137.819148)
			(xy 41.897348 -137.809112) (xy 41.813437 -137.791139) (xy 41.731577 -137.765387) (xy 41.652488 -137.732083)
			(xy 41.576866 -137.691519) (xy 41.505374 -137.644052) (xy 41.438641 -137.590099) (xy 41.377254 -137.530135)
			(xy 41.321751 -137.464685) (xy 41.272622 -137.394326) (xy 41.230296 -137.319675) (xy 41.195147 -137.241389)
			(xy 41.167484 -137.160155) (xy 41.147548 -137.076688) (xy 41.135517 -136.99172) (xy 41.131495 -136.906)
			(xy 37.531802 -136.906) (xy 37.531802 -141.742414) (xy 37.531945 -141.747162) (xy 37.53374 -141.756489)
			(xy 37.535358 -141.760956) (xy 37.542978 -141.780006) (xy 37.542978 -141.78026) (xy 37.544736 -141.784826)
			(xy 37.546662 -141.794419) (xy 37.546788 -141.79931) (xy 37.546788 -143.547592) (xy 37.554408 -143.566388)
			(xy 37.561774 -143.5735) (xy 38.974014 -144.98574) (xy 38.981411 -144.992591) (xy 39.000009 -145.000329)
			(xy 39.010082 -145.000726)
		)
		(stroke
			(width 0)
			(type solid)
		)
		(fill yes)
		(layer "In7.Cu")
		(net "P52V_HS_FILTER")
	)
	(gr_poly
		(pts
			(xy 121.487946 -73.689972) (xy 121.498012 -73.68954) (xy 121.516602 -73.681811) (xy 121.524014 -73.674986)
			(xy 122.286014 -72.912986) (xy 122.292868 -72.905591) (xy 122.30061 -72.886992) (xy 122.301 -72.876918)
			(xy 122.301 -68.474082) (xy 122.301427 -68.464013) (xy 122.309146 -68.445414) (xy 122.315986 -68.438014)
			(xy 124.864114 -65.889886) (xy 124.871509 -65.883032) (xy 124.890108 -65.87529) (xy 124.900182 -65.8749)
			(xy 142.434818 -65.8749) (xy 142.444887 -65.875327) (xy 142.463486 -65.883046) (xy 142.470886 -65.889886)
			(xy 143.199612 -66.618612) (xy 143.21028 -66.624962) (xy 143.21663 -66.62674) (xy 143.26637 -66.641945)
			(xy 143.363464 -66.679266) (xy 143.457252 -66.724252) (xy 143.547132 -66.776613) (xy 143.632523 -66.836011)
			(xy 143.712878 -66.902066) (xy 143.787677 -66.97435) (xy 143.85644 -67.0524) (xy 143.918723 -67.135711)
			(xy 143.974126 -67.223748) (xy 144.022292 -67.315944) (xy 144.062911 -67.411704) (xy 144.09572 -67.510414)
			(xy 144.12051 -67.611436) (xy 144.137119 -67.714121) (xy 144.145442 -67.817806) (xy 144.146016 -67.869816)
			(xy 144.145524 -67.920308) (xy 144.137647 -68.020984) (xy 144.121958 -68.120741) (xy 144.098552 -68.218975)
			(xy 144.06757 -68.315089) (xy 144.029202 -68.408499) (xy 143.98368 -68.49864) (xy 143.931279 -68.584965)
			(xy 143.902176 -68.626228) (xy 143.892778 -68.639436) (xy 143.892524 -68.671694) (xy 143.966184 -68.77685)
			(xy 143.996664 -68.787772) (xy 144.012412 -68.783454) (xy 144.06832 -68.768218) (xy 144.181761 -68.744522)
			(xy 144.296559 -68.728656) (xy 144.412175 -68.720694) (xy 144.47012 -68.720208) (xy 144.52867 -68.720708)
			(xy 144.645489 -68.728818) (xy 144.761466 -68.744997) (xy 144.876044 -68.769169) (xy 144.988674 -68.801216)
			(xy 145.098814 -68.840985) (xy 145.205936 -68.888285) (xy 145.309526 -68.94289) (xy 145.409086 -69.004536)
			(xy 145.504138 -69.072928) (xy 145.594227 -69.147738) (xy 145.678919 -69.228606) (xy 145.757808 -69.315145)
			(xy 145.830516 -69.406939) (xy 145.896693 -69.503547) (xy 145.956021 -69.604505) (xy 146.008216 -69.709329)
			(xy 146.053028 -69.817516) (xy 146.090241 -69.928546) (xy 146.119676 -70.041886) (xy 146.141192 -70.156993)
			(xy 146.154687 -70.273313) (xy 146.160094 -70.390288) (xy 146.159643 -70.409816) (xy 146.590009 -70.409816)
			(xy 146.594036 -70.293213) (xy 146.606098 -70.177166) (xy 146.626137 -70.062228) (xy 146.654059 -69.948946)
			(xy 146.689729 -69.83786) (xy 146.732978 -69.7295) (xy 146.783601 -69.624382) (xy 146.841354 -69.523007)
			(xy 146.905965 -69.425858) (xy 146.977123 -69.333398) (xy 147.054491 -69.246067) (xy 147.1377 -69.164283)
			(xy 147.226353 -69.088434) (xy 147.320027 -69.018882) (xy 147.418277 -68.955958) (xy 147.520634 -68.899962)
			(xy 147.62661 -68.851162) (xy 147.735701 -68.80979) (xy 147.847385 -68.776042) (xy 147.961132 -68.75008)
			(xy 148.0764 -68.732027) (xy 148.192638 -68.72197) (xy 148.309292 -68.719956) (xy 148.425808 -68.725995)
			(xy 148.54163 -68.740059) (xy 148.656205 -68.762079) (xy 148.768988 -68.791952) (xy 148.879442 -68.829534)
			(xy 148.987039 -68.874648) (xy 149.091268 -68.927077) (xy 149.191631 -68.986572) (xy 149.28765 -69.052849)
			(xy 149.378868 -69.125593) (xy 149.46485 -69.204457) (xy 149.545187 -69.289065) (xy 149.619494 -69.379014)
			(xy 149.687419 -69.473875) (xy 149.748638 -69.573196) (xy 149.802858 -69.676504) (xy 149.849822 -69.783307)
			(xy 149.889305 -69.893095) (xy 149.92112 -70.005346) (xy 149.945115 -70.119524) (xy 149.961175 -70.235086)
			(xy 149.969224 -70.35148) (xy 149.969728 -70.409816) (xy 149.969224 -70.468152) (xy 149.961175 -70.584546)
			(xy 149.945115 -70.700108) (xy 149.92112 -70.814286) (xy 149.889305 -70.926537) (xy 149.849822 -71.036325)
			(xy 149.802858 -71.143128) (xy 149.748638 -71.246436) (xy 149.687419 -71.345757) (xy 149.619494 -71.440618)
			(xy 149.545187 -71.530567) (xy 149.46485 -71.615175) (xy 149.378868 -71.694039) (xy 149.28765 -71.766783)
			(xy 149.191631 -71.83306) (xy 149.091268 -71.892555) (xy 148.987039 -71.944984) (xy 148.879442 -71.990098)
			(xy 148.768988 -72.02768) (xy 148.656205 -72.057553) (xy 148.54163 -72.079573) (xy 148.425808 -72.093637)
			(xy 148.309292 -72.099676) (xy 148.192638 -72.097662) (xy 148.0764 -72.087605) (xy 147.961132 -72.069552)
			(xy 147.847385 -72.04359) (xy 147.735701 -72.009842) (xy 147.62661 -71.96847) (xy 147.520634 -71.91967)
			(xy 147.418277 -71.863674) (xy 147.320027 -71.80075) (xy 147.226353 -71.731198) (xy 147.1377 -71.655349)
			(xy 147.054491 -71.573565) (xy 146.977123 -71.486234) (xy 146.905965 -71.393774) (xy 146.841354 -71.296625)
			(xy 146.783601 -71.19525) (xy 146.732978 -71.090132) (xy 146.689729 -70.981772) (xy 146.654059 -70.870686)
			(xy 146.626137 -70.757404) (xy 146.606098 -70.642466) (xy 146.594036 -70.526419) (xy 146.590009 -70.409816)
			(xy 146.159643 -70.409816) (xy 146.157389 -70.507357) (xy 146.146584 -70.623957) (xy 146.127731 -70.73953)
			(xy 146.10092 -70.85352) (xy 146.066281 -70.965379) (xy 146.023979 -71.074572) (xy 145.974218 -71.180573)
			(xy 145.917236 -71.282874) (xy 145.853307 -71.380984) (xy 145.782739 -71.474432) (xy 145.705869 -71.562769)
			(xy 145.623066 -71.645571) (xy 145.534729 -71.722441) (xy 145.441281 -71.79301) (xy 145.343171 -71.856938)
			(xy 145.240869 -71.91392) (xy 145.134868 -71.963681) (xy 145.025675 -72.005982) (xy 144.913816 -72.040621)
			(xy 144.799826 -72.067432) (xy 144.684253 -72.086284) (xy 144.567653 -72.097089) (xy 144.450584 -72.099794)
			(xy 144.333609 -72.094387) (xy 144.217289 -72.080892) (xy 144.102182 -72.059375) (xy 143.988842 -72.02994)
			(xy 143.877812 -71.992727) (xy 143.769625 -71.947915) (xy 143.664801 -71.895719) (xy 143.563843 -71.83639)
			(xy 143.467236 -71.770213) (xy 143.375442 -71.697506) (xy 143.288904 -71.618616) (xy 143.208035 -71.533924)
			(xy 143.133226 -71.443835) (xy 143.064834 -71.348783) (xy 143.003188 -71.249223) (xy 142.948584 -71.145633)
			(xy 142.901284 -71.038511) (xy 142.861515 -70.92837) (xy 142.829468 -70.815741) (xy 142.805297 -70.701162)
			(xy 142.789118 -70.585185) (xy 142.781008 -70.468366) (xy 142.780512 -70.409816) (xy 142.781037 -70.34986)
			(xy 142.78954 -70.230249) (xy 142.806503 -70.111543) (xy 142.831842 -69.994338) (xy 142.86543 -69.879225)
			(xy 142.907096 -69.766785) (xy 142.956631 -69.657582) (xy 143.013785 -69.552167) (xy 143.078272 -69.45107)
			(xy 143.149765 -69.354801) (xy 143.188436 -69.30898) (xy 143.199104 -69.296534) (xy 143.201898 -69.264276)
			(xy 143.137636 -69.153278) (xy 143.108426 -69.139816) (xy 143.092424 -69.142864) (xy 143.085566 -69.144134)
			(xy 143.077692 -69.145658) (xy 143.064484 -69.152516) (xy 142.254986 -69.962014) (xy 142.248132 -69.969409)
			(xy 142.24039 -69.988008) (xy 142.24 -69.998082) (xy 142.24 -72.241918) (xy 142.240427 -72.251987)
			(xy 142.248146 -72.270586) (xy 142.254986 -72.277986) (xy 143.241014 -73.264014) (xy 143.248409 -73.270868)
			(xy 143.267008 -73.27861) (xy 143.277082 -73.279) (xy 159.617918 -73.279) (xy 159.627987 -73.278573)
			(xy 159.646586 -73.270854) (xy 159.653986 -73.264014) (xy 160.767014 -72.150986) (xy 160.773868 -72.143591)
			(xy 160.78161 -72.124992) (xy 160.782 -72.114918) (xy 160.782 -67.712082) (xy 160.782427 -67.702013)
			(xy 160.790146 -67.683414) (xy 160.796986 -67.676014) (xy 162.583114 -65.889886) (xy 162.590509 -65.883032)
			(xy 162.609108 -65.87529) (xy 162.619182 -65.8749) (xy 175.709326 -65.8749) (xy 175.719311 -65.874358)
			(xy 175.737737 -65.866638) (xy 175.74514 -65.859914) (xy 177.330354 -64.274954) (xy 177.358527 -64.247571)
			(xy 177.419961 -64.198596) (xy 177.486492 -64.156805) (xy 177.557283 -64.122724) (xy 177.631444 -64.096781)
			(xy 177.708043 -64.079303) (xy 177.786116 -64.070508) (xy 177.8254 -64.069976) (xy 182.1434 -64.069976)
			(xy 182.182683 -64.070526) (xy 182.260756 -64.07932) (xy 182.337354 -64.096796) (xy 182.411515 -64.122735)
			(xy 182.482307 -64.156811) (xy 182.54884 -64.198597) (xy 182.610279 -64.247566) (xy 182.638446 -64.274954)
			(xy 184.22366 -65.859914) (xy 184.231004 -65.866724) (xy 184.249468 -65.874449) (xy 184.259474 -65.8749)
			(xy 199.746362 -65.8749) (xy 199.775064 -65.849754) (xy 199.77735 -65.83045) (xy 199.783209 -65.787971)
			(xy 199.802048 -65.704309) (xy 199.828849 -65.622848) (xy 199.863366 -65.544345) (xy 199.905277 -65.469527)
			(xy 199.954193 -65.399089) (xy 200.00966 -65.333686) (xy 200.071163 -65.273924) (xy 200.138132 -65.220358)
			(xy 200.209945 -65.173485) (xy 200.285936 -65.13374) (xy 200.365398 -65.101492) (xy 200.447595 -65.07704)
			(xy 200.531763 -65.060612) (xy 200.617122 -65.052359) (xy 200.702878 -65.052359) (xy 200.788237 -65.060612)
			(xy 200.872405 -65.07704) (xy 200.954602 -65.101492) (xy 201.034064 -65.13374) (xy 201.110055 -65.173485)
			(xy 201.181868 -65.220358) (xy 201.248837 -65.273924) (xy 201.31034 -65.333686) (xy 201.365807 -65.399089)
			(xy 201.414723 -65.469527) (xy 201.456634 -65.544345) (xy 201.491151 -65.622848) (xy 201.517952 -65.704309)
			(xy 201.536791 -65.787971) (xy 201.54265 -65.83045) (xy 201.544936 -65.849754) (xy 201.573638 -65.8749)
			(xy 201.739246 -65.8749) (xy 201.768202 -65.848992) (xy 201.770234 -65.829434) (xy 201.77532 -65.786263)
			(xy 201.792837 -65.701115) (xy 201.818579 -65.618081) (xy 201.852299 -65.537956) (xy 201.893677 -65.461502)
			(xy 201.942316 -65.389451) (xy 201.997753 -65.322489) (xy 202.059459 -65.261256) (xy 202.126846 -65.206335)
			(xy 202.199269 -65.158251) (xy 202.276038 -65.117463) (xy 202.356421 -65.08436) (xy 202.43965 -65.059258)
			(xy 202.524931 -65.042396) (xy 202.61145 -65.033935) (xy 202.654916 -65.033398) (xy 202.694774 -65.033843)
			(xy 202.774169 -65.040975) (xy 202.852609 -65.055181) (xy 202.929463 -65.076346) (xy 203.004115 -65.104302)
			(xy 203.075968 -65.138823) (xy 203.144445 -65.179633) (xy 203.208996 -65.226405) (xy 203.269105 -65.278764)
			(xy 203.297028 -65.30721) (xy 203.30414 -65.31483) (xy 203.32319 -65.322958) (xy 203.417678 -65.322704)
			(xy 203.436728 -65.314576) (xy 203.44384 -65.306956) (xy 203.471773 -65.278173) (xy 203.532012 -65.225207)
			(xy 203.596775 -65.177881) (xy 203.665537 -65.136579) (xy 203.737739 -65.101636) (xy 203.812794 -65.073337)
			(xy 203.890092 -65.051911) (xy 203.969006 -65.037532) (xy 204.048894 -65.030318) (xy 204.089 -65.029842)
			(xy 204.131576 -65.030341) (xy 204.216338 -65.038479) (xy 204.299935 -65.05468) (xy 204.381601 -65.078797)
			(xy 204.460588 -65.110608) (xy 204.536173 -65.149821) (xy 204.607665 -65.196079) (xy 204.674408 -65.248958)
			(xy 204.735793 -65.307974) (xy 204.763878 -65.339976) (xy 204.771244 -65.348612) (xy 204.791818 -65.357756)
			(xy 204.892656 -65.356232) (xy 204.912976 -65.346326) (xy 204.920088 -65.337436) (xy 204.948188 -65.303391)
			(xy 205.010086 -65.240443) (xy 205.077914 -65.183937) (xy 205.151007 -65.134427) (xy 205.228644 -65.092403)
			(xy 205.310063 -65.058276) (xy 205.394462 -65.032383) (xy 205.481012 -65.014977) (xy 205.568859 -65.006232)
			(xy 205.613 -65.005712) (xy 205.654566 -65.006194) (xy 205.737334 -65.01395) (xy 205.819018 -65.029396)
			(xy 205.898904 -65.052396) (xy 205.976296 -65.082749) (xy 206.050518 -65.120192) (xy 206.120922 -65.164396)
			(xy 206.186895 -65.214976) (xy 206.247861 -65.271492) (xy 206.303287 -65.333449) (xy 206.35269 -65.400308)
			(xy 206.39564 -65.471485) (xy 206.431761 -65.546359) (xy 206.460738 -65.624276) (xy 206.482319 -65.704557)
			(xy 206.496315 -65.786502) (xy 206.499968 -65.82791) (xy 206.501492 -65.847976) (xy 206.530448 -65.8749)
			(xy 208.931002 -65.8749) (xy 208.941146 -65.874459) (xy 208.959856 -65.866618) (xy 208.974084 -65.852156)
			(xy 208.978246 -65.842896) (xy 208.99379 -65.805254) (xy 209.030819 -65.732712) (xy 209.074327 -65.663861)
			(xy 209.12395 -65.599277) (xy 209.179272 -65.539503) (xy 209.239829 -65.485039) (xy 209.305113 -65.436342)
			(xy 209.374578 -65.39382) (xy 209.44764 -65.357829) (xy 209.523688 -65.328672) (xy 209.602084 -65.306592)
			(xy 209.682171 -65.291774) (xy 209.763277 -65.284343) (xy 209.804 -65.283842) (xy 209.84376 -65.284283)
			(xy 209.922961 -65.291383) (xy 210.001212 -65.305526) (xy 210.077888 -65.3266) (xy 210.152376 -65.354436)
			(xy 210.224081 -65.388812) (xy 210.292431 -65.429452) (xy 210.356878 -65.476033) (xy 210.387184 -65.501774)
			(xy 210.394416 -65.507521) (xy 210.411734 -65.513908) (xy 210.420966 -65.51422) (xy 210.450684 -65.513966)
			(xy 210.459813 -65.513544) (xy 210.476874 -65.507038) (xy 210.483958 -65.501266) (xy 210.51444 -65.474862)
			(xy 210.579398 -65.427059) (xy 210.648416 -65.385332) (xy 210.720927 -65.350023) (xy 210.796336 -65.321421)
			(xy 210.874025 -65.299762) (xy 210.953354 -65.285223) (xy 211.033674 -65.277923) (xy 211.074 -65.277492)
			(xy 211.114053 -65.277932) (xy 211.193835 -65.285136) (xy 211.272646 -65.299486) (xy 211.349847 -65.320865)
			(xy 211.424813 -65.349099) (xy 211.496936 -65.383961) (xy 211.565632 -65.425168) (xy 211.630343 -65.472386)
			(xy 211.66074 -65.498472) (xy 211.667861 -65.504154) (xy 211.684912 -65.510534) (xy 211.694014 -65.510918)
			(xy 211.723986 -65.510918) (xy 211.733089 -65.510541) (xy 211.75014 -65.504157) (xy 211.75726 -65.498472)
			(xy 211.787654 -65.472382) (xy 211.852368 -65.425167) (xy 211.921064 -65.383961) (xy 211.993188 -65.349098)
			(xy 212.068153 -65.320862) (xy 212.145354 -65.299479) (xy 212.224165 -65.285124) (xy 212.303946 -65.277913)
			(xy 212.344 -65.277492) (xy 212.344254 -65.277492) (xy 212.384105 -65.277935) (xy 212.463487 -65.285066)
			(xy 212.541913 -65.299274) (xy 212.618751 -65.320445) (xy 212.693386 -65.34841) (xy 212.765218 -65.382944)
			(xy 212.799676 -65.402968) (xy 212.814662 -65.412112) (xy 212.849206 -65.407794) (xy 213.599014 -64.657986)
			(xy 213.605868 -64.650591) (xy 213.61361 -64.631992) (xy 213.614 -64.621918) (xy 213.614 -45.741082)
			(xy 213.613573 -45.731013) (xy 213.605854 -45.712414) (xy 213.599014 -45.705014) (xy 212.612986 -44.718986)
			(xy 212.605591 -44.712132) (xy 212.586992 -44.70439) (xy 212.576918 -44.704) (xy 204.662786 -44.704)
			(xy 204.652717 -44.703574) (xy 204.634116 -44.695856) (xy 204.626718 -44.689014) (xy 202.75169 -42.813986)
			(xy 202.744836 -42.806591) (xy 202.737092 -42.787992) (xy 202.736704 -42.777918) (xy 202.736704 -22.392894)
			(xy 202.73628 -22.382824) (xy 202.728564 -22.364221) (xy 202.721718 -22.356826) (xy 200.704704 -20.339812)
			(xy 200.697306 -20.332963) (xy 200.678708 -20.325226) (xy 200.668636 -20.324826) (xy 165.2524 -20.324826)
			(xy 163.449 -18.521426) (xy 163.449 -2.4892) (xy 162.8648 -1.905) (xy 37.333682 -1.905) (xy 37.323613 -1.905427)
			(xy 37.305014 -1.913146) (xy 37.297614 -1.919986) (xy 35.859466 -3.358134) (xy 35.852618 -3.365531)
			(xy 35.844885 -3.38413) (xy 35.84448 -3.394202) (xy 35.84448 -11.99998) (xy 102.363779 -11.99998)
			(xy 102.367816 -11.786696) (xy 102.379921 -11.573717) (xy 102.400077 -11.361349) (xy 102.428255 -11.149895)
			(xy 102.464414 -10.93966) (xy 102.508503 -10.730943) (xy 102.560459 -10.524044) (xy 102.620206 -10.319259)
			(xy 102.687661 -10.116882) (xy 102.762725 -9.917203) (xy 102.845291 -9.720507) (xy 102.935242 -9.527076)
			(xy 103.032448 -9.337188) (xy 103.13677 -9.151114) (xy 103.248058 -8.969122) (xy 103.366154 -8.79147)
			(xy 103.490888 -8.618415) (xy 103.622081 -8.450205) (xy 103.759545 -8.287079) (xy 103.903084 -8.129271)
			(xy 104.052492 -7.977009) (xy 104.207554 -7.830509) (xy 104.36805 -7.689983) (xy 104.533748 -7.55563)
			(xy 104.704411 -7.427643) (xy 104.879796 -7.306207) (xy 105.05965 -7.191494) (xy 105.243716 -7.083669)
			(xy 105.43173 -6.982887) (xy 105.623424 -6.889292) (xy 105.818522 -6.803018) (xy 106.016745 -6.724189)
			(xy 106.21781 -6.652917) (xy 106.421427 -6.589304) (xy 106.627306 -6.533442) (xy 106.835151 -6.485412)
			(xy 107.044664 -6.44528) (xy 107.255547 -6.413106) (xy 107.467495 -6.388935) (xy 107.680207 -6.372801)
			(xy 107.893377 -6.364729) (xy 108.000038 -6.364224) (xy 129.999994 -6.364224) (xy 130.106655 -6.364737)
			(xy 130.319825 -6.372809) (xy 130.532536 -6.388943) (xy 130.744484 -6.413114) (xy 130.955366 -6.445288)
			(xy 131.164879 -6.48542) (xy 131.372724 -6.533451) (xy 131.578602 -6.589312) (xy 131.782219 -6.652925)
			(xy 131.983283 -6.724197) (xy 132.181506 -6.803026) (xy 132.376604 -6.8893) (xy 132.568297 -6.982895)
			(xy 132.756311 -7.083677) (xy 132.940377 -7.191502) (xy 133.120231 -7.306214) (xy 133.295615 -7.427651)
			(xy 133.466278 -7.555637) (xy 133.631976 -7.689989) (xy 133.792471 -7.830516) (xy 133.947533 -7.977015)
			(xy 134.096941 -8.129278) (xy 134.240479 -8.287085) (xy 134.377943 -8.45021) (xy 134.509136 -8.618421)
			(xy 134.63387 -8.791476) (xy 134.751965 -8.969126) (xy 134.863254 -9.151119) (xy 134.967575 -9.337192)
			(xy 135.064781 -9.52708) (xy 135.154732 -9.720511) (xy 135.237298 -9.917206) (xy 135.312362 -10.116885)
			(xy 135.379816 -10.319262) (xy 135.439564 -10.524046) (xy 135.491519 -10.730945) (xy 135.535608 -10.939661)
			(xy 135.571767 -11.149897) (xy 135.599945 -11.36135) (xy 135.620101 -11.573717) (xy 135.632206 -11.786696)
			(xy 135.636243 -11.99998) (xy 135.632206 -12.213264) (xy 135.620101 -12.426243) (xy 135.599945 -12.63861)
			(xy 135.571767 -12.850063) (xy 135.535608 -13.060299) (xy 135.491519 -13.269015) (xy 135.439564 -13.475914)
			(xy 135.379816 -13.680698) (xy 135.312362 -13.883075) (xy 135.237298 -14.082754) (xy 135.154732 -14.279449)
			(xy 135.064781 -14.47288) (xy 134.967575 -14.662768) (xy 134.863254 -14.848841) (xy 134.751965 -15.030834)
			(xy 134.63387 -15.208484) (xy 134.509136 -15.381539) (xy 134.377943 -15.54975) (xy 134.240479 -15.712875)
			(xy 134.096941 -15.870682) (xy 133.947533 -16.022945) (xy 133.792471 -16.169444) (xy 133.631976 -16.309971)
			(xy 133.466278 -16.444323) (xy 133.295615 -16.572309) (xy 133.120231 -16.693746) (xy 132.940377 -16.808458)
			(xy 132.756311 -16.916283) (xy 132.568297 -17.017065) (xy 132.376604 -17.11066) (xy 132.181506 -17.196934)
			(xy 131.983283 -17.275763) (xy 131.782219 -17.347035) (xy 131.578602 -17.410648) (xy 131.372724 -17.466509)
			(xy 131.164879 -17.51454) (xy 130.955366 -17.554672) (xy 130.744484 -17.586846) (xy 130.532536 -17.611017)
			(xy 130.319825 -17.627151) (xy 130.106655 -17.635223) (xy 129.999994 -17.635728) (xy 108.000038 -17.635728)
			(xy 107.893377 -17.635231) (xy 107.680207 -17.627159) (xy 107.467495 -17.611025) (xy 107.255547 -17.586854)
			(xy 107.044664 -17.55468) (xy 106.835151 -17.514548) (xy 106.627306 -17.466518) (xy 106.421427 -17.410656)
			(xy 106.21781 -17.347043) (xy 106.016745 -17.275771) (xy 105.818522 -17.196942) (xy 105.623424 -17.110668)
			(xy 105.43173 -17.017073) (xy 105.243716 -16.916291) (xy 105.05965 -16.808466) (xy 104.879796 -16.693753)
			(xy 104.704411 -16.572317) (xy 104.533748 -16.44433) (xy 104.36805 -16.309977) (xy 104.207554 -16.169451)
			(xy 104.052492 -16.022951) (xy 103.903084 -15.870689) (xy 103.759545 -15.712881) (xy 103.622081 -15.549755)
			(xy 103.490888 -15.381545) (xy 103.366154 -15.20849) (xy 103.248058 -15.030838) (xy 103.13677 -14.848846)
			(xy 103.032448 -14.662772) (xy 102.935242 -14.472884) (xy 102.845291 -14.279453) (xy 102.762725 -14.082757)
			(xy 102.687661 -13.883078) (xy 102.620206 -13.680701) (xy 102.560459 -13.475916) (xy 102.508503 -13.269017)
			(xy 102.464414 -13.0603) (xy 102.428255 -12.850065) (xy 102.400077 -12.638611) (xy 102.379921 -12.426243)
			(xy 102.367816 -12.213264) (xy 102.363779 -11.99998) (xy 35.84448 -11.99998) (xy 35.84448 -25.59157)
			(xy 42.354235 -25.59157) (xy 42.354235 -25.46243) (xy 42.362185 -25.333535) (xy 42.378055 -25.205375)
			(xy 42.401784 -25.078434) (xy 42.433283 -24.953195) (xy 42.472432 -24.830132) (xy 42.519083 -24.709713)
			(xy 42.573058 -24.592394) (xy 42.634153 -24.47862) (xy 42.702136 -24.368823) (xy 42.77675 -24.26342)
			(xy 42.857711 -24.16281) (xy 42.944711 -24.067375) (xy 43.037422 -23.977476) (xy 43.135492 -23.893455)
			(xy 43.238547 -23.815631) (xy 43.346198 -23.744299) (xy 43.458037 -23.679729) (xy 43.573638 -23.622167)
			(xy 43.692563 -23.57183) (xy 43.814362 -23.52891) (xy 43.938572 -23.493569) (xy 44.064721 -23.465942)
			(xy 44.192333 -23.446133) (xy 44.320922 -23.434217) (xy 44.45 -23.430241) (xy 44.579078 -23.434217)
			(xy 44.707667 -23.446133) (xy 44.835279 -23.465942) (xy 44.961428 -23.493569) (xy 45.085638 -23.52891)
			(xy 45.207437 -23.57183) (xy 45.326362 -23.622167) (xy 45.441963 -23.679729) (xy 45.553802 -23.744299)
			(xy 45.661453 -23.815631) (xy 45.764508 -23.893455) (xy 45.862578 -23.977476) (xy 45.955289 -24.067375)
			(xy 46.042289 -24.16281) (xy 46.12325 -24.26342) (xy 46.197864 -24.368823) (xy 46.265847 -24.47862)
			(xy 46.326942 -24.592394) (xy 46.380917 -24.709713) (xy 46.427568 -24.830132) (xy 46.466717 -24.953195)
			(xy 46.498216 -25.078434) (xy 46.521945 -25.205375) (xy 46.537815 -25.333535) (xy 46.545765 -25.46243)
			(xy 46.546262 -25.527) (xy 46.545765 -25.59157) (xy 46.537815 -25.720465) (xy 46.521945 -25.848625)
			(xy 46.498216 -25.975566) (xy 46.466717 -26.100805) (xy 46.427568 -26.223868) (xy 46.380917 -26.344287)
			(xy 46.326942 -26.461606) (xy 46.265847 -26.57538) (xy 46.197864 -26.685177) (xy 46.12325 -26.79058)
			(xy 46.042289 -26.89119) (xy 45.955289 -26.986625) (xy 45.862578 -27.076524) (xy 45.764508 -27.160545)
			(xy 45.661453 -27.238369) (xy 45.553802 -27.309701) (xy 45.441963 -27.374271) (xy 45.326362 -27.431833)
			(xy 45.207437 -27.48217) (xy 45.085638 -27.52509) (xy 44.961428 -27.560431) (xy 44.835279 -27.588058)
			(xy 44.707667 -27.607867) (xy 44.579078 -27.619783) (xy 44.45 -27.62376) (xy 44.320922 -27.619783)
			(xy 44.192333 -27.607867) (xy 44.064721 -27.588058) (xy 43.938572 -27.560431) (xy 43.814362 -27.52509)
			(xy 43.692563 -27.48217) (xy 43.573638 -27.431833) (xy 43.458037 -27.374271) (xy 43.346198 -27.309701)
			(xy 43.238547 -27.238369) (xy 43.135492 -27.160545) (xy 43.037422 -27.076524) (xy 42.944711 -26.986625)
			(xy 42.857711 -26.89119) (xy 42.77675 -26.79058) (xy 42.702136 -26.685177) (xy 42.634153 -26.57538)
			(xy 42.573058 -26.461606) (xy 42.519083 -26.344287) (xy 42.472432 -26.223868) (xy 42.433283 -26.100805)
			(xy 42.401784 -25.975566) (xy 42.378055 -25.848625) (xy 42.362185 -25.720465) (xy 42.354235 -25.59157)
			(xy 35.84448 -25.59157) (xy 35.84448 -30.591252) (xy 35.844047 -30.601318) (xy 35.836317 -30.619906)
			(xy 35.829494 -30.62732) (xy 33.428339 -33.028475) (xy 59.423804 -33.028475) (xy 59.423804 -32.851505)
			(xy 59.431858 -32.674717) (xy 59.447951 -32.49848) (xy 59.472049 -32.323157) (xy 59.504101 -32.149113)
			(xy 59.544042 -31.976709) (xy 59.591788 -31.806301) (xy 59.647241 -31.638242) (xy 59.710285 -31.472882)
			(xy 59.78079 -31.310562) (xy 59.85861 -31.15162) (xy 59.943584 -30.996384) (xy 60.035535 -30.845177)
			(xy 60.134273 -30.698312) (xy 60.239593 -30.556092) (xy 60.351278 -30.418814) (xy 60.469094 -30.286762)
			(xy 60.592799 -30.160208) (xy 60.722135 -30.039416) (xy 60.856836 -29.924636) (xy 60.996621 -29.816106)
			(xy 61.1412 -29.71405) (xy 61.290275 -29.618681) (xy 61.443536 -29.530196) (xy 61.600666 -29.448778)
			(xy 61.761339 -29.374596) (xy 61.925221 -29.307804) (xy 62.091974 -29.24854) (xy 62.261251 -29.196927)
			(xy 62.432702 -29.153072) (xy 62.605971 -29.117066) (xy 62.780699 -29.088984) (xy 62.956525 -29.068884)
			(xy 63.133083 -29.056807) (xy 63.310008 -29.052779) (xy 63.486933 -29.056807) (xy 63.663491 -29.068884)
			(xy 63.839317 -29.088984) (xy 64.014045 -29.117066) (xy 64.187314 -29.153072) (xy 64.358765 -29.196927)
			(xy 64.528042 -29.24854) (xy 64.694795 -29.307804) (xy 64.858677 -29.374596) (xy 65.01935 -29.448778)
			(xy 65.17648 -29.530196) (xy 65.329741 -29.618681) (xy 65.478816 -29.71405) (xy 65.623395 -29.816106)
			(xy 65.76318 -29.924636) (xy 65.897881 -30.039416) (xy 66.027217 -30.160208) (xy 66.150922 -30.286762)
			(xy 66.268738 -30.418814) (xy 66.380423 -30.556092) (xy 66.485743 -30.698312) (xy 66.584481 -30.845177)
			(xy 66.676432 -30.996384) (xy 66.761406 -31.15162) (xy 66.839226 -31.310562) (xy 66.909731 -31.472882)
			(xy 66.972775 -31.638242) (xy 67.028228 -31.806301) (xy 67.075974 -31.976709) (xy 67.115915 -32.149113)
			(xy 67.147967 -32.323157) (xy 67.172065 -32.49848) (xy 67.188158 -32.674717) (xy 67.196212 -32.851505)
			(xy 67.196716 -32.93999) (xy 67.196212 -33.028475) (xy 67.188158 -33.205263) (xy 67.172065 -33.3815)
			(xy 67.147967 -33.556823) (xy 67.115915 -33.730867) (xy 67.075974 -33.903271) (xy 67.028228 -34.073679)
			(xy 66.972775 -34.241738) (xy 66.909731 -34.407098) (xy 66.839226 -34.569418) (xy 66.761406 -34.72836)
			(xy 66.676432 -34.883596) (xy 66.584481 -35.034803) (xy 66.485743 -35.181668) (xy 66.380423 -35.323888)
			(xy 66.268738 -35.461166) (xy 66.150922 -35.593218) (xy 66.027217 -35.719772) (xy 65.897881 -35.840564)
			(xy 65.76318 -35.955344) (xy 65.623395 -36.063874) (xy 65.478816 -36.16593) (xy 65.329741 -36.261299)
			(xy 65.17648 -36.349784) (xy 65.01935 -36.431202) (xy 64.858677 -36.505384) (xy 64.694795 -36.572176)
			(xy 64.528042 -36.63144) (xy 64.358765 -36.683053) (xy 64.187314 -36.726908) (xy 64.014045 -36.762914)
			(xy 63.839317 -36.790996) (xy 63.663491 -36.811096) (xy 63.486933 -36.823173) (xy 63.310008 -36.827202)
			(xy 63.133083 -36.823173) (xy 62.956525 -36.811096) (xy 62.780699 -36.790996) (xy 62.605971 -36.762914)
			(xy 62.432702 -36.726908) (xy 62.261251 -36.683053) (xy 62.091974 -36.63144) (xy 61.925221 -36.572176)
			(xy 61.761339 -36.505384) (xy 61.600666 -36.431202) (xy 61.443536 -36.349784) (xy 61.290275 -36.261299)
			(xy 61.1412 -36.16593) (xy 60.996621 -36.063874) (xy 60.856836 -35.955344) (xy 60.722135 -35.840564)
			(xy 60.592799 -35.719772) (xy 60.469094 -35.593218) (xy 60.351278 -35.461166) (xy 60.239593 -35.323888)
			(xy 60.134273 -35.181668) (xy 60.035535 -35.034803) (xy 59.943584 -34.883596) (xy 59.85861 -34.72836)
			(xy 59.78079 -34.569418) (xy 59.710285 -34.407098) (xy 59.647241 -34.241738) (xy 59.591788 -34.073679)
			(xy 59.544042 -33.903271) (xy 59.504101 -33.730867) (xy 59.472049 -33.556823) (xy 59.447951 -33.3815)
			(xy 59.431858 -33.205263) (xy 59.423804 -33.028475) (xy 33.428339 -33.028475) (xy 32.1818 -34.275014)
			(xy 32.171386 -34.275014) (xy 32.171386 -38.019995) (xy 73.975239 -38.019995) (xy 73.979145 -37.915492)
			(xy 73.99084 -37.811573) (xy 74.01026 -37.708817) (xy 74.037295 -37.607796) (xy 74.071795 -37.509076)
			(xy 74.113567 -37.413205) (xy 74.162378 -37.320721) (xy 74.217957 -37.232137) (xy 74.279993 -37.147949)
			(xy 74.348139 -37.068627) (xy 74.422016 -36.994612) (xy 74.501212 -36.926318) (xy 74.585284 -36.864126)
			(xy 74.629264 -36.835842) (xy 74.640694 -36.828984) (xy 74.65314 -36.806378) (xy 74.65314 -36.693602)
			(xy 74.640694 -36.670996) (xy 74.629264 -36.664138) (xy 74.585275 -36.635868) (xy 74.501203 -36.573675)
			(xy 74.422008 -36.505381) (xy 74.348132 -36.431365) (xy 74.279986 -36.352042) (xy 74.217951 -36.267854)
			(xy 74.162373 -36.17927) (xy 74.113562 -36.086785) (xy 74.071791 -35.990915) (xy 74.037292 -35.892194)
			(xy 74.010257 -35.791173) (xy 73.990839 -35.688416) (xy 73.979144 -35.584497) (xy 73.975239 -35.479995)
			(xy 73.979145 -35.375492) (xy 73.99084 -35.271573) (xy 74.01026 -35.168817) (xy 74.037295 -35.067796)
			(xy 74.071795 -34.969076) (xy 74.113567 -34.873205) (xy 74.162378 -34.780721) (xy 74.217957 -34.692137)
			(xy 74.279993 -34.607949) (xy 74.348139 -34.528627) (xy 74.422016 -34.454612) (xy 74.501212 -34.386318)
			(xy 74.585284 -34.324126) (xy 74.629264 -34.295842) (xy 74.640694 -34.288984) (xy 74.65314 -34.266378)
			(xy 74.65314 -34.153602) (xy 74.640694 -34.130996) (xy 74.629264 -34.124138) (xy 74.583583 -34.094779)
			(xy 74.496461 -34.029942) (xy 74.414627 -33.958547) (xy 74.338573 -33.881024) (xy 74.268756 -33.79784)
			(xy 74.205596 -33.709495) (xy 74.149473 -33.61652) (xy 74.100726 -33.519475) (xy 74.059647 -33.418944)
			(xy 74.026483 -33.315531) (xy 74.001435 -33.209859) (xy 73.984651 -33.102564) (xy 73.976235 -32.99429)
			(xy 73.975722 -32.93999) (xy 73.976194 -32.88765) (xy 73.984017 -32.783264) (xy 73.99962 -32.679754)
			(xy 74.022914 -32.5777) (xy 74.053769 -32.477671) (xy 74.092013 -32.380228) (xy 74.137432 -32.285916)
			(xy 74.189773 -32.195261) (xy 74.248741 -32.108772) (xy 74.314008 -32.026931) (xy 74.385209 -31.950196)
			(xy 74.461944 -31.878996) (xy 74.543786 -31.81373) (xy 74.630277 -31.754763) (xy 74.720932 -31.702424)
			(xy 74.815245 -31.657006) (xy 74.912688 -31.618763) (xy 75.012717 -31.587909) (xy 75.114772 -31.564616)
			(xy 75.218282 -31.549015) (xy 75.322668 -31.541193) (xy 75.375008 -31.540704) (xy 75.429308 -31.541188)
			(xy 75.537583 -31.549606) (xy 75.644879 -31.566391) (xy 75.750551 -31.591443) (xy 75.853963 -31.624609)
			(xy 75.954494 -31.665692) (xy 76.051538 -31.714443) (xy 76.144511 -31.770569) (xy 76.232854 -31.833732)
			(xy 76.316036 -31.903553) (xy 76.393555 -31.979612) (xy 76.464946 -32.06145) (xy 76.529779 -32.148575)
			(xy 76.559156 -32.194246) (xy 76.566014 -32.205676) (xy 76.58862 -32.218122) (xy 76.701396 -32.218122)
			(xy 76.724002 -32.205676) (xy 76.73086 -32.194246) (xy 76.760214 -32.148561) (xy 76.825052 -32.06144)
			(xy 76.896448 -31.979607) (xy 76.973971 -31.903553) (xy 77.057156 -31.833736) (xy 77.145501 -31.770577)
			(xy 77.238476 -31.714455) (xy 77.335522 -31.665708) (xy 77.436053 -31.624629) (xy 77.539466 -31.591465)
			(xy 77.645138 -31.566417) (xy 77.752434 -31.549634) (xy 77.860708 -31.541217) (xy 77.915008 -31.540704)
			(xy 77.967347 -31.541196) (xy 78.071733 -31.549019) (xy 78.175242 -31.564621) (xy 78.277295 -31.587914)
			(xy 78.377323 -31.618769) (xy 78.474765 -31.657013) (xy 78.569077 -31.702431) (xy 78.659731 -31.75477)
			(xy 78.74622 -31.813738) (xy 78.828061 -31.879004) (xy 78.904796 -31.950203) (xy 78.975995 -32.026937)
			(xy 79.041261 -32.108778) (xy 79.100229 -32.195267) (xy 79.152568 -32.285921) (xy 79.197987 -32.380233)
			(xy 79.23623 -32.477675) (xy 79.267085 -32.577703) (xy 79.290379 -32.679756) (xy 79.305981 -32.783265)
			(xy 79.313804 -32.887651) (xy 79.314294 -32.93999) (xy 79.313797 -32.99429) (xy 79.30538 -33.102564)
			(xy 79.288596 -33.20986) (xy 79.263546 -33.315532) (xy 79.23038 -33.418944) (xy 79.189299 -33.519475)
			(xy 79.140549 -33.616518) (xy 79.084424 -33.709492) (xy 79.021262 -33.797835) (xy 78.951442 -33.881017)
			(xy 78.875384 -33.958537) (xy 78.793547 -34.029928) (xy 78.706422 -34.094761) (xy 78.660752 -34.124138)
			(xy 78.649322 -34.130996) (xy 78.636876 -34.153602) (xy 78.636876 -34.266378) (xy 78.649322 -34.288984)
			(xy 78.660752 -34.295842) (xy 78.704725 -34.324138) (xy 78.7888 -34.386327) (xy 78.867999 -34.454618)
			(xy 78.94188 -34.52863) (xy 79.01003 -34.607951) (xy 79.072068 -34.692137) (xy 79.12765 -34.78072)
			(xy 79.176464 -34.873204) (xy 79.218238 -34.969074) (xy 79.25274 -35.067794) (xy 79.279777 -35.168815)
			(xy 79.299197 -35.271572) (xy 79.310893 -35.375492) (xy 79.314799 -35.479995) (xy 79.310894 -35.584498)
			(xy 79.299199 -35.688418) (xy 79.279779 -35.791175) (xy 79.252743 -35.892196) (xy 79.218242 -35.990917)
			(xy 79.176469 -36.086787) (xy 79.127655 -36.179271) (xy 79.072074 -36.267854) (xy 79.010036 -36.352041)
			(xy 78.941887 -36.431362) (xy 78.868007 -36.505375) (xy 78.788809 -36.573666) (xy 78.704734 -36.635856)
			(xy 78.660752 -36.664138) (xy 78.649322 -36.670996) (xy 78.636876 -36.693602) (xy 78.636876 -36.806378)
			(xy 78.649322 -36.828984) (xy 78.660752 -36.835842) (xy 78.704725 -36.864138) (xy 78.7888 -36.926327)
			(xy 78.867999 -36.994618) (xy 78.94188 -37.06863) (xy 79.01003 -37.147951) (xy 79.072068 -37.232137)
			(xy 79.12765 -37.32072) (xy 79.176464 -37.413204) (xy 79.218238 -37.509074) (xy 79.25274 -37.607794)
			(xy 79.279777 -37.708815) (xy 79.299197 -37.811572) (xy 79.310893 -37.915492) (xy 79.314799 -38.019995)
			(xy 82.865239 -38.019995) (xy 82.869145 -37.915492) (xy 82.88084 -37.811573) (xy 82.90026 -37.708817)
			(xy 82.927295 -37.607796) (xy 82.961795 -37.509076) (xy 83.003567 -37.413205) (xy 83.052378 -37.320721)
			(xy 83.107957 -37.232137) (xy 83.169993 -37.147949) (xy 83.238139 -37.068627) (xy 83.312016 -36.994612)
			(xy 83.391212 -36.926318) (xy 83.475284 -36.864126) (xy 83.519264 -36.835842) (xy 83.530694 -36.828984)
			(xy 83.54314 -36.806378) (xy 83.54314 -36.693602) (xy 83.530694 -36.670996) (xy 83.519264 -36.664138)
			(xy 83.475275 -36.635868) (xy 83.391203 -36.573675) (xy 83.312008 -36.505381) (xy 83.238132 -36.431365)
			(xy 83.169986 -36.352042) (xy 83.107951 -36.267854) (xy 83.052373 -36.17927) (xy 83.003562 -36.086785)
			(xy 82.961791 -35.990915) (xy 82.927292 -35.892194) (xy 82.900257 -35.791173) (xy 82.880839 -35.688416)
			(xy 82.869144 -35.584497) (xy 82.865239 -35.479995) (xy 82.869145 -35.375492) (xy 82.88084 -35.271573)
			(xy 82.90026 -35.168817) (xy 82.927295 -35.067796) (xy 82.961795 -34.969076) (xy 83.003567 -34.873205)
			(xy 83.052378 -34.780721) (xy 83.107957 -34.692137) (xy 83.169993 -34.607949) (xy 83.238139 -34.528627)
			(xy 83.312016 -34.454612) (xy 83.391212 -34.386318) (xy 83.475284 -34.324126) (xy 83.519264 -34.295842)
			(xy 83.530694 -34.288984) (xy 83.54314 -34.266378) (xy 83.54314 -34.153602) (xy 83.530694 -34.130996)
			(xy 83.519264 -34.124138) (xy 83.473583 -34.094779) (xy 83.386461 -34.029942) (xy 83.304627 -33.958547)
			(xy 83.228573 -33.881024) (xy 83.158756 -33.79784) (xy 83.095596 -33.709495) (xy 83.039473 -33.61652)
			(xy 82.990726 -33.519475) (xy 82.949647 -33.418944) (xy 82.916483 -33.315531) (xy 82.891435 -33.209859)
			(xy 82.874651 -33.102564) (xy 82.866235 -32.99429) (xy 82.865722 -32.93999) (xy 82.866194 -32.88765)
			(xy 82.874017 -32.783264) (xy 82.88962 -32.679754) (xy 82.912914 -32.5777) (xy 82.943769 -32.477671)
			(xy 82.982013 -32.380228) (xy 83.027432 -32.285916) (xy 83.079773 -32.195261) (xy 83.138741 -32.108772)
			(xy 83.204008 -32.026931) (xy 83.275209 -31.950196) (xy 83.351944 -31.878996) (xy 83.433786 -31.81373)
			(xy 83.520277 -31.754763) (xy 83.610932 -31.702424) (xy 83.705245 -31.657006) (xy 83.802688 -31.618763)
			(xy 83.902717 -31.587909) (xy 84.004772 -31.564616) (xy 84.108282 -31.549015) (xy 84.212668 -31.541193)
			(xy 84.265008 -31.540704) (xy 84.319308 -31.541188) (xy 84.427583 -31.549606) (xy 84.534879 -31.566391)
			(xy 84.640551 -31.591443) (xy 84.743963 -31.624609) (xy 84.844494 -31.665692) (xy 84.941538 -31.714443)
			(xy 85.034511 -31.770569) (xy 85.122854 -31.833732) (xy 85.206036 -31.903553) (xy 85.283555 -31.979612)
			(xy 85.354946 -32.06145) (xy 85.419779 -32.148575) (xy 85.449156 -32.194246) (xy 85.456014 -32.205676)
			(xy 85.47862 -32.218122) (xy 85.591396 -32.218122) (xy 85.614002 -32.205676) (xy 85.62086 -32.194246)
			(xy 85.650214 -32.148561) (xy 85.715052 -32.06144) (xy 85.786448 -31.979607) (xy 85.863971 -31.903553)
			(xy 85.947156 -31.833736) (xy 86.035501 -31.770577) (xy 86.128476 -31.714455) (xy 86.225522 -31.665708)
			(xy 86.326053 -31.624629) (xy 86.429466 -31.591465) (xy 86.535138 -31.566417) (xy 86.642434 -31.549634)
			(xy 86.750708 -31.541217) (xy 86.805008 -31.540704) (xy 86.857347 -31.541196) (xy 86.961733 -31.549019)
			(xy 87.065242 -31.564621) (xy 87.167295 -31.587914) (xy 87.267323 -31.618769) (xy 87.364765 -31.657013)
			(xy 87.459077 -31.702431) (xy 87.549731 -31.75477) (xy 87.63622 -31.813738) (xy 87.718061 -31.879004)
			(xy 87.794796 -31.950203) (xy 87.865995 -32.026937) (xy 87.931261 -32.108778) (xy 87.990229 -32.195267)
			(xy 88.042568 -32.285921) (xy 88.087987 -32.380233) (xy 88.12623 -32.477675) (xy 88.157085 -32.577703)
			(xy 88.180379 -32.679756) (xy 88.195981 -32.783265) (xy 88.203804 -32.887651) (xy 88.204294 -32.93999)
			(xy 88.203797 -32.99429) (xy 88.19538 -33.102564) (xy 88.178596 -33.20986) (xy 88.153546 -33.315532)
			(xy 88.12038 -33.418944) (xy 88.079299 -33.519475) (xy 88.030549 -33.616518) (xy 87.974424 -33.709492)
			(xy 87.911262 -33.797835) (xy 87.841442 -33.881017) (xy 87.765384 -33.958537) (xy 87.683547 -34.029928)
			(xy 87.596422 -34.094761) (xy 87.550752 -34.124138) (xy 87.539322 -34.130996) (xy 87.526876 -34.153602)
			(xy 87.526876 -34.266378) (xy 87.539322 -34.288984) (xy 87.550752 -34.295842) (xy 87.594725 -34.324138)
			(xy 87.6788 -34.386327) (xy 87.757999 -34.454618) (xy 87.83188 -34.52863) (xy 87.90003 -34.607951)
			(xy 87.962068 -34.692137) (xy 88.01765 -34.78072) (xy 88.066464 -34.873204) (xy 88.108238 -34.969074)
			(xy 88.14274 -35.067794) (xy 88.169777 -35.168815) (xy 88.189197 -35.271572) (xy 88.200893 -35.375492)
			(xy 88.204799 -35.479995) (xy 88.200894 -35.584498) (xy 88.189199 -35.688418) (xy 88.169779 -35.791175)
			(xy 88.142743 -35.892196) (xy 88.108242 -35.990917) (xy 88.066469 -36.086787) (xy 88.017655 -36.179271)
			(xy 87.962074 -36.267854) (xy 87.900036 -36.352041) (xy 87.831887 -36.431362) (xy 87.758007 -36.505375)
			(xy 87.678809 -36.573666) (xy 87.594734 -36.635856) (xy 87.550752 -36.664138) (xy 87.539322 -36.670996)
			(xy 87.526876 -36.693602) (xy 87.526876 -36.806378) (xy 87.539322 -36.828984) (xy 87.550752 -36.835842)
			(xy 87.594725 -36.864138) (xy 87.6788 -36.926327) (xy 87.757999 -36.994618) (xy 87.83188 -37.06863)
			(xy 87.90003 -37.147951) (xy 87.962068 -37.232137) (xy 88.01765 -37.32072) (xy 88.066464 -37.413204)
			(xy 88.108238 -37.509074) (xy 88.14274 -37.607794) (xy 88.169777 -37.708815) (xy 88.189197 -37.811572)
			(xy 88.200893 -37.915492) (xy 88.204799 -38.019995) (xy 91.755239 -38.019995) (xy 91.759145 -37.915492)
			(xy 91.77084 -37.811573) (xy 91.79026 -37.708817) (xy 91.817295 -37.607796) (xy 91.851795 -37.509076)
			(xy 91.893567 -37.413205) (xy 91.942378 -37.320721) (xy 91.997957 -37.232137) (xy 92.059993 -37.147949)
			(xy 92.128139 -37.068627) (xy 92.202016 -36.994612) (xy 92.281212 -36.926318) (xy 92.365284 -36.864126)
			(xy 92.409264 -36.835842) (xy 92.420694 -36.828984) (xy 92.43314 -36.806378) (xy 92.43314 -36.693602)
			(xy 92.420694 -36.670996) (xy 92.409264 -36.664138) (xy 92.365275 -36.635868) (xy 92.281203 -36.573675)
			(xy 92.202008 -36.505381) (xy 92.128132 -36.431365) (xy 92.059986 -36.352042) (xy 91.997951 -36.267854)
			(xy 91.942373 -36.17927) (xy 91.893562 -36.086785) (xy 91.851791 -35.990915) (xy 91.817292 -35.892194)
			(xy 91.790257 -35.791173) (xy 91.770839 -35.688416) (xy 91.759144 -35.584497) (xy 91.755239 -35.479995)
			(xy 91.759145 -35.375492) (xy 91.77084 -35.271573) (xy 91.79026 -35.168817) (xy 91.817295 -35.067796)
			(xy 91.851795 -34.969076) (xy 91.893567 -34.873205) (xy 91.942378 -34.780721) (xy 91.997957 -34.692137)
			(xy 92.059993 -34.607949) (xy 92.128139 -34.528627) (xy 92.202016 -34.454612) (xy 92.281212 -34.386318)
			(xy 92.365284 -34.324126) (xy 92.409264 -34.295842) (xy 92.420694 -34.288984) (xy 92.43314 -34.266378)
			(xy 92.43314 -34.153602) (xy 92.420694 -34.130996) (xy 92.409264 -34.124138) (xy 92.363583 -34.094779)
			(xy 92.276461 -34.029942) (xy 92.194627 -33.958547) (xy 92.118573 -33.881024) (xy 92.048756 -33.79784)
			(xy 91.985596 -33.709495) (xy 91.929473 -33.61652) (xy 91.880726 -33.519475) (xy 91.839647 -33.418944)
			(xy 91.806483 -33.315531) (xy 91.781435 -33.209859) (xy 91.764651 -33.102564) (xy 91.756235 -32.99429)
			(xy 91.755722 -32.93999) (xy 91.756194 -32.88765) (xy 91.764017 -32.783264) (xy 91.77962 -32.679754)
			(xy 91.802914 -32.5777) (xy 91.833769 -32.477671) (xy 91.872013 -32.380228) (xy 91.917432 -32.285916)
			(xy 91.969773 -32.195261) (xy 92.028741 -32.108772) (xy 92.094008 -32.026931) (xy 92.165209 -31.950196)
			(xy 92.241944 -31.878996) (xy 92.323786 -31.81373) (xy 92.410277 -31.754763) (xy 92.500932 -31.702424)
			(xy 92.595245 -31.657006) (xy 92.692688 -31.618763) (xy 92.792717 -31.587909) (xy 92.894772 -31.564616)
			(xy 92.998282 -31.549015) (xy 93.102668 -31.541193) (xy 93.155008 -31.540704) (xy 93.209308 -31.541188)
			(xy 93.317583 -31.549606) (xy 93.424879 -31.566391) (xy 93.530551 -31.591443) (xy 93.633963 -31.624609)
			(xy 93.734494 -31.665692) (xy 93.831538 -31.714443) (xy 93.924511 -31.770569) (xy 94.012854 -31.833732)
			(xy 94.096036 -31.903553) (xy 94.173555 -31.979612) (xy 94.244946 -32.06145) (xy 94.309779 -32.148575)
			(xy 94.339156 -32.194246) (xy 94.346014 -32.205676) (xy 94.36862 -32.218122) (xy 94.481396 -32.218122)
			(xy 94.504002 -32.205676) (xy 94.51086 -32.194246) (xy 94.540214 -32.148561) (xy 94.605052 -32.06144)
			(xy 94.676448 -31.979607) (xy 94.753971 -31.903553) (xy 94.837156 -31.833736) (xy 94.925501 -31.770577)
			(xy 95.018476 -31.714455) (xy 95.115522 -31.665708) (xy 95.216053 -31.624629) (xy 95.319466 -31.591465)
			(xy 95.425138 -31.566417) (xy 95.532434 -31.549634) (xy 95.640708 -31.541217) (xy 95.695008 -31.540704)
			(xy 95.747347 -31.541196) (xy 95.851733 -31.549019) (xy 95.955242 -31.564621) (xy 96.057295 -31.587914)
			(xy 96.157323 -31.618769) (xy 96.254765 -31.657013) (xy 96.349077 -31.702431) (xy 96.439731 -31.75477)
			(xy 96.52622 -31.813738) (xy 96.608061 -31.879004) (xy 96.684796 -31.950203) (xy 96.755995 -32.026937)
			(xy 96.821261 -32.108778) (xy 96.880229 -32.195267) (xy 96.932568 -32.285921) (xy 96.977987 -32.380233)
			(xy 97.01623 -32.477675) (xy 97.047085 -32.577703) (xy 97.070379 -32.679756) (xy 97.085981 -32.783265)
			(xy 97.093804 -32.887651) (xy 97.094294 -32.93999) (xy 97.093797 -32.99429) (xy 97.09114 -33.028475)
			(xy 130.543804 -33.028475) (xy 130.543804 -32.851505) (xy 130.551858 -32.674717) (xy 130.567951 -32.49848)
			(xy 130.592049 -32.323157) (xy 130.624101 -32.149113) (xy 130.664042 -31.976709) (xy 130.711788 -31.806301)
			(xy 130.767241 -31.638242) (xy 130.830285 -31.472882) (xy 130.90079 -31.310562) (xy 130.97861 -31.15162)
			(xy 131.063584 -30.996384) (xy 131.155535 -30.845177) (xy 131.254273 -30.698312) (xy 131.359593 -30.556092)
			(xy 131.471278 -30.418814) (xy 131.589094 -30.286762) (xy 131.712799 -30.160208) (xy 131.842135 -30.039416)
			(xy 131.976836 -29.924636) (xy 132.116621 -29.816106) (xy 132.2612 -29.71405) (xy 132.410275 -29.618681)
			(xy 132.563536 -29.530196) (xy 132.720666 -29.448778) (xy 132.881339 -29.374596) (xy 133.045221 -29.307804)
			(xy 133.211974 -29.24854) (xy 133.381251 -29.196927) (xy 133.552702 -29.153072) (xy 133.725971 -29.117066)
			(xy 133.900699 -29.088984) (xy 134.076525 -29.068884) (xy 134.253083 -29.056807) (xy 134.430008 -29.052779)
			(xy 134.606933 -29.056807) (xy 134.783491 -29.068884) (xy 134.959317 -29.088984) (xy 135.134045 -29.117066)
			(xy 135.307314 -29.153072) (xy 135.478765 -29.196927) (xy 135.648042 -29.24854) (xy 135.814795 -29.307804)
			(xy 135.978677 -29.374596) (xy 136.13935 -29.448778) (xy 136.29648 -29.530196) (xy 136.449741 -29.618681)
			(xy 136.598816 -29.71405) (xy 136.743395 -29.816106) (xy 136.88318 -29.924636) (xy 137.017881 -30.039416)
			(xy 137.147217 -30.160208) (xy 137.270922 -30.286762) (xy 137.388738 -30.418814) (xy 137.500423 -30.556092)
			(xy 137.605743 -30.698312) (xy 137.704481 -30.845177) (xy 137.796432 -30.996384) (xy 137.881406 -31.15162)
			(xy 137.959226 -31.310562) (xy 138.029731 -31.472882) (xy 138.092775 -31.638242) (xy 138.148228 -31.806301)
			(xy 138.195974 -31.976709) (xy 138.235915 -32.149113) (xy 138.267967 -32.323157) (xy 138.292065 -32.49848)
			(xy 138.308158 -32.674717) (xy 138.316212 -32.851505) (xy 138.316716 -32.93999) (xy 138.316212 -33.028475)
			(xy 138.308158 -33.205263) (xy 138.292065 -33.3815) (xy 138.267967 -33.556823) (xy 138.235915 -33.730867)
			(xy 138.195974 -33.903271) (xy 138.148228 -34.073679) (xy 138.092775 -34.241738) (xy 138.029731 -34.407098)
			(xy 137.959226 -34.569418) (xy 137.881406 -34.72836) (xy 137.796432 -34.883596) (xy 137.704481 -35.034803)
			(xy 137.605743 -35.181668) (xy 137.500423 -35.323888) (xy 137.388738 -35.461166) (xy 137.270922 -35.593218)
			(xy 137.147217 -35.719772) (xy 137.017881 -35.840564) (xy 136.88318 -35.955344) (xy 136.743395 -36.063874)
			(xy 136.598816 -36.16593) (xy 136.449741 -36.261299) (xy 136.29648 -36.349784) (xy 136.13935 -36.431202)
			(xy 135.978677 -36.505384) (xy 135.814795 -36.572176) (xy 135.648042 -36.63144) (xy 135.478765 -36.683053)
			(xy 135.307314 -36.726908) (xy 135.134045 -36.762914) (xy 134.959317 -36.790996) (xy 134.783491 -36.811096)
			(xy 134.606933 -36.823173) (xy 134.430008 -36.827202) (xy 134.253083 -36.823173) (xy 134.076525 -36.811096)
			(xy 133.900699 -36.790996) (xy 133.725971 -36.762914) (xy 133.552702 -36.726908) (xy 133.381251 -36.683053)
			(xy 133.211974 -36.63144) (xy 133.045221 -36.572176) (xy 132.881339 -36.505384) (xy 132.720666 -36.431202)
			(xy 132.563536 -36.349784) (xy 132.410275 -36.261299) (xy 132.2612 -36.16593) (xy 132.116621 -36.063874)
			(xy 131.976836 -35.955344) (xy 131.842135 -35.840564) (xy 131.712799 -35.719772) (xy 131.589094 -35.593218)
			(xy 131.471278 -35.461166) (xy 131.359593 -35.323888) (xy 131.254273 -35.181668) (xy 131.155535 -35.034803)
			(xy 131.063584 -34.883596) (xy 130.97861 -34.72836) (xy 130.90079 -34.569418) (xy 130.830285 -34.407098)
			(xy 130.767241 -34.241738) (xy 130.711788 -34.073679) (xy 130.664042 -33.903271) (xy 130.624101 -33.730867)
			(xy 130.592049 -33.556823) (xy 130.567951 -33.3815) (xy 130.551858 -33.205263) (xy 130.543804 -33.028475)
			(xy 97.09114 -33.028475) (xy 97.08538 -33.102564) (xy 97.068596 -33.20986) (xy 97.043546 -33.315532)
			(xy 97.01038 -33.418944) (xy 96.969299 -33.519475) (xy 96.920549 -33.616518) (xy 96.864424 -33.709492)
			(xy 96.801262 -33.797835) (xy 96.731442 -33.881017) (xy 96.655384 -33.958537) (xy 96.573547 -34.029928)
			(xy 96.486422 -34.094761) (xy 96.440752 -34.124138) (xy 96.429322 -34.130996) (xy 96.416876 -34.153602)
			(xy 96.416876 -34.266378) (xy 96.429322 -34.288984) (xy 96.440752 -34.295842) (xy 96.484725 -34.324138)
			(xy 96.5688 -34.386327) (xy 96.647999 -34.454618) (xy 96.72188 -34.52863) (xy 96.79003 -34.607951)
			(xy 96.852068 -34.692137) (xy 96.90765 -34.78072) (xy 96.956464 -34.873204) (xy 96.998238 -34.969074)
			(xy 97.03274 -35.067794) (xy 97.059777 -35.168815) (xy 97.079197 -35.271572) (xy 97.090893 -35.375492)
			(xy 97.094799 -35.479995) (xy 97.090894 -35.584498) (xy 97.079199 -35.688418) (xy 97.059779 -35.791175)
			(xy 97.032743 -35.892196) (xy 96.998242 -35.990917) (xy 96.956469 -36.086787) (xy 96.907655 -36.179271)
			(xy 96.852074 -36.267854) (xy 96.790036 -36.352041) (xy 96.721887 -36.431362) (xy 96.648007 -36.505375)
			(xy 96.568809 -36.573666) (xy 96.484734 -36.635856) (xy 96.440752 -36.664138) (xy 96.429322 -36.670996)
			(xy 96.416876 -36.693602) (xy 96.416876 -36.806378) (xy 96.429322 -36.828984) (xy 96.440752 -36.835842)
			(xy 96.484725 -36.864138) (xy 96.5688 -36.926327) (xy 96.647999 -36.994618) (xy 96.72188 -37.06863)
			(xy 96.79003 -37.147951) (xy 96.852068 -37.232137) (xy 96.90765 -37.32072) (xy 96.956464 -37.413204)
			(xy 96.998238 -37.509074) (xy 97.03274 -37.607794) (xy 97.059777 -37.708815) (xy 97.079197 -37.811572)
			(xy 97.090893 -37.915492) (xy 97.094799 -38.019995) (xy 97.094122 -38.038117) (xy 165.038782 -38.038117)
			(xy 165.038782 -37.861147) (xy 165.046836 -37.684359) (xy 165.062929 -37.508122) (xy 165.087027 -37.332799)
			(xy 165.119079 -37.158755) (xy 165.15902 -36.986351) (xy 165.206766 -36.815943) (xy 165.262219 -36.647884)
			(xy 165.325263 -36.482524) (xy 165.395768 -36.320204) (xy 165.473588 -36.161262) (xy 165.558562 -36.006026)
			(xy 165.650513 -35.854819) (xy 165.749251 -35.707954) (xy 165.854571 -35.565734) (xy 165.966256 -35.428456)
			(xy 166.084072 -35.296404) (xy 166.207777 -35.16985) (xy 166.337113 -35.049058) (xy 166.471814 -34.934278)
			(xy 166.611599 -34.825748) (xy 166.756178 -34.723692) (xy 166.905253 -34.628323) (xy 167.058514 -34.539838)
			(xy 167.215644 -34.45842) (xy 167.376317 -34.384238) (xy 167.540199 -34.317446) (xy 167.706952 -34.258182)
			(xy 167.876229 -34.206569) (xy 168.04768 -34.162714) (xy 168.220949 -34.126708) (xy 168.395677 -34.098626)
			(xy 168.571503 -34.078526) (xy 168.748061 -34.066449) (xy 168.924986 -34.062421) (xy 169.101911 -34.066449)
			(xy 169.278469 -34.078526) (xy 169.454295 -34.098626) (xy 169.629023 -34.126708) (xy 169.802292 -34.162714)
			(xy 169.973743 -34.206569) (xy 170.14302 -34.258182) (xy 170.309773 -34.317446) (xy 170.473655 -34.384238)
			(xy 170.634328 -34.45842) (xy 170.791458 -34.539838) (xy 170.944719 -34.628323) (xy 171.093794 -34.723692)
			(xy 171.238373 -34.825748) (xy 171.378158 -34.934278) (xy 171.512859 -35.049058) (xy 171.642195 -35.16985)
			(xy 171.7659 -35.296404) (xy 171.883716 -35.428456) (xy 171.995401 -35.565734) (xy 172.100721 -35.707954)
			(xy 172.199459 -35.854819) (xy 172.29141 -36.006026) (xy 172.376384 -36.161262) (xy 172.454204 -36.320204)
			(xy 172.524709 -36.482524) (xy 172.587753 -36.647884) (xy 172.643206 -36.815943) (xy 172.690952 -36.986351)
			(xy 172.730893 -37.158755) (xy 172.762945 -37.332799) (xy 172.787043 -37.508122) (xy 172.803136 -37.684359)
			(xy 172.81119 -37.861147) (xy 172.811694 -37.949632) (xy 172.81119 -38.038117) (xy 172.803136 -38.214905)
			(xy 172.787043 -38.391142) (xy 172.762945 -38.566465) (xy 172.730893 -38.740509) (xy 172.690952 -38.912913)
			(xy 172.643206 -39.083321) (xy 172.587753 -39.25138) (xy 172.524709 -39.41674) (xy 172.454204 -39.57906)
			(xy 172.376384 -39.738002) (xy 172.29141 -39.893238) (xy 172.199459 -40.044445) (xy 172.100721 -40.19131)
			(xy 171.995401 -40.33353) (xy 171.883716 -40.470808) (xy 171.7659 -40.60286) (xy 171.642195 -40.729414)
			(xy 171.512859 -40.850206) (xy 171.378158 -40.964986) (xy 171.238373 -41.073516) (xy 171.093794 -41.175572)
			(xy 170.944719 -41.270941) (xy 170.791458 -41.359426) (xy 170.634328 -41.440844) (xy 170.473655 -41.515026)
			(xy 170.309773 -41.581818) (xy 170.14302 -41.641082) (xy 169.973743 -41.692695) (xy 169.802292 -41.73655)
			(xy 169.629023 -41.772556) (xy 169.454295 -41.800638) (xy 169.278469 -41.820738) (xy 169.101911 -41.832815)
			(xy 168.924986 -41.836844) (xy 168.748061 -41.832815) (xy 168.571503 -41.820738) (xy 168.395677 -41.800638)
			(xy 168.220949 -41.772556) (xy 168.04768 -41.73655) (xy 167.876229 -41.692695) (xy 167.706952 -41.641082)
			(xy 167.540199 -41.581818) (xy 167.376317 -41.515026) (xy 167.215644 -41.440844) (xy 167.058514 -41.359426)
			(xy 166.905253 -41.270941) (xy 166.756178 -41.175572) (xy 166.611599 -41.073516) (xy 166.471814 -40.964986)
			(xy 166.337113 -40.850206) (xy 166.207777 -40.729414) (xy 166.084072 -40.60286) (xy 165.966256 -40.470808)
			(xy 165.854571 -40.33353) (xy 165.749251 -40.19131) (xy 165.650513 -40.044445) (xy 165.558562 -39.893238)
			(xy 165.473588 -39.738002) (xy 165.395768 -39.57906) (xy 165.325263 -39.41674) (xy 165.262219 -39.25138)
			(xy 165.206766 -39.083321) (xy 165.15902 -38.912913) (xy 165.119079 -38.740509) (xy 165.087027 -38.566465)
			(xy 165.062929 -38.391142) (xy 165.046836 -38.214905) (xy 165.038782 -38.038117) (xy 97.094122 -38.038117)
			(xy 97.090894 -38.124498) (xy 97.079199 -38.228418) (xy 97.059779 -38.331175) (xy 97.032743 -38.432196)
			(xy 96.998242 -38.530917) (xy 96.956469 -38.626787) (xy 96.907655 -38.719271) (xy 96.852074 -38.807854)
			(xy 96.790036 -38.892041) (xy 96.721887 -38.971362) (xy 96.648007 -39.045375) (xy 96.568809 -39.113666)
			(xy 96.484734 -39.175856) (xy 96.440752 -39.204138) (xy 96.429322 -39.210996) (xy 96.416876 -39.233602)
			(xy 96.416876 -39.346378) (xy 96.429322 -39.368984) (xy 96.440752 -39.375842) (xy 96.486428 -39.405209)
			(xy 96.573549 -39.470046) (xy 96.655383 -39.54144) (xy 96.731437 -39.618962) (xy 96.801254 -39.702146)
			(xy 96.864414 -39.79049) (xy 96.920536 -39.883464) (xy 96.969284 -39.980509) (xy 97.010364 -40.081039)
			(xy 97.043528 -40.184451) (xy 97.068578 -40.290122) (xy 97.085362 -40.397417) (xy 97.09378 -40.50569)
			(xy 97.094294 -40.55999) (xy 97.093799 -40.612329) (xy 97.085977 -40.716716) (xy 97.070376 -40.820225)
			(xy 97.047084 -40.92228) (xy 97.01623 -41.022308) (xy 96.977987 -41.119751) (xy 96.932569 -41.214064)
			(xy 96.88023 -41.304719) (xy 96.821263 -41.391209) (xy 96.755998 -41.47305) (xy 96.684799 -41.549786)
			(xy 96.608064 -41.620986) (xy 96.526223 -41.686253) (xy 96.439734 -41.745221) (xy 96.34908 -41.797561)
			(xy 96.254768 -41.84298) (xy 96.157325 -41.881224) (xy 96.057297 -41.912079) (xy 95.955243 -41.935373)
			(xy 95.851733 -41.950975) (xy 95.747347 -41.958798) (xy 95.695008 -41.959276) (xy 95.640709 -41.958742)
			(xy 95.532437 -41.950326) (xy 95.425143 -41.933543) (xy 95.319473 -41.908494) (xy 95.216062 -41.875331)
			(xy 95.115532 -41.834252) (xy 95.018489 -41.785505) (xy 94.925516 -41.729384) (xy 94.837172 -41.666225)
			(xy 94.753989 -41.596409) (xy 94.676468 -41.520355) (xy 94.605075 -41.438522) (xy 94.540239 -41.351402)
			(xy 94.51086 -41.305734) (xy 94.504002 -41.294304) (xy 94.481396 -41.281858) (xy 94.36862 -41.281858)
			(xy 94.346014 -41.294304) (xy 94.339156 -41.305734) (xy 94.309784 -41.351407) (xy 94.244948 -41.438528)
			(xy 94.173554 -41.520362) (xy 94.096033 -41.596417) (xy 94.01285 -41.666234) (xy 93.924506 -41.729395)
			(xy 93.831532 -41.785518) (xy 93.734488 -41.834266) (xy 93.633958 -41.875346) (xy 93.530547 -41.90851)
			(xy 93.424875 -41.93356) (xy 93.317581 -41.950345) (xy 93.209308 -41.958762) (xy 93.155008 -41.959276)
			(xy 93.102668 -41.958801) (xy 92.998281 -41.950979) (xy 92.894771 -41.935377) (xy 92.792715 -41.912084)
			(xy 92.692686 -41.88123) (xy 92.595242 -41.842986) (xy 92.500929 -41.797568) (xy 92.410274 -41.745228)
			(xy 92.323783 -41.68626) (xy 92.241941 -41.620993) (xy 92.165206 -41.549793) (xy 92.094006 -41.473057)
			(xy 92.028739 -41.391215) (xy 91.969771 -41.304725) (xy 91.917431 -41.214069) (xy 91.872013 -41.119756)
			(xy 91.833769 -41.022312) (xy 91.802915 -40.922283) (xy 91.779622 -40.820228) (xy 91.764021 -40.716717)
			(xy 91.756199 -40.61233) (xy 91.755722 -40.55999) (xy 91.756242 -40.50569) (xy 91.76466 -40.397418)
			(xy 91.781445 -40.290124) (xy 91.806494 -40.184453) (xy 91.839659 -40.081042) (xy 91.880739 -39.980513)
			(xy 91.929487 -39.883469) (xy 91.985609 -39.790496) (xy 92.048769 -39.702153) (xy 92.118586 -39.61897)
			(xy 92.194641 -39.541449) (xy 92.276474 -39.470056) (xy 92.363596 -39.40522) (xy 92.409264 -39.375842)
			(xy 92.420694 -39.368984) (xy 92.43314 -39.346378) (xy 92.43314 -39.233602) (xy 92.420694 -39.210996)
			(xy 92.409264 -39.204138) (xy 92.365275 -39.175868) (xy 92.281203 -39.113675) (xy 92.202008 -39.045381)
			(xy 92.128132 -38.971365) (xy 92.059986 -38.892042) (xy 91.997951 -38.807854) (xy 91.942373 -38.71927)
			(xy 91.893562 -38.626785) (xy 91.851791 -38.530915) (xy 91.817292 -38.432194) (xy 91.790257 -38.331173)
			(xy 91.770839 -38.228416) (xy 91.759144 -38.124497) (xy 91.755239 -38.019995) (xy 88.204799 -38.019995)
			(xy 88.200894 -38.124498) (xy 88.189199 -38.228418) (xy 88.169779 -38.331175) (xy 88.142743 -38.432196)
			(xy 88.108242 -38.530917) (xy 88.066469 -38.626787) (xy 88.017655 -38.719271) (xy 87.962074 -38.807854)
			(xy 87.900036 -38.892041) (xy 87.831887 -38.971362) (xy 87.758007 -39.045375) (xy 87.678809 -39.113666)
			(xy 87.594734 -39.175856) (xy 87.550752 -39.204138) (xy 87.539322 -39.210996) (xy 87.526876 -39.233602)
			(xy 87.526876 -39.346378) (xy 87.539322 -39.368984) (xy 87.550752 -39.375842) (xy 87.596428 -39.405209)
			(xy 87.683549 -39.470046) (xy 87.765383 -39.54144) (xy 87.841437 -39.618962) (xy 87.911254 -39.702146)
			(xy 87.974414 -39.79049) (xy 88.030536 -39.883464) (xy 88.079284 -39.980509) (xy 88.120364 -40.081039)
			(xy 88.153528 -40.184451) (xy 88.178578 -40.290122) (xy 88.195362 -40.397417) (xy 88.20378 -40.50569)
			(xy 88.204294 -40.55999) (xy 88.203799 -40.612329) (xy 88.195977 -40.716716) (xy 88.180376 -40.820225)
			(xy 88.157084 -40.92228) (xy 88.12623 -41.022308) (xy 88.087987 -41.119751) (xy 88.042569 -41.214064)
			(xy 87.99023 -41.304719) (xy 87.931263 -41.391209) (xy 87.865998 -41.47305) (xy 87.794799 -41.549786)
			(xy 87.718064 -41.620986) (xy 87.636223 -41.686253) (xy 87.549734 -41.745221) (xy 87.45908 -41.797561)
			(xy 87.364768 -41.84298) (xy 87.267325 -41.881224) (xy 87.167297 -41.912079) (xy 87.065243 -41.935373)
			(xy 86.961733 -41.950975) (xy 86.857347 -41.958798) (xy 86.805008 -41.959276) (xy 86.750709 -41.958742)
			(xy 86.642437 -41.950326) (xy 86.535143 -41.933543) (xy 86.429473 -41.908494) (xy 86.326062 -41.875331)
			(xy 86.225532 -41.834252) (xy 86.128489 -41.785505) (xy 86.035516 -41.729384) (xy 85.947172 -41.666225)
			(xy 85.863989 -41.596409) (xy 85.786468 -41.520355) (xy 85.715075 -41.438522) (xy 85.650239 -41.351402)
			(xy 85.62086 -41.305734) (xy 85.614002 -41.294304) (xy 85.591396 -41.281858) (xy 85.47862 -41.281858)
			(xy 85.456014 -41.294304) (xy 85.449156 -41.305734) (xy 85.419784 -41.351407) (xy 85.354948 -41.438528)
			(xy 85.283554 -41.520362) (xy 85.206033 -41.596417) (xy 85.12285 -41.666234) (xy 85.034506 -41.729395)
			(xy 84.941532 -41.785518) (xy 84.844488 -41.834266) (xy 84.743958 -41.875346) (xy 84.640547 -41.90851)
			(xy 84.534875 -41.93356) (xy 84.427581 -41.950345) (xy 84.319308 -41.958762) (xy 84.265008 -41.959276)
			(xy 84.212668 -41.958801) (xy 84.108281 -41.950979) (xy 84.004771 -41.935377) (xy 83.902715 -41.912084)
			(xy 83.802686 -41.88123) (xy 83.705242 -41.842986) (xy 83.610929 -41.797568) (xy 83.520274 -41.745228)
			(xy 83.433783 -41.68626) (xy 83.351941 -41.620993) (xy 83.275206 -41.549793) (xy 83.204006 -41.473057)
			(xy 83.138739 -41.391215) (xy 83.079771 -41.304725) (xy 83.027431 -41.214069) (xy 82.982013 -41.119756)
			(xy 82.943769 -41.022312) (xy 82.912915 -40.922283) (xy 82.889622 -40.820228) (xy 82.874021 -40.716717)
			(xy 82.866199 -40.61233) (xy 82.865722 -40.55999) (xy 82.866242 -40.50569) (xy 82.87466 -40.397418)
			(xy 82.891445 -40.290124) (xy 82.916494 -40.184453) (xy 82.949659 -40.081042) (xy 82.990739 -39.980513)
			(xy 83.039487 -39.883469) (xy 83.095609 -39.790496) (xy 83.158769 -39.702153) (xy 83.228586 -39.61897)
			(xy 83.304641 -39.541449) (xy 83.386474 -39.470056) (xy 83.473596 -39.40522) (xy 83.519264 -39.375842)
			(xy 83.530694 -39.368984) (xy 83.54314 -39.346378) (xy 83.54314 -39.233602) (xy 83.530694 -39.210996)
			(xy 83.519264 -39.204138) (xy 83.475275 -39.175868) (xy 83.391203 -39.113675) (xy 83.312008 -39.045381)
			(xy 83.238132 -38.971365) (xy 83.169986 -38.892042) (xy 83.107951 -38.807854) (xy 83.052373 -38.71927)
			(xy 83.003562 -38.626785) (xy 82.961791 -38.530915) (xy 82.927292 -38.432194) (xy 82.900257 -38.331173)
			(xy 82.880839 -38.228416) (xy 82.869144 -38.124497) (xy 82.865239 -38.019995) (xy 79.314799 -38.019995)
			(xy 79.310894 -38.124498) (xy 79.299199 -38.228418) (xy 79.279779 -38.331175) (xy 79.252743 -38.432196)
			(xy 79.218242 -38.530917) (xy 79.176469 -38.626787) (xy 79.127655 -38.719271) (xy 79.072074 -38.807854)
			(xy 79.010036 -38.892041) (xy 78.941887 -38.971362) (xy 78.868007 -39.045375) (xy 78.788809 -39.113666)
			(xy 78.704734 -39.175856) (xy 78.660752 -39.204138) (xy 78.649322 -39.210996) (xy 78.636876 -39.233602)
			(xy 78.636876 -39.346378) (xy 78.649322 -39.368984) (xy 78.660752 -39.375842) (xy 78.706428 -39.405209)
			(xy 78.793549 -39.470046) (xy 78.875383 -39.54144) (xy 78.951437 -39.618962) (xy 79.021254 -39.702146)
			(xy 79.084414 -39.79049) (xy 79.140536 -39.883464) (xy 79.189284 -39.980509) (xy 79.230364 -40.081039)
			(xy 79.263528 -40.184451) (xy 79.288578 -40.290122) (xy 79.305362 -40.397417) (xy 79.31378 -40.50569)
			(xy 79.314294 -40.55999) (xy 79.313799 -40.612329) (xy 79.305977 -40.716716) (xy 79.290376 -40.820225)
			(xy 79.267084 -40.92228) (xy 79.23623 -41.022308) (xy 79.197987 -41.119751) (xy 79.152569 -41.214064)
			(xy 79.10023 -41.304719) (xy 79.041263 -41.391209) (xy 78.975998 -41.47305) (xy 78.904799 -41.549786)
			(xy 78.828064 -41.620986) (xy 78.746223 -41.686253) (xy 78.659734 -41.745221) (xy 78.56908 -41.797561)
			(xy 78.474768 -41.84298) (xy 78.377325 -41.881224) (xy 78.277297 -41.912079) (xy 78.175243 -41.935373)
			(xy 78.071733 -41.950975) (xy 77.967347 -41.958798) (xy 77.915008 -41.959276) (xy 77.860709 -41.958742)
			(xy 77.752437 -41.950326) (xy 77.645143 -41.933543) (xy 77.539473 -41.908494) (xy 77.436062 -41.875331)
			(xy 77.335532 -41.834252) (xy 77.238489 -41.785505) (xy 77.145516 -41.729384) (xy 77.057172 -41.666225)
			(xy 76.973989 -41.596409) (xy 76.896468 -41.520355) (xy 76.825075 -41.438522) (xy 76.760239 -41.351402)
			(xy 76.73086 -41.305734) (xy 76.724002 -41.294304) (xy 76.701396 -41.281858) (xy 76.58862 -41.281858)
			(xy 76.566014 -41.294304) (xy 76.559156 -41.305734) (xy 76.529784 -41.351407) (xy 76.464948 -41.438528)
			(xy 76.393554 -41.520362) (xy 76.316033 -41.596417) (xy 76.23285 -41.666234) (xy 76.144506 -41.729395)
			(xy 76.051532 -41.785518) (xy 75.954488 -41.834266) (xy 75.853958 -41.875346) (xy 75.750547 -41.90851)
			(xy 75.644875 -41.93356) (xy 75.537581 -41.950345) (xy 75.429308 -41.958762) (xy 75.375008 -41.959276)
			(xy 75.322668 -41.958801) (xy 75.218281 -41.950979) (xy 75.114771 -41.935377) (xy 75.012715 -41.912084)
			(xy 74.912686 -41.88123) (xy 74.815242 -41.842986) (xy 74.720929 -41.797568) (xy 74.630274 -41.745228)
			(xy 74.543783 -41.68626) (xy 74.461941 -41.620993) (xy 74.385206 -41.549793) (xy 74.314006 -41.473057)
			(xy 74.248739 -41.391215) (xy 74.189771 -41.304725) (xy 74.137431 -41.214069) (xy 74.092013 -41.119756)
			(xy 74.053769 -41.022312) (xy 74.022915 -40.922283) (xy 73.999622 -40.820228) (xy 73.984021 -40.716717)
			(xy 73.976199 -40.61233) (xy 73.975722 -40.55999) (xy 73.976242 -40.50569) (xy 73.98466 -40.397418)
			(xy 74.001445 -40.290124) (xy 74.026494 -40.184453) (xy 74.059659 -40.081042) (xy 74.100739 -39.980513)
			(xy 74.149487 -39.883469) (xy 74.205609 -39.790496) (xy 74.268769 -39.702153) (xy 74.338586 -39.61897)
			(xy 74.414641 -39.541449) (xy 74.496474 -39.470056) (xy 74.583596 -39.40522) (xy 74.629264 -39.375842)
			(xy 74.640694 -39.368984) (xy 74.65314 -39.346378) (xy 74.65314 -39.233602) (xy 74.640694 -39.210996)
			(xy 74.629264 -39.204138) (xy 74.585275 -39.175868) (xy 74.501203 -39.113675) (xy 74.422008 -39.045381)
			(xy 74.348132 -38.971365) (xy 74.279986 -38.892042) (xy 74.217951 -38.807854) (xy 74.162373 -38.71927)
			(xy 74.113562 -38.626785) (xy 74.071791 -38.530915) (xy 74.037292 -38.432194) (xy 74.010257 -38.331173)
			(xy 73.990839 -38.228416) (xy 73.979144 -38.124497) (xy 73.975239 -38.019995) (xy 32.171386 -38.019995)
			(xy 32.171386 -49.1236) (xy 35.37199 -52.324) (xy 74.548492 -52.324) (xy 74.548938 -52.285712) (xy 74.555556 -52.209422)
			(xy 74.5687 -52.133982) (xy 74.588274 -52.05995) (xy 74.600816 -52.023772) (xy 74.603457 -52.015334)
			(xy 74.603457 -51.997666) (xy 74.600816 -51.989228) (xy 74.58826 -51.953053) (xy 74.568663 -51.879024)
			(xy 74.555512 -51.803583) (xy 74.548903 -51.727289) (xy 74.548492 -51.689) (xy 74.548913 -51.648946)
			(xy 74.556124 -51.569165) (xy 74.570479 -51.490354) (xy 74.591862 -51.413153) (xy 74.620098 -51.338188)
			(xy 74.654961 -51.266064) (xy 74.696167 -51.197368) (xy 74.743382 -51.132654) (xy 74.769472 -51.10226)
			(xy 74.775157 -51.09514) (xy 74.781541 -51.078089) (xy 74.781918 -51.068986) (xy 74.781918 -51.039014)
			(xy 74.781534 -51.029912) (xy 74.775154 -51.012861) (xy 74.769472 -51.00574) (xy 74.743386 -50.975343)
			(xy 74.696168 -50.910632) (xy 74.654961 -50.841936) (xy 74.620099 -50.769813) (xy 74.591865 -50.694847)
			(xy 74.570486 -50.617646) (xy 74.556136 -50.538835) (xy 74.548932 -50.459053) (xy 74.548492 -50.419)
			(xy 74.548938 -50.380712) (xy 74.555556 -50.304422) (xy 74.5687 -50.228982) (xy 74.588274 -50.15495)
			(xy 74.600816 -50.118772) (xy 74.603457 -50.110334) (xy 74.603457 -50.092666) (xy 74.600816 -50.084228)
			(xy 74.58826 -50.048053) (xy 74.568663 -49.974024) (xy 74.555512 -49.898583) (xy 74.548903 -49.822289)
			(xy 74.548492 -49.784) (xy 74.548996 -49.741652) (xy 74.557047 -49.657338) (xy 74.573076 -49.574172)
			(xy 74.596937 -49.492905) (xy 74.628416 -49.414275) (xy 74.667227 -49.338994) (xy 74.713017 -49.267742)
			(xy 74.765373 -49.201166) (xy 74.823821 -49.139868) (xy 74.887831 -49.084403) (xy 74.956823 -49.035274)
			(xy 75.030173 -48.992925) (xy 75.107216 -48.957741) (xy 75.187255 -48.930039) (xy 75.269564 -48.910071)
			(xy 75.353399 -48.898018) (xy 75.438 -48.893988) (xy 75.522601 -48.898018) (xy 75.606436 -48.910071)
			(xy 75.688745 -48.930039) (xy 75.768784 -48.957741) (xy 75.845827 -48.992925) (xy 75.919177 -49.035274)
			(xy 75.988169 -49.084403) (xy 76.052179 -49.139868) (xy 76.110627 -49.201166) (xy 76.162983 -49.267742)
			(xy 76.208773 -49.338994) (xy 76.247584 -49.414275) (xy 76.279063 -49.492905) (xy 76.302924 -49.574172)
			(xy 76.318953 -49.657338) (xy 76.327004 -49.741652) (xy 76.327508 -49.784) (xy 76.327062 -49.822288)
			(xy 76.320444 -49.898578) (xy 76.3073 -49.974018) (xy 76.287726 -50.04805) (xy 76.275184 -50.084228)
			(xy 76.272543 -50.092666) (xy 76.272543 -50.110334) (xy 76.275184 -50.118772) (xy 76.28774 -50.154947)
			(xy 76.307337 -50.228976) (xy 76.320488 -50.304417) (xy 76.327097 -50.380711) (xy 76.327508 -50.419)
			(xy 76.327087 -50.459054) (xy 76.319876 -50.538835) (xy 76.305521 -50.617646) (xy 76.284138 -50.694847)
			(xy 76.255902 -50.769812) (xy 76.221039 -50.841936) (xy 76.179833 -50.910632) (xy 76.132618 -50.975346)
			(xy 76.106528 -51.00574) (xy 76.100843 -51.01286) (xy 76.094459 -51.029911) (xy 76.094082 -51.039014)
			(xy 76.094082 -51.068986) (xy 76.094466 -51.078088) (xy 76.100846 -51.095139) (xy 76.106528 -51.10226)
			(xy 76.132614 -51.132657) (xy 76.179832 -51.197368) (xy 76.221039 -51.266064) (xy 76.255901 -51.338187)
			(xy 76.284135 -51.413153) (xy 76.305514 -51.490354) (xy 76.319864 -51.569165) (xy 76.327068 -51.648947)
			(xy 76.327508 -51.689) (xy 76.327062 -51.727288) (xy 76.320444 -51.803578) (xy 76.3073 -51.879018)
			(xy 76.287726 -51.95305) (xy 76.275184 -51.989228) (xy 76.272543 -51.997666) (xy 76.272543 -52.015334)
			(xy 76.275184 -52.023772) (xy 76.28774 -52.059947) (xy 76.307337 -52.133976) (xy 76.320488 -52.209417)
			(xy 76.327097 -52.285711) (xy 76.327508 -52.324) (xy 80.009492 -52.324) (xy 80.009938 -52.285712)
			(xy 80.016556 -52.209422) (xy 80.0297 -52.133982) (xy 80.049274 -52.05995) (xy 80.061816 -52.023772)
			(xy 80.064457 -52.015334) (xy 80.064457 -51.997666) (xy 80.061816 -51.989228) (xy 80.04926 -51.953053)
			(xy 80.029663 -51.879024) (xy 80.016512 -51.803583) (xy 80.009903 -51.727289) (xy 80.009492 -51.689)
			(xy 80.009913 -51.648946) (xy 80.017124 -51.569165) (xy 80.031479 -51.490354) (xy 80.052862 -51.413153)
			(xy 80.081098 -51.338188) (xy 80.115961 -51.266064) (xy 80.157167 -51.197368) (xy 80.204382 -51.132654)
			(xy 80.230472 -51.10226) (xy 80.236157 -51.09514) (xy 80.242541 -51.078089) (xy 80.242918 -51.068986)
			(xy 80.242918 -51.039014) (xy 80.242534 -51.029912) (xy 80.236154 -51.012861) (xy 80.230472 -51.00574)
			(xy 80.204386 -50.975343) (xy 80.157168 -50.910632) (xy 80.115961 -50.841936) (xy 80.081099 -50.769813)
			(xy 80.052865 -50.694847) (xy 80.031486 -50.617646) (xy 80.017136 -50.538835) (xy 80.009932 -50.459053)
			(xy 80.009492 -50.419) (xy 80.009938 -50.380712) (xy 80.016556 -50.304422) (xy 80.0297 -50.228982)
			(xy 80.049274 -50.15495) (xy 80.061816 -50.118772) (xy 80.064457 -50.110334) (xy 80.064457 -50.092666)
			(xy 80.061816 -50.084228) (xy 80.04926 -50.048053) (xy 80.029663 -49.974024) (xy 80.016512 -49.898583)
			(xy 80.009903 -49.822289) (xy 80.009492 -49.784) (xy 80.009996 -49.741652) (xy 80.018047 -49.657338)
			(xy 80.034076 -49.574172) (xy 80.057937 -49.492905) (xy 80.089416 -49.414275) (xy 80.128227 -49.338994)
			(xy 80.174017 -49.267742) (xy 80.226373 -49.201166) (xy 80.284821 -49.139868) (xy 80.348831 -49.084403)
			(xy 80.417823 -49.035274) (xy 80.491173 -48.992925) (xy 80.568216 -48.957741) (xy 80.648255 -48.930039)
			(xy 80.730564 -48.910071) (xy 80.814399 -48.898018) (xy 80.899 -48.893988) (xy 80.983601 -48.898018)
			(xy 81.067436 -48.910071) (xy 81.149745 -48.930039) (xy 81.229784 -48.957741) (xy 81.306827 -48.992925)
			(xy 81.380177 -49.035274) (xy 81.449169 -49.084403) (xy 81.513179 -49.139868) (xy 81.571627 -49.201166)
			(xy 81.623983 -49.267742) (xy 81.669773 -49.338994) (xy 81.708584 -49.414275) (xy 81.740063 -49.492905)
			(xy 81.763924 -49.574172) (xy 81.779953 -49.657338) (xy 81.788004 -49.741652) (xy 81.788508 -49.784)
			(xy 81.788062 -49.822288) (xy 81.781444 -49.898578) (xy 81.7683 -49.974018) (xy 81.748726 -50.04805)
			(xy 81.736184 -50.084228) (xy 81.733543 -50.092666) (xy 81.733543 -50.110334) (xy 81.736184 -50.118772)
			(xy 81.74874 -50.154947) (xy 81.768337 -50.228976) (xy 81.781488 -50.304417) (xy 81.788097 -50.380711)
			(xy 81.788508 -50.419) (xy 81.788087 -50.459054) (xy 81.780876 -50.538835) (xy 81.766521 -50.617646)
			(xy 81.745138 -50.694847) (xy 81.716902 -50.769812) (xy 81.682039 -50.841936) (xy 81.640833 -50.910632)
			(xy 81.593618 -50.975346) (xy 81.567528 -51.00574) (xy 81.561843 -51.01286) (xy 81.555459 -51.029911)
			(xy 81.555082 -51.039014) (xy 81.555082 -51.068986) (xy 81.555466 -51.078088) (xy 81.561846 -51.095139)
			(xy 81.567528 -51.10226) (xy 81.593614 -51.132657) (xy 81.640832 -51.197368) (xy 81.682039 -51.266064)
			(xy 81.716901 -51.338187) (xy 81.745135 -51.413153) (xy 81.766514 -51.490354) (xy 81.780864 -51.569165)
			(xy 81.788068 -51.648947) (xy 81.788508 -51.689) (xy 81.788062 -51.727288) (xy 81.781444 -51.803578)
			(xy 81.7683 -51.879018) (xy 81.748726 -51.95305) (xy 81.736184 -51.989228) (xy 81.733543 -51.997666)
			(xy 81.733543 -52.015334) (xy 81.736184 -52.023772) (xy 81.74874 -52.059947) (xy 81.768337 -52.133976)
			(xy 81.781488 -52.209417) (xy 81.788097 -52.285711) (xy 81.788508 -52.324) (xy 85.470492 -52.324)
			(xy 85.470938 -52.285712) (xy 85.477556 -52.209422) (xy 85.4907 -52.133982) (xy 85.510274 -52.05995)
			(xy 85.522816 -52.023772) (xy 85.525457 -52.015334) (xy 85.525457 -51.997666) (xy 85.522816 -51.989228)
			(xy 85.51026 -51.953053) (xy 85.490663 -51.879024) (xy 85.477512 -51.803583) (xy 85.470903 -51.727289)
			(xy 85.470492 -51.689) (xy 85.470913 -51.648946) (xy 85.478124 -51.569165) (xy 85.492479 -51.490354)
			(xy 85.513862 -51.413153) (xy 85.542098 -51.338188) (xy 85.576961 -51.266064) (xy 85.618167 -51.197368)
			(xy 85.665382 -51.132654) (xy 85.691472 -51.10226) (xy 85.697157 -51.09514) (xy 85.703541 -51.078089)
			(xy 85.703918 -51.068986) (xy 85.703918 -51.039014) (xy 85.703534 -51.029912) (xy 85.697154 -51.012861)
			(xy 85.691472 -51.00574) (xy 85.665386 -50.975343) (xy 85.618168 -50.910632) (xy 85.576961 -50.841936)
			(xy 85.542099 -50.769813) (xy 85.513865 -50.694847) (xy 85.492486 -50.617646) (xy 85.478136 -50.538835)
			(xy 85.470932 -50.459053) (xy 85.470492 -50.419) (xy 85.470938 -50.380712) (xy 85.477556 -50.304422)
			(xy 85.4907 -50.228982) (xy 85.510274 -50.15495) (xy 85.522816 -50.118772) (xy 85.525457 -50.110334)
			(xy 85.525457 -50.092666) (xy 85.522816 -50.084228) (xy 85.51026 -50.048053) (xy 85.490663 -49.974024)
			(xy 85.477512 -49.898583) (xy 85.470903 -49.822289) (xy 85.470492 -49.784) (xy 85.470996 -49.741652)
			(xy 85.479047 -49.657338) (xy 85.495076 -49.574172) (xy 85.518937 -49.492905) (xy 85.550416 -49.414275)
			(xy 85.589227 -49.338994) (xy 85.635017 -49.267742) (xy 85.687373 -49.201166) (xy 85.745821 -49.139868)
			(xy 85.809831 -49.084403) (xy 85.878823 -49.035274) (xy 85.952173 -48.992925) (xy 86.029216 -48.957741)
			(xy 86.109255 -48.930039) (xy 86.191564 -48.910071) (xy 86.275399 -48.898018) (xy 86.36 -48.893988)
			(xy 86.444601 -48.898018) (xy 86.528436 -48.910071) (xy 86.610745 -48.930039) (xy 86.690784 -48.957741)
			(xy 86.767827 -48.992925) (xy 86.841177 -49.035274) (xy 86.910169 -49.084403) (xy 86.974179 -49.139868)
			(xy 87.032627 -49.201166) (xy 87.084983 -49.267742) (xy 87.130773 -49.338994) (xy 87.169584 -49.414275)
			(xy 87.201063 -49.492905) (xy 87.224924 -49.574172) (xy 87.240953 -49.657338) (xy 87.249004 -49.741652)
			(xy 87.249508 -49.784) (xy 87.249062 -49.822288) (xy 87.242444 -49.898578) (xy 87.2293 -49.974018)
			(xy 87.209726 -50.04805) (xy 87.197184 -50.084228) (xy 87.194543 -50.092666) (xy 87.194543 -50.110334)
			(xy 87.197184 -50.118772) (xy 87.20974 -50.154947) (xy 87.229337 -50.228976) (xy 87.242488 -50.304417)
			(xy 87.249097 -50.380711) (xy 87.249508 -50.419) (xy 87.249087 -50.459054) (xy 87.241876 -50.538835)
			(xy 87.227521 -50.617646) (xy 87.206138 -50.694847) (xy 87.177902 -50.769812) (xy 87.143039 -50.841936)
			(xy 87.101833 -50.910632) (xy 87.054618 -50.975346) (xy 87.028528 -51.00574) (xy 87.022843 -51.01286)
			(xy 87.016459 -51.029911) (xy 87.016082 -51.039014) (xy 87.016082 -51.068986) (xy 87.016466 -51.078088)
			(xy 87.022846 -51.095139) (xy 87.028528 -51.10226) (xy 87.054614 -51.132657) (xy 87.101832 -51.197368)
			(xy 87.143039 -51.266064) (xy 87.177901 -51.338187) (xy 87.206135 -51.413153) (xy 87.227514 -51.490354)
			(xy 87.241864 -51.569165) (xy 87.249068 -51.648947) (xy 87.249508 -51.689) (xy 87.249062 -51.727288)
			(xy 87.242444 -51.803578) (xy 87.2293 -51.879018) (xy 87.209726 -51.95305) (xy 87.197184 -51.989228)
			(xy 87.194543 -51.997666) (xy 87.194543 -52.015334) (xy 87.197184 -52.023772) (xy 87.20974 -52.059947)
			(xy 87.229337 -52.133976) (xy 87.242488 -52.209417) (xy 87.249097 -52.285711) (xy 87.249508 -52.324)
			(xy 90.931492 -52.324) (xy 90.931938 -52.285712) (xy 90.938556 -52.209422) (xy 90.9517 -52.133982)
			(xy 90.971274 -52.05995) (xy 90.983816 -52.023772) (xy 90.986457 -52.015334) (xy 90.986457 -51.997666)
			(xy 90.983816 -51.989228) (xy 90.97126 -51.953053) (xy 90.951663 -51.879024) (xy 90.938512 -51.803583)
			(xy 90.931903 -51.727289) (xy 90.931492 -51.689) (xy 90.931913 -51.648946) (xy 90.939124 -51.569165)
			(xy 90.953479 -51.490354) (xy 90.974862 -51.413153) (xy 91.003098 -51.338188) (xy 91.037961 -51.266064)
			(xy 91.079167 -51.197368) (xy 91.126382 -51.132654) (xy 91.152472 -51.10226) (xy 91.158157 -51.09514)
			(xy 91.164541 -51.078089) (xy 91.164918 -51.068986) (xy 91.164918 -51.039014) (xy 91.164534 -51.029912)
			(xy 91.158154 -51.012861) (xy 91.152472 -51.00574) (xy 91.126386 -50.975343) (xy 91.079168 -50.910632)
			(xy 91.037961 -50.841936) (xy 91.003099 -50.769813) (xy 90.974865 -50.694847) (xy 90.953486 -50.617646)
			(xy 90.939136 -50.538835) (xy 90.931932 -50.459053) (xy 90.931492 -50.419) (xy 90.931938 -50.380712)
			(xy 90.938556 -50.304422) (xy 90.9517 -50.228982) (xy 90.971274 -50.15495) (xy 90.983816 -50.118772)
			(xy 90.986457 -50.110334) (xy 90.986457 -50.092666) (xy 90.983816 -50.084228) (xy 90.97126 -50.048053)
			(xy 90.951663 -49.974024) (xy 90.938512 -49.898583) (xy 90.931903 -49.822289) (xy 90.931492 -49.784)
			(xy 90.931996 -49.741652) (xy 90.940047 -49.657338) (xy 90.956076 -49.574172) (xy 90.979937 -49.492905)
			(xy 91.011416 -49.414275) (xy 91.050227 -49.338994) (xy 91.096017 -49.267742) (xy 91.148373 -49.201166)
			(xy 91.206821 -49.139868) (xy 91.270831 -49.084403) (xy 91.339823 -49.035274) (xy 91.413173 -48.992925)
			(xy 91.490216 -48.957741) (xy 91.570255 -48.930039) (xy 91.652564 -48.910071) (xy 91.736399 -48.898018)
			(xy 91.821 -48.893988) (xy 91.905601 -48.898018) (xy 91.989436 -48.910071) (xy 92.071745 -48.930039)
			(xy 92.151784 -48.957741) (xy 92.228827 -48.992925) (xy 92.302177 -49.035274) (xy 92.371169 -49.084403)
			(xy 92.435179 -49.139868) (xy 92.493627 -49.201166) (xy 92.545983 -49.267742) (xy 92.591773 -49.338994)
			(xy 92.630584 -49.414275) (xy 92.662063 -49.492905) (xy 92.685924 -49.574172) (xy 92.701953 -49.657338)
			(xy 92.710004 -49.741652) (xy 92.710508 -49.784) (xy 92.710062 -49.822288) (xy 92.703444 -49.898578)
			(xy 92.6903 -49.974018) (xy 92.670726 -50.04805) (xy 92.658184 -50.084228) (xy 92.655543 -50.092666)
			(xy 92.655543 -50.110334) (xy 92.658184 -50.118772) (xy 92.67074 -50.154947) (xy 92.690337 -50.228976)
			(xy 92.703488 -50.304417) (xy 92.710097 -50.380711) (xy 92.710508 -50.419) (xy 92.710087 -50.459054)
			(xy 92.702876 -50.538835) (xy 92.688521 -50.617646) (xy 92.667138 -50.694847) (xy 92.638902 -50.769812)
			(xy 92.604039 -50.841936) (xy 92.562833 -50.910632) (xy 92.515618 -50.975346) (xy 92.489528 -51.00574)
			(xy 92.483843 -51.01286) (xy 92.477459 -51.029911) (xy 92.477082 -51.039014) (xy 92.477082 -51.068986)
			(xy 92.477466 -51.078088) (xy 92.483846 -51.095139) (xy 92.489528 -51.10226) (xy 92.515614 -51.132657)
			(xy 92.562832 -51.197368) (xy 92.604039 -51.266064) (xy 92.638901 -51.338187) (xy 92.667135 -51.413153)
			(xy 92.688514 -51.490354) (xy 92.702864 -51.569165) (xy 92.710068 -51.648947) (xy 92.710508 -51.689)
			(xy 92.710062 -51.727288) (xy 92.703444 -51.803578) (xy 92.6903 -51.879018) (xy 92.670726 -51.95305)
			(xy 92.658184 -51.989228) (xy 92.655543 -51.997666) (xy 92.655543 -52.015334) (xy 92.658184 -52.023772)
			(xy 92.67074 -52.059947) (xy 92.690337 -52.133976) (xy 92.703488 -52.209417) (xy 92.710097 -52.285711)
			(xy 92.710508 -52.324) (xy 96.392492 -52.324) (xy 96.392938 -52.285712) (xy 96.399556 -52.209422)
			(xy 96.4127 -52.133982) (xy 96.432274 -52.05995) (xy 96.444816 -52.023772) (xy 96.447457 -52.015334)
			(xy 96.447457 -51.997666) (xy 96.444816 -51.989228) (xy 96.43226 -51.953053) (xy 96.412663 -51.879024)
			(xy 96.399512 -51.803583) (xy 96.392903 -51.727289) (xy 96.392492 -51.689) (xy 96.392913 -51.648946)
			(xy 96.400124 -51.569165) (xy 96.414479 -51.490354) (xy 96.435862 -51.413153) (xy 96.464098 -51.338188)
			(xy 96.498961 -51.266064) (xy 96.540167 -51.197368) (xy 96.587382 -51.132654) (xy 96.613472 -51.10226)
			(xy 96.619157 -51.09514) (xy 96.625541 -51.078089) (xy 96.625918 -51.068986) (xy 96.625918 -51.039014)
			(xy 96.625534 -51.029912) (xy 96.619154 -51.012861) (xy 96.613472 -51.00574) (xy 96.587386 -50.975343)
			(xy 96.540168 -50.910632) (xy 96.498961 -50.841936) (xy 96.464099 -50.769813) (xy 96.435865 -50.694847)
			(xy 96.414486 -50.617646) (xy 96.400136 -50.538835) (xy 96.392932 -50.459053) (xy 96.392492 -50.419)
			(xy 96.392938 -50.380712) (xy 96.399556 -50.304422) (xy 96.4127 -50.228982) (xy 96.432274 -50.15495)
			(xy 96.444816 -50.118772) (xy 96.447457 -50.110334) (xy 96.447457 -50.092666) (xy 96.444816 -50.084228)
			(xy 96.43226 -50.048053) (xy 96.412663 -49.974024) (xy 96.399512 -49.898583) (xy 96.392903 -49.822289)
			(xy 96.392492 -49.784) (xy 96.392996 -49.741652) (xy 96.401047 -49.657338) (xy 96.417076 -49.574172)
			(xy 96.440937 -49.492905) (xy 96.472416 -49.414275) (xy 96.511227 -49.338994) (xy 96.557017 -49.267742)
			(xy 96.609373 -49.201166) (xy 96.667821 -49.139868) (xy 96.731831 -49.084403) (xy 96.800823 -49.035274)
			(xy 96.874173 -48.992925) (xy 96.951216 -48.957741) (xy 97.031255 -48.930039) (xy 97.113564 -48.910071)
			(xy 97.197399 -48.898018) (xy 97.282 -48.893988) (xy 97.366601 -48.898018) (xy 97.450436 -48.910071)
			(xy 97.532745 -48.930039) (xy 97.612784 -48.957741) (xy 97.689827 -48.992925) (xy 97.763177 -49.035274)
			(xy 97.832169 -49.084403) (xy 97.896179 -49.139868) (xy 97.954627 -49.201166) (xy 98.006983 -49.267742)
			(xy 98.052773 -49.338994) (xy 98.091584 -49.414275) (xy 98.123063 -49.492905) (xy 98.146924 -49.574172)
			(xy 98.162953 -49.657338) (xy 98.171004 -49.741652) (xy 98.171508 -49.784) (xy 98.171062 -49.822288)
			(xy 98.164444 -49.898578) (xy 98.1513 -49.974018) (xy 98.131726 -50.04805) (xy 98.119184 -50.084228)
			(xy 98.116543 -50.092666) (xy 98.116543 -50.110334) (xy 98.119184 -50.118772) (xy 98.13174 -50.154947)
			(xy 98.151337 -50.228976) (xy 98.164488 -50.304417) (xy 98.171097 -50.380711) (xy 98.171508 -50.419)
			(xy 98.171087 -50.459054) (xy 98.163876 -50.538835) (xy 98.149521 -50.617646) (xy 98.128138 -50.694847)
			(xy 98.099902 -50.769812) (xy 98.065039 -50.841936) (xy 98.023833 -50.910632) (xy 97.976618 -50.975346)
			(xy 97.950528 -51.00574) (xy 97.944843 -51.01286) (xy 97.938459 -51.029911) (xy 97.938082 -51.039014)
			(xy 97.938082 -51.068986) (xy 97.938466 -51.078088) (xy 97.944846 -51.095139) (xy 97.950528 -51.10226)
			(xy 97.976614 -51.132657) (xy 98.023832 -51.197368) (xy 98.065039 -51.266064) (xy 98.099901 -51.338187)
			(xy 98.128135 -51.413153) (xy 98.149514 -51.490354) (xy 98.163864 -51.569165) (xy 98.171068 -51.648947)
			(xy 98.171508 -51.689) (xy 98.171062 -51.727288) (xy 98.164444 -51.803578) (xy 98.1513 -51.879018)
			(xy 98.131726 -51.95305) (xy 98.119184 -51.989228) (xy 98.116543 -51.997666) (xy 98.116543 -52.015334)
			(xy 98.119184 -52.023772) (xy 98.13174 -52.059947) (xy 98.151337 -52.133976) (xy 98.164488 -52.209417)
			(xy 98.171097 -52.285711) (xy 98.171508 -52.324) (xy 101.853492 -52.324) (xy 101.853938 -52.285712)
			(xy 101.860556 -52.209422) (xy 101.8737 -52.133982) (xy 101.893274 -52.05995) (xy 101.905816 -52.023772)
			(xy 101.908457 -52.015334) (xy 101.908457 -51.997666) (xy 101.905816 -51.989228) (xy 101.89326 -51.953053)
			(xy 101.873663 -51.879024) (xy 101.860512 -51.803583) (xy 101.853903 -51.727289) (xy 101.853492 -51.689)
			(xy 101.853913 -51.648946) (xy 101.861124 -51.569165) (xy 101.875479 -51.490354) (xy 101.896862 -51.413153)
			(xy 101.925098 -51.338188) (xy 101.959961 -51.266064) (xy 102.001167 -51.197368) (xy 102.048382 -51.132654)
			(xy 102.074472 -51.10226) (xy 102.080157 -51.09514) (xy 102.086541 -51.078089) (xy 102.086918 -51.068986)
			(xy 102.086918 -51.039014) (xy 102.086534 -51.029912) (xy 102.080154 -51.012861) (xy 102.074472 -51.00574)
			(xy 102.048386 -50.975343) (xy 102.001168 -50.910632) (xy 101.959961 -50.841936) (xy 101.925099 -50.769813)
			(xy 101.896865 -50.694847) (xy 101.875486 -50.617646) (xy 101.861136 -50.538835) (xy 101.853932 -50.459053)
			(xy 101.853492 -50.419) (xy 101.853938 -50.380712) (xy 101.860556 -50.304422) (xy 101.8737 -50.228982)
			(xy 101.893274 -50.15495) (xy 101.905816 -50.118772) (xy 101.908457 -50.110334) (xy 101.908457 -50.092666)
			(xy 101.905816 -50.084228) (xy 101.89326 -50.048053) (xy 101.873663 -49.974024) (xy 101.860512 -49.898583)
			(xy 101.853903 -49.822289) (xy 101.853492 -49.784) (xy 101.853996 -49.741652) (xy 101.862047 -49.657338)
			(xy 101.878076 -49.574172) (xy 101.901937 -49.492905) (xy 101.933416 -49.414275) (xy 101.972227 -49.338994)
			(xy 102.018017 -49.267742) (xy 102.070373 -49.201166) (xy 102.128821 -49.139868) (xy 102.192831 -49.084403)
			(xy 102.261823 -49.035274) (xy 102.335173 -48.992925) (xy 102.412216 -48.957741) (xy 102.492255 -48.930039)
			(xy 102.574564 -48.910071) (xy 102.658399 -48.898018) (xy 102.743 -48.893988) (xy 102.827601 -48.898018)
			(xy 102.911436 -48.910071) (xy 102.993745 -48.930039) (xy 103.073784 -48.957741) (xy 103.150827 -48.992925)
			(xy 103.224177 -49.035274) (xy 103.293169 -49.084403) (xy 103.357179 -49.139868) (xy 103.415627 -49.201166)
			(xy 103.467983 -49.267742) (xy 103.513773 -49.338994) (xy 103.552584 -49.414275) (xy 103.584063 -49.492905)
			(xy 103.607924 -49.574172) (xy 103.623953 -49.657338) (xy 103.632004 -49.741652) (xy 103.632508 -49.784)
			(xy 103.632062 -49.822288) (xy 103.625444 -49.898578) (xy 103.6123 -49.974018) (xy 103.592726 -50.04805)
			(xy 103.580184 -50.084228) (xy 103.577543 -50.092666) (xy 103.577543 -50.110334) (xy 103.580184 -50.118772)
			(xy 103.59274 -50.154947) (xy 103.612337 -50.228976) (xy 103.625488 -50.304417) (xy 103.632097 -50.380711)
			(xy 103.632508 -50.419) (xy 103.632087 -50.459054) (xy 103.624876 -50.538835) (xy 103.610521 -50.617646)
			(xy 103.589138 -50.694847) (xy 103.560902 -50.769812) (xy 103.526039 -50.841936) (xy 103.484833 -50.910632)
			(xy 103.437618 -50.975346) (xy 103.411528 -51.00574) (xy 103.405843 -51.01286) (xy 103.399459 -51.029911)
			(xy 103.399082 -51.039014) (xy 103.399082 -51.068986) (xy 103.399466 -51.078088) (xy 103.405846 -51.095139)
			(xy 103.411528 -51.10226) (xy 103.437614 -51.132657) (xy 103.484832 -51.197368) (xy 103.526039 -51.266064)
			(xy 103.560901 -51.338187) (xy 103.589135 -51.413153) (xy 103.610514 -51.490354) (xy 103.624864 -51.569165)
			(xy 103.632068 -51.648947) (xy 103.632508 -51.689) (xy 103.632062 -51.727288) (xy 103.625444 -51.803578)
			(xy 103.6123 -51.879018) (xy 103.592726 -51.95305) (xy 103.580184 -51.989228) (xy 103.577543 -51.997666)
			(xy 103.577543 -52.015334) (xy 103.580184 -52.023772) (xy 103.59274 -52.059947) (xy 103.612337 -52.133976)
			(xy 103.625488 -52.209417) (xy 103.632097 -52.285711) (xy 103.632508 -52.324) (xy 107.314492 -52.324)
			(xy 107.314938 -52.285712) (xy 107.321556 -52.209422) (xy 107.3347 -52.133982) (xy 107.354274 -52.05995)
			(xy 107.366816 -52.023772) (xy 107.369457 -52.015334) (xy 107.369457 -51.997666) (xy 107.366816 -51.989228)
			(xy 107.35426 -51.953053) (xy 107.334663 -51.879024) (xy 107.321512 -51.803583) (xy 107.314903 -51.727289)
			(xy 107.314492 -51.689) (xy 107.314913 -51.648946) (xy 107.322124 -51.569165) (xy 107.336479 -51.490354)
			(xy 107.357862 -51.413153) (xy 107.386098 -51.338188) (xy 107.420961 -51.266064) (xy 107.462167 -51.197368)
			(xy 107.509382 -51.132654) (xy 107.535472 -51.10226) (xy 107.541157 -51.09514) (xy 107.547541 -51.078089)
			(xy 107.547918 -51.068986) (xy 107.547918 -51.039014) (xy 107.547534 -51.029912) (xy 107.541154 -51.012861)
			(xy 107.535472 -51.00574) (xy 107.509386 -50.975343) (xy 107.462168 -50.910632) (xy 107.420961 -50.841936)
			(xy 107.386099 -50.769813) (xy 107.357865 -50.694847) (xy 107.336486 -50.617646) (xy 107.322136 -50.538835)
			(xy 107.314932 -50.459053) (xy 107.314492 -50.419) (xy 107.314938 -50.380712) (xy 107.321556 -50.304422)
			(xy 107.3347 -50.228982) (xy 107.354274 -50.15495) (xy 107.366816 -50.118772) (xy 107.369457 -50.110334)
			(xy 107.369457 -50.092666) (xy 107.366816 -50.084228) (xy 107.35426 -50.048053) (xy 107.334663 -49.974024)
			(xy 107.321512 -49.898583) (xy 107.314903 -49.822289) (xy 107.314492 -49.784) (xy 107.314996 -49.741652)
			(xy 107.323047 -49.657338) (xy 107.339076 -49.574172) (xy 107.362937 -49.492905) (xy 107.394416 -49.414275)
			(xy 107.433227 -49.338994) (xy 107.479017 -49.267742) (xy 107.531373 -49.201166) (xy 107.589821 -49.139868)
			(xy 107.653831 -49.084403) (xy 107.722823 -49.035274) (xy 107.796173 -48.992925) (xy 107.873216 -48.957741)
			(xy 107.953255 -48.930039) (xy 108.035564 -48.910071) (xy 108.119399 -48.898018) (xy 108.204 -48.893988)
			(xy 108.288601 -48.898018) (xy 108.372436 -48.910071) (xy 108.454745 -48.930039) (xy 108.534784 -48.957741)
			(xy 108.611827 -48.992925) (xy 108.685177 -49.035274) (xy 108.754169 -49.084403) (xy 108.818179 -49.139868)
			(xy 108.876627 -49.201166) (xy 108.928983 -49.267742) (xy 108.974773 -49.338994) (xy 109.013584 -49.414275)
			(xy 109.045063 -49.492905) (xy 109.068924 -49.574172) (xy 109.084953 -49.657338) (xy 109.093004 -49.741652)
			(xy 109.093508 -49.784) (xy 109.093062 -49.822288) (xy 109.086444 -49.898578) (xy 109.0733 -49.974018)
			(xy 109.053726 -50.04805) (xy 109.041184 -50.084228) (xy 109.038543 -50.092666) (xy 109.038543 -50.110334)
			(xy 109.041184 -50.118772) (xy 109.05374 -50.154947) (xy 109.073337 -50.228976) (xy 109.086488 -50.304417)
			(xy 109.093097 -50.380711) (xy 109.093508 -50.419) (xy 109.093087 -50.459054) (xy 109.085876 -50.538835)
			(xy 109.071521 -50.617646) (xy 109.050138 -50.694847) (xy 109.021902 -50.769812) (xy 108.987039 -50.841936)
			(xy 108.945833 -50.910632) (xy 108.898618 -50.975346) (xy 108.872528 -51.00574) (xy 108.866843 -51.01286)
			(xy 108.860459 -51.029911) (xy 108.860082 -51.039014) (xy 108.860082 -51.068986) (xy 108.860466 -51.078088)
			(xy 108.866846 -51.095139) (xy 108.872528 -51.10226) (xy 108.898614 -51.132657) (xy 108.945832 -51.197368)
			(xy 108.987039 -51.266064) (xy 109.021901 -51.338187) (xy 109.050135 -51.413153) (xy 109.071514 -51.490354)
			(xy 109.085864 -51.569165) (xy 109.093068 -51.648947) (xy 109.093508 -51.689) (xy 109.093062 -51.727288)
			(xy 109.086444 -51.803578) (xy 109.0733 -51.879018) (xy 109.053726 -51.95305) (xy 109.041184 -51.989228)
			(xy 109.038543 -51.997666) (xy 109.038543 -52.015334) (xy 109.041184 -52.023772) (xy 109.05374 -52.059947)
			(xy 109.073337 -52.133976) (xy 109.084323 -52.197) (xy 152.653492 -52.197) (xy 152.653938 -52.158712)
			(xy 152.660556 -52.082422) (xy 152.6737 -52.006982) (xy 152.693274 -51.93295) (xy 152.705816 -51.896772)
			(xy 152.708457 -51.888334) (xy 152.708457 -51.870666) (xy 152.705816 -51.862228) (xy 152.69326 -51.826053)
			(xy 152.673663 -51.752024) (xy 152.660512 -51.676583) (xy 152.653903 -51.600289) (xy 152.653492 -51.562)
			(xy 152.653913 -51.521946) (xy 152.661124 -51.442165) (xy 152.675479 -51.363354) (xy 152.696862 -51.286153)
			(xy 152.725098 -51.211188) (xy 152.759961 -51.139064) (xy 152.801167 -51.070368) (xy 152.848382 -51.005654)
			(xy 152.874472 -50.97526) (xy 152.880157 -50.96814) (xy 152.886541 -50.951089) (xy 152.886918 -50.941986)
			(xy 152.886918 -50.912014) (xy 152.886534 -50.902912) (xy 152.880154 -50.885861) (xy 152.874472 -50.87874)
			(xy 152.848386 -50.848343) (xy 152.801168 -50.783632) (xy 152.759961 -50.714936) (xy 152.725099 -50.642813)
			(xy 152.696865 -50.567847) (xy 152.675486 -50.490646) (xy 152.661136 -50.411835) (xy 152.653932 -50.332053)
			(xy 152.653492 -50.292) (xy 152.653938 -50.253712) (xy 152.660556 -50.177422) (xy 152.6737 -50.101982)
			(xy 152.693274 -50.02795) (xy 152.705816 -49.991772) (xy 152.708457 -49.983334) (xy 152.708457 -49.965666)
			(xy 152.705816 -49.957228) (xy 152.69326 -49.921053) (xy 152.673663 -49.847024) (xy 152.660512 -49.771583)
			(xy 152.653903 -49.695289) (xy 152.653492 -49.657) (xy 152.653996 -49.614652) (xy 152.662047 -49.530338)
			(xy 152.678076 -49.447172) (xy 152.701937 -49.365905) (xy 152.733416 -49.287275) (xy 152.772227 -49.211994)
			(xy 152.818017 -49.140742) (xy 152.870373 -49.074166) (xy 152.928821 -49.012868) (xy 152.992831 -48.957403)
			(xy 153.061823 -48.908274) (xy 153.135173 -48.865925) (xy 153.212216 -48.830741) (xy 153.292255 -48.803039)
			(xy 153.374564 -48.783071) (xy 153.458399 -48.771018) (xy 153.543 -48.766988) (xy 153.627601 -48.771018)
			(xy 153.711436 -48.783071) (xy 153.793745 -48.803039) (xy 153.873784 -48.830741) (xy 153.950827 -48.865925)
			(xy 154.024177 -48.908274) (xy 154.093169 -48.957403) (xy 154.157179 -49.012868) (xy 154.215627 -49.074166)
			(xy 154.267983 -49.140742) (xy 154.313773 -49.211994) (xy 154.352584 -49.287275) (xy 154.384063 -49.365905)
			(xy 154.407924 -49.447172) (xy 154.423953 -49.530338) (xy 154.432004 -49.614652) (xy 154.432508 -49.657)
			(xy 154.432062 -49.695288) (xy 154.425444 -49.771578) (xy 154.4123 -49.847018) (xy 154.392726 -49.92105)
			(xy 154.380184 -49.957228) (xy 154.377543 -49.965666) (xy 154.377543 -49.983334) (xy 154.380184 -49.991772)
			(xy 154.39274 -50.027947) (xy 154.412337 -50.101976) (xy 154.425488 -50.177417) (xy 154.432097 -50.253711)
			(xy 154.432508 -50.292) (xy 154.432087 -50.332054) (xy 154.424876 -50.411835) (xy 154.410521 -50.490646)
			(xy 154.389138 -50.567847) (xy 154.360902 -50.642812) (xy 154.326039 -50.714936) (xy 154.284833 -50.783632)
			(xy 154.237618 -50.848346) (xy 154.211528 -50.87874) (xy 154.205843 -50.88586) (xy 154.199459 -50.902911)
			(xy 154.199082 -50.912014) (xy 154.199082 -50.941986) (xy 154.199466 -50.951088) (xy 154.205846 -50.968139)
			(xy 154.211528 -50.97526) (xy 154.237614 -51.005657) (xy 154.284832 -51.070368) (xy 154.326039 -51.139064)
			(xy 154.360901 -51.211187) (xy 154.389135 -51.286153) (xy 154.410514 -51.363354) (xy 154.424864 -51.442165)
			(xy 154.432068 -51.521947) (xy 154.432508 -51.562) (xy 154.432062 -51.600288) (xy 154.425444 -51.676578)
			(xy 154.4123 -51.752018) (xy 154.392726 -51.82605) (xy 154.380184 -51.862228) (xy 154.377543 -51.870666)
			(xy 154.377543 -51.888334) (xy 154.380184 -51.896772) (xy 154.39274 -51.932947) (xy 154.412337 -52.006976)
			(xy 154.425488 -52.082417) (xy 154.432097 -52.158711) (xy 154.432508 -52.197) (xy 158.114492 -52.197)
			(xy 158.114938 -52.158712) (xy 158.121556 -52.082422) (xy 158.1347 -52.006982) (xy 158.154274 -51.93295)
			(xy 158.166816 -51.896772) (xy 158.169457 -51.888334) (xy 158.169457 -51.870666) (xy 158.166816 -51.862228)
			(xy 158.15426 -51.826053) (xy 158.134663 -51.752024) (xy 158.121512 -51.676583) (xy 158.114903 -51.600289)
			(xy 158.114492 -51.562) (xy 158.114913 -51.521946) (xy 158.122124 -51.442165) (xy 158.136479 -51.363354)
			(xy 158.157862 -51.286153) (xy 158.186098 -51.211188) (xy 158.220961 -51.139064) (xy 158.262167 -51.070368)
			(xy 158.309382 -51.005654) (xy 158.335472 -50.97526) (xy 158.341157 -50.96814) (xy 158.347541 -50.951089)
			(xy 158.347918 -50.941986) (xy 158.347918 -50.912014) (xy 158.347534 -50.902912) (xy 158.341154 -50.885861)
			(xy 158.335472 -50.87874) (xy 158.309386 -50.848343) (xy 158.262168 -50.783632) (xy 158.220961 -50.714936)
			(xy 158.186099 -50.642813) (xy 158.157865 -50.567847) (xy 158.136486 -50.490646) (xy 158.122136 -50.411835)
			(xy 158.114932 -50.332053) (xy 158.114492 -50.292) (xy 158.114938 -50.253712) (xy 158.121556 -50.177422)
			(xy 158.1347 -50.101982) (xy 158.154274 -50.02795) (xy 158.166816 -49.991772) (xy 158.169457 -49.983334)
			(xy 158.169457 -49.965666) (xy 158.166816 -49.957228) (xy 158.15426 -49.921053) (xy 158.134663 -49.847024)
			(xy 158.121512 -49.771583) (xy 158.114903 -49.695289) (xy 158.114492 -49.657) (xy 158.114996 -49.614652)
			(xy 158.123047 -49.530338) (xy 158.139076 -49.447172) (xy 158.162937 -49.365905) (xy 158.194416 -49.287275)
			(xy 158.233227 -49.211994) (xy 158.279017 -49.140742) (xy 158.331373 -49.074166) (xy 158.389821 -49.012868)
			(xy 158.453831 -48.957403) (xy 158.522823 -48.908274) (xy 158.596173 -48.865925) (xy 158.673216 -48.830741)
			(xy 158.753255 -48.803039) (xy 158.835564 -48.783071) (xy 158.919399 -48.771018) (xy 159.004 -48.766988)
			(xy 159.088601 -48.771018) (xy 159.172436 -48.783071) (xy 159.254745 -48.803039) (xy 159.334784 -48.830741)
			(xy 159.411827 -48.865925) (xy 159.485177 -48.908274) (xy 159.554169 -48.957403) (xy 159.618179 -49.012868)
			(xy 159.676627 -49.074166) (xy 159.728983 -49.140742) (xy 159.774773 -49.211994) (xy 159.813584 -49.287275)
			(xy 159.845063 -49.365905) (xy 159.868924 -49.447172) (xy 159.884953 -49.530338) (xy 159.893004 -49.614652)
			(xy 159.893508 -49.657) (xy 159.893062 -49.695288) (xy 159.886444 -49.771578) (xy 159.8733 -49.847018)
			(xy 159.853726 -49.92105) (xy 159.841184 -49.957228) (xy 159.838543 -49.965666) (xy 159.838543 -49.983334)
			(xy 159.841184 -49.991772) (xy 159.85374 -50.027947) (xy 159.873337 -50.101976) (xy 159.886488 -50.177417)
			(xy 159.893097 -50.253711) (xy 159.893508 -50.292) (xy 159.893087 -50.332054) (xy 159.885876 -50.411835)
			(xy 159.871521 -50.490646) (xy 159.850138 -50.567847) (xy 159.821902 -50.642812) (xy 159.787039 -50.714936)
			(xy 159.745833 -50.783632) (xy 159.698618 -50.848346) (xy 159.672528 -50.87874) (xy 159.666843 -50.88586)
			(xy 159.660459 -50.902911) (xy 159.660082 -50.912014) (xy 159.660082 -50.941986) (xy 159.660466 -50.951088)
			(xy 159.666846 -50.968139) (xy 159.672528 -50.97526) (xy 159.698614 -51.005657) (xy 159.745832 -51.070368)
			(xy 159.787039 -51.139064) (xy 159.821901 -51.211187) (xy 159.850135 -51.286153) (xy 159.871514 -51.363354)
			(xy 159.885864 -51.442165) (xy 159.893068 -51.521947) (xy 159.893508 -51.562) (xy 159.893062 -51.600288)
			(xy 159.886444 -51.676578) (xy 159.8733 -51.752018) (xy 159.853726 -51.82605) (xy 159.841184 -51.862228)
			(xy 159.838543 -51.870666) (xy 159.838543 -51.888334) (xy 159.841184 -51.896772) (xy 159.85374 -51.932947)
			(xy 159.873337 -52.006976) (xy 159.886488 -52.082417) (xy 159.893097 -52.158711) (xy 159.893508 -52.197)
			(xy 163.575492 -52.197) (xy 163.575938 -52.158712) (xy 163.582556 -52.082422) (xy 163.5957 -52.006982)
			(xy 163.615274 -51.93295) (xy 163.627816 -51.896772) (xy 163.630457 -51.888334) (xy 163.630457 -51.870666)
			(xy 163.627816 -51.862228) (xy 163.61526 -51.826053) (xy 163.595663 -51.752024) (xy 163.582512 -51.676583)
			(xy 163.575903 -51.600289) (xy 163.575492 -51.562) (xy 163.575913 -51.521946) (xy 163.583124 -51.442165)
			(xy 163.597479 -51.363354) (xy 163.618862 -51.286153) (xy 163.647098 -51.211188) (xy 163.681961 -51.139064)
			(xy 163.723167 -51.070368) (xy 163.770382 -51.005654) (xy 163.796472 -50.97526) (xy 163.802157 -50.96814)
			(xy 163.808541 -50.951089) (xy 163.808918 -50.941986) (xy 163.808918 -50.912014) (xy 163.808534 -50.902912)
			(xy 163.802154 -50.885861) (xy 163.796472 -50.87874) (xy 163.770386 -50.848343) (xy 163.723168 -50.783632)
			(xy 163.681961 -50.714936) (xy 163.647099 -50.642813) (xy 163.618865 -50.567847) (xy 163.597486 -50.490646)
			(xy 163.583136 -50.411835) (xy 163.575932 -50.332053) (xy 163.575492 -50.292) (xy 163.575938 -50.253712)
			(xy 163.582556 -50.177422) (xy 163.5957 -50.101982) (xy 163.615274 -50.02795) (xy 163.627816 -49.991772)
			(xy 163.630457 -49.983334) (xy 163.630457 -49.965666) (xy 163.627816 -49.957228) (xy 163.61526 -49.921053)
			(xy 163.595663 -49.847024) (xy 163.582512 -49.771583) (xy 163.575903 -49.695289) (xy 163.575492 -49.657)
			(xy 163.575996 -49.614652) (xy 163.584047 -49.530338) (xy 163.600076 -49.447172) (xy 163.623937 -49.365905)
			(xy 163.655416 -49.287275) (xy 163.694227 -49.211994) (xy 163.740017 -49.140742) (xy 163.792373 -49.074166)
			(xy 163.850821 -49.012868) (xy 163.914831 -48.957403) (xy 163.983823 -48.908274) (xy 164.057173 -48.865925)
			(xy 164.134216 -48.830741) (xy 164.214255 -48.803039) (xy 164.296564 -48.783071) (xy 164.380399 -48.771018)
			(xy 164.465 -48.766988) (xy 164.549601 -48.771018) (xy 164.633436 -48.783071) (xy 164.715745 -48.803039)
			(xy 164.795784 -48.830741) (xy 164.872827 -48.865925) (xy 164.946177 -48.908274) (xy 165.015169 -48.957403)
			(xy 165.079179 -49.012868) (xy 165.137627 -49.074166) (xy 165.189983 -49.140742) (xy 165.235773 -49.211994)
			(xy 165.274584 -49.287275) (xy 165.306063 -49.365905) (xy 165.329924 -49.447172) (xy 165.345953 -49.530338)
			(xy 165.354004 -49.614652) (xy 165.354508 -49.657) (xy 165.354062 -49.695288) (xy 165.347444 -49.771578)
			(xy 165.3343 -49.847018) (xy 165.314726 -49.92105) (xy 165.302184 -49.957228) (xy 165.299543 -49.965666)
			(xy 165.299543 -49.983334) (xy 165.302184 -49.991772) (xy 165.31474 -50.027947) (xy 165.334337 -50.101976)
			(xy 165.347488 -50.177417) (xy 165.354097 -50.253711) (xy 165.354508 -50.292) (xy 165.354087 -50.332054)
			(xy 165.346876 -50.411835) (xy 165.332521 -50.490646) (xy 165.311138 -50.567847) (xy 165.282902 -50.642812)
			(xy 165.248039 -50.714936) (xy 165.206833 -50.783632) (xy 165.159618 -50.848346) (xy 165.133528 -50.87874)
			(xy 165.127843 -50.88586) (xy 165.121459 -50.902911) (xy 165.121082 -50.912014) (xy 165.121082 -50.941986)
			(xy 165.121466 -50.951088) (xy 165.127846 -50.968139) (xy 165.133528 -50.97526) (xy 165.159614 -51.005657)
			(xy 165.206832 -51.070368) (xy 165.248039 -51.139064) (xy 165.282901 -51.211187) (xy 165.311135 -51.286153)
			(xy 165.332514 -51.363354) (xy 165.346864 -51.442165) (xy 165.354068 -51.521947) (xy 165.354508 -51.562)
			(xy 165.354062 -51.600288) (xy 165.347444 -51.676578) (xy 165.3343 -51.752018) (xy 165.314726 -51.82605)
			(xy 165.302184 -51.862228) (xy 165.299543 -51.870666) (xy 165.299543 -51.888334) (xy 165.302184 -51.896772)
			(xy 165.31474 -51.932947) (xy 165.334337 -52.006976) (xy 165.347488 -52.082417) (xy 165.354097 -52.158711)
			(xy 165.354508 -52.197) (xy 169.036492 -52.197) (xy 169.036938 -52.158712) (xy 169.043556 -52.082422)
			(xy 169.0567 -52.006982) (xy 169.076274 -51.93295) (xy 169.088816 -51.896772) (xy 169.091457 -51.888334)
			(xy 169.091457 -51.870666) (xy 169.088816 -51.862228) (xy 169.07626 -51.826053) (xy 169.056663 -51.752024)
			(xy 169.043512 -51.676583) (xy 169.036903 -51.600289) (xy 169.036492 -51.562) (xy 169.036913 -51.521946)
			(xy 169.044124 -51.442165) (xy 169.058479 -51.363354) (xy 169.079862 -51.286153) (xy 169.108098 -51.211188)
			(xy 169.142961 -51.139064) (xy 169.184167 -51.070368) (xy 169.231382 -51.005654) (xy 169.257472 -50.97526)
			(xy 169.263157 -50.96814) (xy 169.269541 -50.951089) (xy 169.269918 -50.941986) (xy 169.269918 -50.912014)
			(xy 169.269534 -50.902912) (xy 169.263154 -50.885861) (xy 169.257472 -50.87874) (xy 169.231386 -50.848343)
			(xy 169.184168 -50.783632) (xy 169.142961 -50.714936) (xy 169.108099 -50.642813) (xy 169.079865 -50.567847)
			(xy 169.058486 -50.490646) (xy 169.044136 -50.411835) (xy 169.036932 -50.332053) (xy 169.036492 -50.292)
			(xy 169.036938 -50.253712) (xy 169.043556 -50.177422) (xy 169.0567 -50.101982) (xy 169.076274 -50.02795)
			(xy 169.088816 -49.991772) (xy 169.091457 -49.983334) (xy 169.091457 -49.965666) (xy 169.088816 -49.957228)
			(xy 169.07626 -49.921053) (xy 169.056663 -49.847024) (xy 169.043512 -49.771583) (xy 169.036903 -49.695289)
			(xy 169.036492 -49.657) (xy 169.036996 -49.614652) (xy 169.045047 -49.530338) (xy 169.061076 -49.447172)
			(xy 169.084937 -49.365905) (xy 169.116416 -49.287275) (xy 169.155227 -49.211994) (xy 169.201017 -49.140742)
			(xy 169.253373 -49.074166) (xy 169.311821 -49.012868) (xy 169.375831 -48.957403) (xy 169.444823 -48.908274)
			(xy 169.518173 -48.865925) (xy 169.595216 -48.830741) (xy 169.675255 -48.803039) (xy 169.757564 -48.783071)
			(xy 169.841399 -48.771018) (xy 169.926 -48.766988) (xy 170.010601 -48.771018) (xy 170.094436 -48.783071)
			(xy 170.176745 -48.803039) (xy 170.256784 -48.830741) (xy 170.333827 -48.865925) (xy 170.407177 -48.908274)
			(xy 170.476169 -48.957403) (xy 170.540179 -49.012868) (xy 170.598627 -49.074166) (xy 170.650983 -49.140742)
			(xy 170.696773 -49.211994) (xy 170.735584 -49.287275) (xy 170.767063 -49.365905) (xy 170.790924 -49.447172)
			(xy 170.806953 -49.530338) (xy 170.815004 -49.614652) (xy 170.815508 -49.657) (xy 170.815062 -49.695288)
			(xy 170.808444 -49.771578) (xy 170.7953 -49.847018) (xy 170.775726 -49.92105) (xy 170.763184 -49.957228)
			(xy 170.760543 -49.965666) (xy 170.760543 -49.983334) (xy 170.763184 -49.991772) (xy 170.77574 -50.027947)
			(xy 170.795337 -50.101976) (xy 170.808488 -50.177417) (xy 170.815097 -50.253711) (xy 170.815508 -50.292)
			(xy 170.815087 -50.332054) (xy 170.807876 -50.411835) (xy 170.793521 -50.490646) (xy 170.772138 -50.567847)
			(xy 170.743902 -50.642812) (xy 170.709039 -50.714936) (xy 170.667833 -50.783632) (xy 170.620618 -50.848346)
			(xy 170.594528 -50.87874) (xy 170.588843 -50.88586) (xy 170.582459 -50.902911) (xy 170.582082 -50.912014)
			(xy 170.582082 -50.941986) (xy 170.582466 -50.951088) (xy 170.588846 -50.968139) (xy 170.594528 -50.97526)
			(xy 170.620614 -51.005657) (xy 170.667832 -51.070368) (xy 170.709039 -51.139064) (xy 170.743901 -51.211187)
			(xy 170.772135 -51.286153) (xy 170.793514 -51.363354) (xy 170.807864 -51.442165) (xy 170.815068 -51.521947)
			(xy 170.815508 -51.562) (xy 170.815062 -51.600288) (xy 170.808444 -51.676578) (xy 170.7953 -51.752018)
			(xy 170.775726 -51.82605) (xy 170.763184 -51.862228) (xy 170.760543 -51.870666) (xy 170.760543 -51.888334)
			(xy 170.763184 -51.896772) (xy 170.77574 -51.932947) (xy 170.795337 -52.006976) (xy 170.808488 -52.082417)
			(xy 170.815097 -52.158711) (xy 170.815508 -52.197) (xy 174.497492 -52.197) (xy 174.497938 -52.158712)
			(xy 174.504556 -52.082422) (xy 174.5177 -52.006982) (xy 174.537274 -51.93295) (xy 174.549816 -51.896772)
			(xy 174.552457 -51.888334) (xy 174.552457 -51.870666) (xy 174.549816 -51.862228) (xy 174.53726 -51.826053)
			(xy 174.517663 -51.752024) (xy 174.504512 -51.676583) (xy 174.497903 -51.600289) (xy 174.497492 -51.562)
			(xy 174.497913 -51.521946) (xy 174.505124 -51.442165) (xy 174.519479 -51.363354) (xy 174.540862 -51.286153)
			(xy 174.569098 -51.211188) (xy 174.603961 -51.139064) (xy 174.645167 -51.070368) (xy 174.692382 -51.005654)
			(xy 174.718472 -50.97526) (xy 174.724157 -50.96814) (xy 174.730541 -50.951089) (xy 174.730918 -50.941986)
			(xy 174.730918 -50.912014) (xy 174.730534 -50.902912) (xy 174.724154 -50.885861) (xy 174.718472 -50.87874)
			(xy 174.692386 -50.848343) (xy 174.645168 -50.783632) (xy 174.603961 -50.714936) (xy 174.569099 -50.642813)
			(xy 174.540865 -50.567847) (xy 174.519486 -50.490646) (xy 174.505136 -50.411835) (xy 174.497932 -50.332053)
			(xy 174.497492 -50.292) (xy 174.497938 -50.253712) (xy 174.504556 -50.177422) (xy 174.5177 -50.101982)
			(xy 174.537274 -50.02795) (xy 174.549816 -49.991772) (xy 174.552457 -49.983334) (xy 174.552457 -49.965666)
			(xy 174.549816 -49.957228) (xy 174.53726 -49.921053) (xy 174.517663 -49.847024) (xy 174.504512 -49.771583)
			(xy 174.497903 -49.695289) (xy 174.497492 -49.657) (xy 174.497996 -49.614652) (xy 174.506047 -49.530338)
			(xy 174.522076 -49.447172) (xy 174.545937 -49.365905) (xy 174.577416 -49.287275) (xy 174.616227 -49.211994)
			(xy 174.662017 -49.140742) (xy 174.714373 -49.074166) (xy 174.772821 -49.012868) (xy 174.836831 -48.957403)
			(xy 174.905823 -48.908274) (xy 174.979173 -48.865925) (xy 175.056216 -48.830741) (xy 175.136255 -48.803039)
			(xy 175.218564 -48.783071) (xy 175.302399 -48.771018) (xy 175.387 -48.766988) (xy 175.471601 -48.771018)
			(xy 175.555436 -48.783071) (xy 175.637745 -48.803039) (xy 175.717784 -48.830741) (xy 175.794827 -48.865925)
			(xy 175.868177 -48.908274) (xy 175.937169 -48.957403) (xy 176.001179 -49.012868) (xy 176.059627 -49.074166)
			(xy 176.111983 -49.140742) (xy 176.157773 -49.211994) (xy 176.196584 -49.287275) (xy 176.228063 -49.365905)
			(xy 176.251924 -49.447172) (xy 176.267953 -49.530338) (xy 176.276004 -49.614652) (xy 176.276508 -49.657)
			(xy 176.276062 -49.695288) (xy 176.269444 -49.771578) (xy 176.2563 -49.847018) (xy 176.236726 -49.92105)
			(xy 176.224184 -49.957228) (xy 176.221543 -49.965666) (xy 176.221543 -49.983334) (xy 176.224184 -49.991772)
			(xy 176.23674 -50.027947) (xy 176.256337 -50.101976) (xy 176.269488 -50.177417) (xy 176.276097 -50.253711)
			(xy 176.276508 -50.292) (xy 176.276087 -50.332054) (xy 176.268876 -50.411835) (xy 176.254521 -50.490646)
			(xy 176.233138 -50.567847) (xy 176.204902 -50.642812) (xy 176.170039 -50.714936) (xy 176.128833 -50.783632)
			(xy 176.081618 -50.848346) (xy 176.055528 -50.87874) (xy 176.049843 -50.88586) (xy 176.043459 -50.902911)
			(xy 176.043082 -50.912014) (xy 176.043082 -50.941986) (xy 176.043466 -50.951088) (xy 176.049846 -50.968139)
			(xy 176.055528 -50.97526) (xy 176.081614 -51.005657) (xy 176.128832 -51.070368) (xy 176.170039 -51.139064)
			(xy 176.204901 -51.211187) (xy 176.233135 -51.286153) (xy 176.254514 -51.363354) (xy 176.268864 -51.442165)
			(xy 176.276068 -51.521947) (xy 176.276508 -51.562) (xy 176.276062 -51.600288) (xy 176.269444 -51.676578)
			(xy 176.2563 -51.752018) (xy 176.236726 -51.82605) (xy 176.224184 -51.862228) (xy 176.221543 -51.870666)
			(xy 176.221543 -51.888334) (xy 176.224184 -51.896772) (xy 176.23674 -51.932947) (xy 176.256337 -52.006976)
			(xy 176.269488 -52.082417) (xy 176.276097 -52.158711) (xy 176.276508 -52.197) (xy 179.955952 -52.197)
			(xy 179.956401 -52.158712) (xy 179.963018 -52.082422) (xy 179.976162 -52.006983) (xy 179.995734 -51.93295)
			(xy 180.008276 -51.896772) (xy 180.010919 -51.888334) (xy 180.010919 -51.870666) (xy 180.008276 -51.862228)
			(xy 179.995718 -51.826054) (xy 179.976122 -51.752024) (xy 179.962971 -51.676583) (xy 179.956363 -51.600289)
			(xy 179.955952 -51.562) (xy 179.956383 -51.521947) (xy 179.963594 -51.442165) (xy 179.977948 -51.363355)
			(xy 179.999329 -51.286155) (xy 180.027565 -51.21119) (xy 180.062426 -51.139066) (xy 180.10363 -51.070369)
			(xy 180.150843 -51.005654) (xy 180.176932 -50.97526) (xy 180.182612 -50.968136) (xy 180.189 -50.951089)
			(xy 180.189378 -50.941986) (xy 180.189378 -50.912014) (xy 180.188981 -50.902914) (xy 180.182609 -50.885863)
			(xy 180.176932 -50.87874) (xy 180.150856 -50.848335) (xy 180.103636 -50.783625) (xy 180.062427 -50.714932)
			(xy 180.027563 -50.64281) (xy 179.999327 -50.567845) (xy 179.977947 -50.490645) (xy 179.963597 -50.411835)
			(xy 179.956392 -50.332053) (xy 179.955952 -50.292) (xy 179.956401 -50.253712) (xy 179.963018 -50.177422)
			(xy 179.976162 -50.101983) (xy 179.995734 -50.02795) (xy 180.008276 -49.991772) (xy 180.010919 -49.983334)
			(xy 180.010919 -49.965666) (xy 180.008276 -49.957228) (xy 179.995718 -49.921054) (xy 179.976122 -49.847024)
			(xy 179.962971 -49.771583) (xy 179.956363 -49.695289) (xy 179.955952 -49.657) (xy 179.956456 -49.614652)
			(xy 179.964507 -49.530338) (xy 179.980536 -49.447172) (xy 180.004397 -49.365905) (xy 180.035876 -49.287275)
			(xy 180.074687 -49.211994) (xy 180.120477 -49.140742) (xy 180.172833 -49.074166) (xy 180.231281 -49.012868)
			(xy 180.295291 -48.957403) (xy 180.364283 -48.908274) (xy 180.437633 -48.865925) (xy 180.514676 -48.830741)
			(xy 180.594715 -48.803039) (xy 180.677024 -48.783071) (xy 180.760859 -48.771018) (xy 180.84546 -48.766988)
			(xy 180.930061 -48.771018) (xy 181.013896 -48.783071) (xy 181.096205 -48.803039) (xy 181.176244 -48.830741)
			(xy 181.253287 -48.865925) (xy 181.326637 -48.908274) (xy 181.395629 -48.957403) (xy 181.459639 -49.012868)
			(xy 181.518087 -49.074166) (xy 181.570443 -49.140742) (xy 181.616233 -49.211994) (xy 181.655044 -49.287275)
			(xy 181.686523 -49.365905) (xy 181.710384 -49.447172) (xy 181.726413 -49.530338) (xy 181.734464 -49.614652)
			(xy 181.734968 -49.657) (xy 181.734524 -49.695288) (xy 181.727906 -49.771578) (xy 181.714761 -49.847018)
			(xy 181.695187 -49.92105) (xy 181.682644 -49.957228) (xy 181.680001 -49.965666) (xy 181.680001 -49.983334)
			(xy 181.682644 -49.991772) (xy 181.695203 -50.027946) (xy 181.714798 -50.101975) (xy 181.727949 -50.177417)
			(xy 181.734557 -50.25371) (xy 181.734968 -50.292) (xy 181.734532 -50.332053) (xy 181.727322 -50.411834)
			(xy 181.712968 -50.490644) (xy 181.691587 -50.567844) (xy 181.663352 -50.64281) (xy 181.628492 -50.714933)
			(xy 181.587289 -50.78363) (xy 181.540077 -50.848345) (xy 181.513988 -50.87874) (xy 181.50831 -50.885866)
			(xy 181.50192 -50.902912) (xy 181.501542 -50.912014) (xy 181.501542 -50.941986) (xy 181.501935 -50.951087)
			(xy 181.508309 -50.968138) (xy 181.513988 -50.97526) (xy 181.540068 -51.005663) (xy 181.587287 -51.070373)
			(xy 181.628495 -51.139067) (xy 181.663358 -51.211189) (xy 181.691594 -51.286154) (xy 181.712973 -51.363355)
			(xy 181.727323 -51.442165) (xy 181.734528 -51.521947) (xy 181.734968 -51.562) (xy 181.734524 -51.600288)
			(xy 181.727906 -51.676578) (xy 181.714761 -51.752018) (xy 181.695187 -51.82605) (xy 181.682644 -51.862228)
			(xy 181.680001 -51.870666) (xy 181.680001 -51.888334) (xy 181.682644 -51.896772) (xy 181.695203 -51.932946)
			(xy 181.714798 -52.006975) (xy 181.727949 -52.082417) (xy 181.734557 -52.15871) (xy 181.734968 -52.197)
			(xy 185.416952 -52.197) (xy 185.417401 -52.158712) (xy 185.424018 -52.082422) (xy 185.437162 -52.006983)
			(xy 185.456734 -51.93295) (xy 185.469276 -51.896772) (xy 185.471919 -51.888334) (xy 185.471919 -51.870666)
			(xy 185.469276 -51.862228) (xy 185.456718 -51.826054) (xy 185.437122 -51.752024) (xy 185.423971 -51.676583)
			(xy 185.417363 -51.600289) (xy 185.416952 -51.562) (xy 185.417383 -51.521947) (xy 185.424594 -51.442165)
			(xy 185.438948 -51.363355) (xy 185.460329 -51.286155) (xy 185.488565 -51.21119) (xy 185.523426 -51.139066)
			(xy 185.56463 -51.070369) (xy 185.611843 -51.005654) (xy 185.637932 -50.97526) (xy 185.643612 -50.968136)
			(xy 185.65 -50.951089) (xy 185.650378 -50.941986) (xy 185.650378 -50.912014) (xy 185.649981 -50.902914)
			(xy 185.643609 -50.885863) (xy 185.637932 -50.87874) (xy 185.611856 -50.848335) (xy 185.564636 -50.783625)
			(xy 185.523427 -50.714932) (xy 185.488563 -50.64281) (xy 185.460327 -50.567845) (xy 185.438947 -50.490645)
			(xy 185.424597 -50.411835) (xy 185.417392 -50.332053) (xy 185.416952 -50.292) (xy 185.417401 -50.253712)
			(xy 185.424018 -50.177422) (xy 185.437162 -50.101983) (xy 185.456734 -50.02795) (xy 185.469276 -49.991772)
			(xy 185.471919 -49.983334) (xy 185.471919 -49.965666) (xy 185.469276 -49.957228) (xy 185.456718 -49.921054)
			(xy 185.437122 -49.847024) (xy 185.423971 -49.771583) (xy 185.417363 -49.695289) (xy 185.416952 -49.657)
			(xy 185.417456 -49.614652) (xy 185.425507 -49.530338) (xy 185.441536 -49.447172) (xy 185.465397 -49.365905)
			(xy 185.496876 -49.287275) (xy 185.535687 -49.211994) (xy 185.581477 -49.140742) (xy 185.633833 -49.074166)
			(xy 185.692281 -49.012868) (xy 185.756291 -48.957403) (xy 185.825283 -48.908274) (xy 185.898633 -48.865925)
			(xy 185.975676 -48.830741) (xy 186.055715 -48.803039) (xy 186.138024 -48.783071) (xy 186.221859 -48.771018)
			(xy 186.30646 -48.766988) (xy 186.391061 -48.771018) (xy 186.474896 -48.783071) (xy 186.557205 -48.803039)
			(xy 186.637244 -48.830741) (xy 186.714287 -48.865925) (xy 186.787637 -48.908274) (xy 186.856629 -48.957403)
			(xy 186.920639 -49.012868) (xy 186.979087 -49.074166) (xy 187.031443 -49.140742) (xy 187.077233 -49.211994)
			(xy 187.116044 -49.287275) (xy 187.147523 -49.365905) (xy 187.171384 -49.447172) (xy 187.187413 -49.530338)
			(xy 187.195464 -49.614652) (xy 187.195968 -49.657) (xy 187.195524 -49.695288) (xy 187.188906 -49.771578)
			(xy 187.175761 -49.847018) (xy 187.156187 -49.92105) (xy 187.143644 -49.957228) (xy 187.141001 -49.965666)
			(xy 187.141001 -49.983334) (xy 187.143644 -49.991772) (xy 187.156203 -50.027946) (xy 187.175798 -50.101975)
			(xy 187.188949 -50.177417) (xy 187.195557 -50.25371) (xy 187.195968 -50.292) (xy 187.195532 -50.332053)
			(xy 187.188322 -50.411834) (xy 187.173968 -50.490644) (xy 187.152587 -50.567844) (xy 187.124352 -50.64281)
			(xy 187.089492 -50.714933) (xy 187.048289 -50.78363) (xy 187.001077 -50.848345) (xy 186.974988 -50.87874)
			(xy 186.96931 -50.885866) (xy 186.96292 -50.902912) (xy 186.962542 -50.912014) (xy 186.962542 -50.941986)
			(xy 186.962935 -50.951087) (xy 186.969309 -50.968138) (xy 186.974988 -50.97526) (xy 187.001068 -51.005663)
			(xy 187.048287 -51.070373) (xy 187.089495 -51.139067) (xy 187.124358 -51.211189) (xy 187.152594 -51.286154)
			(xy 187.173973 -51.363355) (xy 187.188323 -51.442165) (xy 187.195528 -51.521947) (xy 187.195968 -51.562)
			(xy 187.195524 -51.600288) (xy 187.188906 -51.676578) (xy 187.175761 -51.752018) (xy 187.156187 -51.82605)
			(xy 187.143644 -51.862228) (xy 187.141001 -51.870666) (xy 187.141001 -51.888334) (xy 187.143644 -51.896772)
			(xy 187.156203 -51.932946) (xy 187.175798 -52.006975) (xy 187.188949 -52.082417) (xy 187.195557 -52.15871)
			(xy 187.195968 -52.197) (xy 187.195464 -52.239348) (xy 187.187413 -52.323662) (xy 187.171384 -52.406828)
			(xy 187.147523 -52.488095) (xy 187.116044 -52.566725) (xy 187.077233 -52.642006) (xy 187.031443 -52.713258)
			(xy 186.979087 -52.779834) (xy 186.920639 -52.841132) (xy 186.856629 -52.896597) (xy 186.787637 -52.945726)
			(xy 186.714287 -52.988075) (xy 186.637244 -53.023259) (xy 186.557205 -53.050961) (xy 186.474896 -53.070929)
			(xy 186.391061 -53.082982) (xy 186.30646 -53.087013) (xy 186.221859 -53.082982) (xy 186.138024 -53.070929)
			(xy 186.055715 -53.050961) (xy 185.975676 -53.023259) (xy 185.898633 -52.988075) (xy 185.825283 -52.945726)
			(xy 185.756291 -52.896597) (xy 185.692281 -52.841132) (xy 185.633833 -52.779834) (xy 185.581477 -52.713258)
			(xy 185.535687 -52.642006) (xy 185.496876 -52.566725) (xy 185.465397 -52.488095) (xy 185.441536 -52.406828)
			(xy 185.425507 -52.323662) (xy 185.417456 -52.239348) (xy 185.416952 -52.197) (xy 181.734968 -52.197)
			(xy 181.734464 -52.239348) (xy 181.726413 -52.323662) (xy 181.710384 -52.406828) (xy 181.686523 -52.488095)
			(xy 181.655044 -52.566725) (xy 181.616233 -52.642006) (xy 181.570443 -52.713258) (xy 181.518087 -52.779834)
			(xy 181.459639 -52.841132) (xy 181.395629 -52.896597) (xy 181.326637 -52.945726) (xy 181.253287 -52.988075)
			(xy 181.176244 -53.023259) (xy 181.096205 -53.050961) (xy 181.013896 -53.070929) (xy 180.930061 -53.082982)
			(xy 180.84546 -53.087013) (xy 180.760859 -53.082982) (xy 180.677024 -53.070929) (xy 180.594715 -53.050961)
			(xy 180.514676 -53.023259) (xy 180.437633 -52.988075) (xy 180.364283 -52.945726) (xy 180.295291 -52.896597)
			(xy 180.231281 -52.841132) (xy 180.172833 -52.779834) (xy 180.120477 -52.713258) (xy 180.074687 -52.642006)
			(xy 180.035876 -52.566725) (xy 180.004397 -52.488095) (xy 179.980536 -52.406828) (xy 179.964507 -52.323662)
			(xy 179.956456 -52.239348) (xy 179.955952 -52.197) (xy 176.276508 -52.197) (xy 176.276004 -52.239348)
			(xy 176.267953 -52.323662) (xy 176.251924 -52.406828) (xy 176.228063 -52.488095) (xy 176.196584 -52.566725)
			(xy 176.157773 -52.642006) (xy 176.111983 -52.713258) (xy 176.059627 -52.779834) (xy 176.001179 -52.841132)
			(xy 175.937169 -52.896597) (xy 175.868177 -52.945726) (xy 175.794827 -52.988075) (xy 175.717784 -53.023259)
			(xy 175.637745 -53.050961) (xy 175.555436 -53.070929) (xy 175.471601 -53.082982) (xy 175.387 -53.087013)
			(xy 175.302399 -53.082982) (xy 175.218564 -53.070929) (xy 175.136255 -53.050961) (xy 175.056216 -53.023259)
			(xy 174.979173 -52.988075) (xy 174.905823 -52.945726) (xy 174.836831 -52.896597) (xy 174.772821 -52.841132)
			(xy 174.714373 -52.779834) (xy 174.662017 -52.713258) (xy 174.616227 -52.642006) (xy 174.577416 -52.566725)
			(xy 174.545937 -52.488095) (xy 174.522076 -52.406828) (xy 174.506047 -52.323662) (xy 174.497996 -52.239348)
			(xy 174.497492 -52.197) (xy 170.815508 -52.197) (xy 170.815004 -52.239348) (xy 170.806953 -52.323662)
			(xy 170.790924 -52.406828) (xy 170.767063 -52.488095) (xy 170.735584 -52.566725) (xy 170.696773 -52.642006)
			(xy 170.650983 -52.713258) (xy 170.598627 -52.779834) (xy 170.540179 -52.841132) (xy 170.476169 -52.896597)
			(xy 170.407177 -52.945726) (xy 170.333827 -52.988075) (xy 170.256784 -53.023259) (xy 170.176745 -53.050961)
			(xy 170.094436 -53.070929) (xy 170.010601 -53.082982) (xy 169.926 -53.087013) (xy 169.841399 -53.082982)
			(xy 169.757564 -53.070929) (xy 169.675255 -53.050961) (xy 169.595216 -53.023259) (xy 169.518173 -52.988075)
			(xy 169.444823 -52.945726) (xy 169.375831 -52.896597) (xy 169.311821 -52.841132) (xy 169.253373 -52.779834)
			(xy 169.201017 -52.713258) (xy 169.155227 -52.642006) (xy 169.116416 -52.566725) (xy 169.084937 -52.488095)
			(xy 169.061076 -52.406828) (xy 169.045047 -52.323662) (xy 169.036996 -52.239348) (xy 169.036492 -52.197)
			(xy 165.354508 -52.197) (xy 165.354004 -52.239348) (xy 165.345953 -52.323662) (xy 165.329924 -52.406828)
			(xy 165.306063 -52.488095) (xy 165.274584 -52.566725) (xy 165.235773 -52.642006) (xy 165.189983 -52.713258)
			(xy 165.137627 -52.779834) (xy 165.079179 -52.841132) (xy 165.015169 -52.896597) (xy 164.946177 -52.945726)
			(xy 164.872827 -52.988075) (xy 164.795784 -53.023259) (xy 164.715745 -53.050961) (xy 164.633436 -53.070929)
			(xy 164.549601 -53.082982) (xy 164.465 -53.087013) (xy 164.380399 -53.082982) (xy 164.296564 -53.070929)
			(xy 164.214255 -53.050961) (xy 164.134216 -53.023259) (xy 164.057173 -52.988075) (xy 163.983823 -52.945726)
			(xy 163.914831 -52.896597) (xy 163.850821 -52.841132) (xy 163.792373 -52.779834) (xy 163.740017 -52.713258)
			(xy 163.694227 -52.642006) (xy 163.655416 -52.566725) (xy 163.623937 -52.488095) (xy 163.600076 -52.406828)
			(xy 163.584047 -52.323662) (xy 163.575996 -52.239348) (xy 163.575492 -52.197) (xy 159.893508 -52.197)
			(xy 159.893004 -52.239348) (xy 159.884953 -52.323662) (xy 159.868924 -52.406828) (xy 159.845063 -52.488095)
			(xy 159.813584 -52.566725) (xy 159.774773 -52.642006) (xy 159.728983 -52.713258) (xy 159.676627 -52.779834)
			(xy 159.618179 -52.841132) (xy 159.554169 -52.896597) (xy 159.485177 -52.945726) (xy 159.411827 -52.988075)
			(xy 159.334784 -53.023259) (xy 159.254745 -53.050961) (xy 159.172436 -53.070929) (xy 159.088601 -53.082982)
			(xy 159.004 -53.087013) (xy 158.919399 -53.082982) (xy 158.835564 -53.070929) (xy 158.753255 -53.050961)
			(xy 158.673216 -53.023259) (xy 158.596173 -52.988075) (xy 158.522823 -52.945726) (xy 158.453831 -52.896597)
			(xy 158.389821 -52.841132) (xy 158.331373 -52.779834) (xy 158.279017 -52.713258) (xy 158.233227 -52.642006)
			(xy 158.194416 -52.566725) (xy 158.162937 -52.488095) (xy 158.139076 -52.406828) (xy 158.123047 -52.323662)
			(xy 158.114996 -52.239348) (xy 158.114492 -52.197) (xy 154.432508 -52.197) (xy 154.432004 -52.239348)
			(xy 154.423953 -52.323662) (xy 154.407924 -52.406828) (xy 154.384063 -52.488095) (xy 154.352584 -52.566725)
			(xy 154.313773 -52.642006) (xy 154.267983 -52.713258) (xy 154.215627 -52.779834) (xy 154.157179 -52.841132)
			(xy 154.093169 -52.896597) (xy 154.024177 -52.945726) (xy 153.950827 -52.988075) (xy 153.873784 -53.023259)
			(xy 153.793745 -53.050961) (xy 153.711436 -53.070929) (xy 153.627601 -53.082982) (xy 153.543 -53.087013)
			(xy 153.458399 -53.082982) (xy 153.374564 -53.070929) (xy 153.292255 -53.050961) (xy 153.212216 -53.023259)
			(xy 153.135173 -52.988075) (xy 153.061823 -52.945726) (xy 152.992831 -52.896597) (xy 152.928821 -52.841132)
			(xy 152.870373 -52.779834) (xy 152.818017 -52.713258) (xy 152.772227 -52.642006) (xy 152.733416 -52.566725)
			(xy 152.701937 -52.488095) (xy 152.678076 -52.406828) (xy 152.662047 -52.323662) (xy 152.653996 -52.239348)
			(xy 152.653492 -52.197) (xy 109.084323 -52.197) (xy 109.086488 -52.209417) (xy 109.093097 -52.285711)
			(xy 109.093508 -52.324) (xy 109.093004 -52.366348) (xy 109.084953 -52.450662) (xy 109.068924 -52.533828)
			(xy 109.045063 -52.615095) (xy 109.013584 -52.693725) (xy 108.974773 -52.769006) (xy 108.928983 -52.840258)
			(xy 108.876627 -52.906834) (xy 108.818179 -52.968132) (xy 108.754169 -53.023597) (xy 108.685177 -53.072726)
			(xy 108.611827 -53.115075) (xy 108.534784 -53.150259) (xy 108.454745 -53.177961) (xy 108.372436 -53.197929)
			(xy 108.288601 -53.209982) (xy 108.204 -53.214013) (xy 108.119399 -53.209982) (xy 108.035564 -53.197929)
			(xy 107.953255 -53.177961) (xy 107.873216 -53.150259) (xy 107.796173 -53.115075) (xy 107.722823 -53.072726)
			(xy 107.653831 -53.023597) (xy 107.589821 -52.968132) (xy 107.531373 -52.906834) (xy 107.479017 -52.840258)
			(xy 107.433227 -52.769006) (xy 107.394416 -52.693725) (xy 107.362937 -52.615095) (xy 107.339076 -52.533828)
			(xy 107.323047 -52.450662) (xy 107.314996 -52.366348) (xy 107.314492 -52.324) (xy 103.632508 -52.324)
			(xy 103.632004 -52.366348) (xy 103.623953 -52.450662) (xy 103.607924 -52.533828) (xy 103.584063 -52.615095)
			(xy 103.552584 -52.693725) (xy 103.513773 -52.769006) (xy 103.467983 -52.840258) (xy 103.415627 -52.906834)
			(xy 103.357179 -52.968132) (xy 103.293169 -53.023597) (xy 103.224177 -53.072726) (xy 103.150827 -53.115075)
			(xy 103.073784 -53.150259) (xy 102.993745 -53.177961) (xy 102.911436 -53.197929) (xy 102.827601 -53.209982)
			(xy 102.743 -53.214013) (xy 102.658399 -53.209982) (xy 102.574564 -53.197929) (xy 102.492255 -53.177961)
			(xy 102.412216 -53.150259) (xy 102.335173 -53.115075) (xy 102.261823 -53.072726) (xy 102.192831 -53.023597)
			(xy 102.128821 -52.968132) (xy 102.070373 -52.906834) (xy 102.018017 -52.840258) (xy 101.972227 -52.769006)
			(xy 101.933416 -52.693725) (xy 101.901937 -52.615095) (xy 101.878076 -52.533828) (xy 101.862047 -52.450662)
			(xy 101.853996 -52.366348) (xy 101.853492 -52.324) (xy 98.171508 -52.324) (xy 98.171004 -52.366348)
			(xy 98.162953 -52.450662) (xy 98.146924 -52.533828) (xy 98.123063 -52.615095) (xy 98.091584 -52.693725)
			(xy 98.052773 -52.769006) (xy 98.006983 -52.840258) (xy 97.954627 -52.906834) (xy 97.896179 -52.968132)
			(xy 97.832169 -53.023597) (xy 97.763177 -53.072726) (xy 97.689827 -53.115075) (xy 97.612784 -53.150259)
			(xy 97.532745 -53.177961) (xy 97.450436 -53.197929) (xy 97.366601 -53.209982) (xy 97.282 -53.214013)
			(xy 97.197399 -53.209982) (xy 97.113564 -53.197929) (xy 97.031255 -53.177961) (xy 96.951216 -53.150259)
			(xy 96.874173 -53.115075) (xy 96.800823 -53.072726) (xy 96.731831 -53.023597) (xy 96.667821 -52.968132)
			(xy 96.609373 -52.906834) (xy 96.557017 -52.840258) (xy 96.511227 -52.769006) (xy 96.472416 -52.693725)
			(xy 96.440937 -52.615095) (xy 96.417076 -52.533828) (xy 96.401047 -52.450662) (xy 96.392996 -52.366348)
			(xy 96.392492 -52.324) (xy 92.710508 -52.324) (xy 92.710004 -52.366348) (xy 92.701953 -52.450662)
			(xy 92.685924 -52.533828) (xy 92.662063 -52.615095) (xy 92.630584 -52.693725) (xy 92.591773 -52.769006)
			(xy 92.545983 -52.840258) (xy 92.493627 -52.906834) (xy 92.435179 -52.968132) (xy 92.371169 -53.023597)
			(xy 92.302177 -53.072726) (xy 92.228827 -53.115075) (xy 92.151784 -53.150259) (xy 92.071745 -53.177961)
			(xy 91.989436 -53.197929) (xy 91.905601 -53.209982) (xy 91.821 -53.214013) (xy 91.736399 -53.209982)
			(xy 91.652564 -53.197929) (xy 91.570255 -53.177961) (xy 91.490216 -53.150259) (xy 91.413173 -53.115075)
			(xy 91.339823 -53.072726) (xy 91.270831 -53.023597) (xy 91.206821 -52.968132) (xy 91.148373 -52.906834)
			(xy 91.096017 -52.840258) (xy 91.050227 -52.769006) (xy 91.011416 -52.693725) (xy 90.979937 -52.615095)
			(xy 90.956076 -52.533828) (xy 90.940047 -52.450662) (xy 90.931996 -52.366348) (xy 90.931492 -52.324)
			(xy 87.249508 -52.324) (xy 87.249004 -52.366348) (xy 87.240953 -52.450662) (xy 87.224924 -52.533828)
			(xy 87.201063 -52.615095) (xy 87.169584 -52.693725) (xy 87.130773 -52.769006) (xy 87.084983 -52.840258)
			(xy 87.032627 -52.906834) (xy 86.974179 -52.968132) (xy 86.910169 -53.023597) (xy 86.841177 -53.072726)
			(xy 86.767827 -53.115075) (xy 86.690784 -53.150259) (xy 86.610745 -53.177961) (xy 86.528436 -53.197929)
			(xy 86.444601 -53.209982) (xy 86.36 -53.214013) (xy 86.275399 -53.209982) (xy 86.191564 -53.197929)
			(xy 86.109255 -53.177961) (xy 86.029216 -53.150259) (xy 85.952173 -53.115075) (xy 85.878823 -53.072726)
			(xy 85.809831 -53.023597) (xy 85.745821 -52.968132) (xy 85.687373 -52.906834) (xy 85.635017 -52.840258)
			(xy 85.589227 -52.769006) (xy 85.550416 -52.693725) (xy 85.518937 -52.615095) (xy 85.495076 -52.533828)
			(xy 85.479047 -52.450662) (xy 85.470996 -52.366348) (xy 85.470492 -52.324) (xy 81.788508 -52.324)
			(xy 81.788004 -52.366348) (xy 81.779953 -52.450662) (xy 81.763924 -52.533828) (xy 81.740063 -52.615095)
			(xy 81.708584 -52.693725) (xy 81.669773 -52.769006) (xy 81.623983 -52.840258) (xy 81.571627 -52.906834)
			(xy 81.513179 -52.968132) (xy 81.449169 -53.023597) (xy 81.380177 -53.072726) (xy 81.306827 -53.115075)
			(xy 81.229784 -53.150259) (xy 81.149745 -53.177961) (xy 81.067436 -53.197929) (xy 80.983601 -53.209982)
			(xy 80.899 -53.214013) (xy 80.814399 -53.209982) (xy 80.730564 -53.197929) (xy 80.648255 -53.177961)
			(xy 80.568216 -53.150259) (xy 80.491173 -53.115075) (xy 80.417823 -53.072726) (xy 80.348831 -53.023597)
			(xy 80.284821 -52.968132) (xy 80.226373 -52.906834) (xy 80.174017 -52.840258) (xy 80.128227 -52.769006)
			(xy 80.089416 -52.693725) (xy 80.057937 -52.615095) (xy 80.034076 -52.533828) (xy 80.018047 -52.450662)
			(xy 80.009996 -52.366348) (xy 80.009492 -52.324) (xy 76.327508 -52.324) (xy 76.327004 -52.366348)
			(xy 76.318953 -52.450662) (xy 76.302924 -52.533828) (xy 76.279063 -52.615095) (xy 76.247584 -52.693725)
			(xy 76.208773 -52.769006) (xy 76.162983 -52.840258) (xy 76.110627 -52.906834) (xy 76.052179 -52.968132)
			(xy 75.988169 -53.023597) (xy 75.919177 -53.072726) (xy 75.845827 -53.115075) (xy 75.768784 -53.150259)
			(xy 75.688745 -53.177961) (xy 75.606436 -53.197929) (xy 75.522601 -53.209982) (xy 75.438 -53.214013)
			(xy 75.353399 -53.209982) (xy 75.269564 -53.197929) (xy 75.187255 -53.177961) (xy 75.107216 -53.150259)
			(xy 75.030173 -53.115075) (xy 74.956823 -53.072726) (xy 74.887831 -53.023597) (xy 74.823821 -52.968132)
			(xy 74.765373 -52.906834) (xy 74.713017 -52.840258) (xy 74.667227 -52.769006) (xy 74.628416 -52.693725)
			(xy 74.596937 -52.615095) (xy 74.573076 -52.533828) (xy 74.557047 -52.450662) (xy 74.548996 -52.366348)
			(xy 74.548492 -52.324) (xy 35.37199 -52.324) (xy 36.16452 -53.11648) (xy 39.699946 -53.11648) (xy 40.513 -53.929534)
			(xy 40.513 -59.0296) (xy 40.767 -59.2836) (xy 42.3418 -59.2836) (xy 42.8752 -58.7502) (xy 42.8752 -55.0164)
			(xy 44.7294 -53.1622) (xy 46.566328 -53.1622) (xy 46.608293 -53.150028) (xy 46.693995 -53.132975)
			(xy 46.780955 -53.124399) (xy 46.824646 -53.123846) (xy 46.868339 -53.124364) (xy 46.955303 -53.132936)
			(xy 47.041005 -53.150003) (xy 47.082964 -53.1622) (xy 47.371 -53.1622) (xy 47.7774 -53.5686) (xy 47.7774 -55.96001)
			(xy 66.673991 -55.96001) (xy 66.677995 -55.85428) (xy 66.689983 -55.749156) (xy 66.709888 -55.64524)
			(xy 66.737595 -55.543127) (xy 66.772945 -55.443401) (xy 66.815736 -55.346635) (xy 66.865722 -55.253382)
			(xy 66.922618 -55.164176) (xy 66.986098 -55.079529) (xy 67.055798 -54.999925) (xy 67.131318 -54.925821)
			(xy 67.212227 -54.85764) (xy 67.29806 -54.795774) (xy 67.388326 -54.740576) (xy 67.482508 -54.692363)
			(xy 67.580067 -54.651411) (xy 67.680444 -54.617955) (xy 67.783063 -54.592185) (xy 67.887337 -54.574251)
			(xy 67.99267 -54.564254) (xy 68.098456 -54.562251) (xy 68.204091 -54.568255) (xy 68.308969 -54.582231)
			(xy 68.41249 -54.604099) (xy 68.514061 -54.633733) (xy 68.6131 -54.670964) (xy 68.709039 -54.715578)
			(xy 68.801329 -54.767321) (xy 68.889442 -54.825895) (xy 68.972873 -54.890965) (xy 69.051143 -54.962159)
			(xy 69.123805 -55.039068) (xy 69.190443 -55.121252) (xy 69.250674 -55.208241) (xy 69.304153 -55.299535)
			(xy 69.350576 -55.394613) (xy 69.389674 -55.492929) (xy 69.421225 -55.593921) (xy 69.445048 -55.69701)
			(xy 69.461006 -55.801605) (xy 69.469008 -55.907107) (xy 69.469508 -55.96001) (xy 77.976991 -55.96001)
			(xy 77.980995 -55.85428) (xy 77.992983 -55.749156) (xy 78.012888 -55.64524) (xy 78.040595 -55.543127)
			(xy 78.075945 -55.443401) (xy 78.118736 -55.346635) (xy 78.168722 -55.253382) (xy 78.225618 -55.164176)
			(xy 78.289098 -55.079529) (xy 78.358798 -54.999925) (xy 78.434318 -54.925821) (xy 78.515227 -54.85764)
			(xy 78.60106 -54.795774) (xy 78.691326 -54.740576) (xy 78.785508 -54.692363) (xy 78.883067 -54.651411)
			(xy 78.983444 -54.617955) (xy 79.086063 -54.592185) (xy 79.190337 -54.574251) (xy 79.29567 -54.564254)
			(xy 79.401456 -54.562251) (xy 79.507091 -54.568255) (xy 79.611969 -54.582231) (xy 79.71549 -54.604099)
			(xy 79.817061 -54.633733) (xy 79.9161 -54.670964) (xy 80.012039 -54.715578) (xy 80.104329 -54.767321)
			(xy 80.192442 -54.825895) (xy 80.275873 -54.890965) (xy 80.354143 -54.962159) (xy 80.426805 -55.039068)
			(xy 80.493443 -55.121252) (xy 80.553674 -55.208241) (xy 80.607153 -55.299535) (xy 80.653576 -55.394613)
			(xy 80.692674 -55.492929) (xy 80.724225 -55.593921) (xy 80.748048 -55.69701) (xy 80.764006 -55.801605)
			(xy 80.772008 -55.907107) (xy 80.772508 -55.96001) (xy 89.279991 -55.96001) (xy 89.283995 -55.85428)
			(xy 89.295983 -55.749156) (xy 89.315888 -55.64524) (xy 89.343595 -55.543127) (xy 89.378945 -55.443401)
			(xy 89.421736 -55.346635) (xy 89.471722 -55.253382) (xy 89.528618 -55.164176) (xy 89.592098 -55.079529)
			(xy 89.661798 -54.999925) (xy 89.737318 -54.925821) (xy 89.818227 -54.85764) (xy 89.90406 -54.795774)
			(xy 89.994326 -54.740576) (xy 90.088508 -54.692363) (xy 90.186067 -54.651411) (xy 90.286444 -54.617955)
			(xy 90.389063 -54.592185) (xy 90.493337 -54.574251) (xy 90.59867 -54.564254) (xy 90.704456 -54.562251)
			(xy 90.810091 -54.568255) (xy 90.914969 -54.582231) (xy 91.01849 -54.604099) (xy 91.120061 -54.633733)
			(xy 91.2191 -54.670964) (xy 91.315039 -54.715578) (xy 91.407329 -54.767321) (xy 91.495442 -54.825895)
			(xy 91.578873 -54.890965) (xy 91.657143 -54.962159) (xy 91.729805 -55.039068) (xy 91.796443 -55.121252)
			(xy 91.856674 -55.208241) (xy 91.910153 -55.299535) (xy 91.956576 -55.394613) (xy 91.995674 -55.492929)
			(xy 92.027225 -55.593921) (xy 92.051048 -55.69701) (xy 92.067006 -55.801605) (xy 92.075008 -55.907107)
			(xy 92.075508 -55.96001) (xy 107.440991 -55.96001) (xy 107.444995 -55.85428) (xy 107.456983 -55.749156)
			(xy 107.476888 -55.64524) (xy 107.504595 -55.543127) (xy 107.539945 -55.443401) (xy 107.582736 -55.346635)
			(xy 107.632722 -55.253382) (xy 107.689618 -55.164176) (xy 107.753098 -55.079529) (xy 107.822798 -54.999925)
			(xy 107.898318 -54.925821) (xy 107.979227 -54.85764) (xy 108.06506 -54.795774) (xy 108.155326 -54.740576)
			(xy 108.249508 -54.692363) (xy 108.347067 -54.651411) (xy 108.447444 -54.617955) (xy 108.550063 -54.592185)
			(xy 108.654337 -54.574251) (xy 108.75967 -54.564254) (xy 108.865456 -54.562251) (xy 108.971091 -54.568255)
			(xy 109.075969 -54.582231) (xy 109.17949 -54.604099) (xy 109.281061 -54.633733) (xy 109.3801 -54.670964)
			(xy 109.476039 -54.715578) (xy 109.568329 -54.767321) (xy 109.656442 -54.825895) (xy 109.739873 -54.890965)
			(xy 109.818143 -54.962159) (xy 109.890805 -55.039068) (xy 109.957443 -55.121252) (xy 110.017674 -55.208241)
			(xy 110.071153 -55.299535) (xy 110.117576 -55.394613) (xy 110.156674 -55.492929) (xy 110.188225 -55.593921)
			(xy 110.212048 -55.69701) (xy 110.228006 -55.801605) (xy 110.236008 -55.907107) (xy 110.236508 -55.96001)
			(xy 118.616991 -55.96001) (xy 118.620995 -55.85428) (xy 118.632983 -55.749156) (xy 118.652888 -55.64524)
			(xy 118.680595 -55.543127) (xy 118.715945 -55.443401) (xy 118.758736 -55.346635) (xy 118.808722 -55.253382)
			(xy 118.865618 -55.164176) (xy 118.929098 -55.079529) (xy 118.998798 -54.999925) (xy 119.074318 -54.925821)
			(xy 119.155227 -54.85764) (xy 119.24106 -54.795774) (xy 119.331326 -54.740576) (xy 119.425508 -54.692363)
			(xy 119.523067 -54.651411) (xy 119.623444 -54.617955) (xy 119.726063 -54.592185) (xy 119.830337 -54.574251)
			(xy 119.93567 -54.564254) (xy 120.041456 -54.562251) (xy 120.147091 -54.568255) (xy 120.251969 -54.582231)
			(xy 120.35549 -54.604099) (xy 120.457061 -54.633733) (xy 120.5561 -54.670964) (xy 120.652039 -54.715578)
			(xy 120.744329 -54.767321) (xy 120.832442 -54.825895) (xy 120.915873 -54.890965) (xy 120.994143 -54.962159)
			(xy 121.066805 -55.039068) (xy 121.133443 -55.121252) (xy 121.193674 -55.208241) (xy 121.247153 -55.299535)
			(xy 121.293576 -55.394613) (xy 121.332674 -55.492929) (xy 121.364225 -55.593921) (xy 121.388048 -55.69701)
			(xy 121.404006 -55.801605) (xy 121.412008 -55.907107) (xy 121.412508 -55.96001) (xy 129.792991 -55.96001)
			(xy 129.796995 -55.85428) (xy 129.808983 -55.749156) (xy 129.828888 -55.64524) (xy 129.856595 -55.543127)
			(xy 129.891945 -55.443401) (xy 129.934736 -55.346635) (xy 129.984722 -55.253382) (xy 130.041618 -55.164176)
			(xy 130.105098 -55.079529) (xy 130.174798 -54.999925) (xy 130.250318 -54.925821) (xy 130.331227 -54.85764)
			(xy 130.41706 -54.795774) (xy 130.507326 -54.740576) (xy 130.601508 -54.692363) (xy 130.699067 -54.651411)
			(xy 130.799444 -54.617955) (xy 130.902063 -54.592185) (xy 131.006337 -54.574251) (xy 131.11167 -54.564254)
			(xy 131.217456 -54.562251) (xy 131.323091 -54.568255) (xy 131.427969 -54.582231) (xy 131.53149 -54.604099)
			(xy 131.633061 -54.633733) (xy 131.7321 -54.670964) (xy 131.828039 -54.715578) (xy 131.920329 -54.767321)
			(xy 132.008442 -54.825895) (xy 132.091873 -54.890965) (xy 132.170143 -54.962159) (xy 132.242805 -55.039068)
			(xy 132.309443 -55.121252) (xy 132.369674 -55.208241) (xy 132.423153 -55.299535) (xy 132.469576 -55.394613)
			(xy 132.508674 -55.492929) (xy 132.540225 -55.593921) (xy 132.564048 -55.69701) (xy 132.580006 -55.801605)
			(xy 132.588008 -55.907107) (xy 132.588508 -55.96001) (xy 145.540991 -55.96001) (xy 145.544995 -55.85428)
			(xy 145.556983 -55.749156) (xy 145.576888 -55.64524) (xy 145.604595 -55.543127) (xy 145.639945 -55.443401)
			(xy 145.682736 -55.346635) (xy 145.732722 -55.253382) (xy 145.789618 -55.164176) (xy 145.853098 -55.079529)
			(xy 145.922798 -54.999925) (xy 145.998318 -54.925821) (xy 146.079227 -54.85764) (xy 146.16506 -54.795774)
			(xy 146.255326 -54.740576) (xy 146.349508 -54.692363) (xy 146.447067 -54.651411) (xy 146.547444 -54.617955)
			(xy 146.650063 -54.592185) (xy 146.754337 -54.574251) (xy 146.85967 -54.564254) (xy 146.965456 -54.562251)
			(xy 147.071091 -54.568255) (xy 147.175969 -54.582231) (xy 147.27949 -54.604099) (xy 147.381061 -54.633733)
			(xy 147.4801 -54.670964) (xy 147.576039 -54.715578) (xy 147.668329 -54.767321) (xy 147.756442 -54.825895)
			(xy 147.839873 -54.890965) (xy 147.918143 -54.962159) (xy 147.990805 -55.039068) (xy 148.057443 -55.121252)
			(xy 148.117674 -55.208241) (xy 148.171153 -55.299535) (xy 148.217576 -55.394613) (xy 148.256674 -55.492929)
			(xy 148.288225 -55.593921) (xy 148.312048 -55.69701) (xy 148.328006 -55.801605) (xy 148.336008 -55.907107)
			(xy 148.336508 -55.96001) (xy 156.716991 -55.96001) (xy 156.720995 -55.85428) (xy 156.732983 -55.749156)
			(xy 156.752888 -55.64524) (xy 156.780595 -55.543127) (xy 156.815945 -55.443401) (xy 156.858736 -55.346635)
			(xy 156.908722 -55.253382) (xy 156.965618 -55.164176) (xy 157.029098 -55.079529) (xy 157.098798 -54.999925)
			(xy 157.174318 -54.925821) (xy 157.255227 -54.85764) (xy 157.34106 -54.795774) (xy 157.431326 -54.740576)
			(xy 157.525508 -54.692363) (xy 157.623067 -54.651411) (xy 157.723444 -54.617955) (xy 157.826063 -54.592185)
			(xy 157.930337 -54.574251) (xy 158.03567 -54.564254) (xy 158.141456 -54.562251) (xy 158.247091 -54.568255)
			(xy 158.351969 -54.582231) (xy 158.45549 -54.604099) (xy 158.557061 -54.633733) (xy 158.6561 -54.670964)
			(xy 158.752039 -54.715578) (xy 158.844329 -54.767321) (xy 158.932442 -54.825895) (xy 159.015873 -54.890965)
			(xy 159.094143 -54.962159) (xy 159.166805 -55.039068) (xy 159.233443 -55.121252) (xy 159.293674 -55.208241)
			(xy 159.347153 -55.299535) (xy 159.393576 -55.394613) (xy 159.432674 -55.492929) (xy 159.464225 -55.593921)
			(xy 159.488048 -55.69701) (xy 159.504006 -55.801605) (xy 159.512008 -55.907107) (xy 159.512508 -55.96001)
			(xy 167.892991 -55.96001) (xy 167.896995 -55.85428) (xy 167.908983 -55.749156) (xy 167.928888 -55.64524)
			(xy 167.956595 -55.543127) (xy 167.991945 -55.443401) (xy 168.034736 -55.346635) (xy 168.084722 -55.253382)
			(xy 168.141618 -55.164176) (xy 168.205098 -55.079529) (xy 168.274798 -54.999925) (xy 168.350318 -54.925821)
			(xy 168.431227 -54.85764) (xy 168.51706 -54.795774) (xy 168.607326 -54.740576) (xy 168.701508 -54.692363)
			(xy 168.799067 -54.651411) (xy 168.899444 -54.617955) (xy 169.002063 -54.592185) (xy 169.106337 -54.574251)
			(xy 169.21167 -54.564254) (xy 169.317456 -54.562251) (xy 169.423091 -54.568255) (xy 169.527969 -54.582231)
			(xy 169.63149 -54.604099) (xy 169.733061 -54.633733) (xy 169.8321 -54.670964) (xy 169.928039 -54.715578)
			(xy 170.020329 -54.767321) (xy 170.108442 -54.825895) (xy 170.191873 -54.890965) (xy 170.270143 -54.962159)
			(xy 170.342805 -55.039068) (xy 170.409443 -55.121252) (xy 170.469674 -55.208241) (xy 170.523153 -55.299535)
			(xy 170.569576 -55.394613) (xy 170.608674 -55.492929) (xy 170.640225 -55.593921) (xy 170.664048 -55.69701)
			(xy 170.680006 -55.801605) (xy 170.688008 -55.907107) (xy 170.688508 -55.96001) (xy 185.541165 -55.96001)
			(xy 185.545169 -55.85428) (xy 185.557157 -55.749156) (xy 185.577062 -55.64524) (xy 185.604769 -55.543127)
			(xy 185.640119 -55.443401) (xy 185.68291 -55.346635) (xy 185.732896 -55.253382) (xy 185.789792 -55.164176)
			(xy 185.853272 -55.079529) (xy 185.922972 -54.999925) (xy 185.998492 -54.925821) (xy 186.079401 -54.85764)
			(xy 186.165234 -54.795774) (xy 186.2555 -54.740576) (xy 186.349682 -54.692363) (xy 186.447241 -54.651411)
			(xy 186.547618 -54.617955) (xy 186.650237 -54.592185) (xy 186.754511 -54.574251) (xy 186.859844 -54.564254)
			(xy 186.96563 -54.562251) (xy 187.071265 -54.568255) (xy 187.176143 -54.582231) (xy 187.279664 -54.604099)
			(xy 187.381235 -54.633733) (xy 187.480274 -54.670964) (xy 187.576213 -54.715578) (xy 187.668503 -54.767321)
			(xy 187.756616 -54.825895) (xy 187.840047 -54.890965) (xy 187.918317 -54.962159) (xy 187.990979 -55.039068)
			(xy 188.057617 -55.121252) (xy 188.117848 -55.208241) (xy 188.171327 -55.299535) (xy 188.21775 -55.394613)
			(xy 188.256848 -55.492929) (xy 188.288399 -55.593921) (xy 188.312222 -55.69701) (xy 188.32818 -55.801605)
			(xy 188.336182 -55.907107) (xy 188.336682 -55.96001) (xy 196.717165 -55.96001) (xy 196.721169 -55.85428)
			(xy 196.733157 -55.749156) (xy 196.753062 -55.64524) (xy 196.780769 -55.543127) (xy 196.816119 -55.443401)
			(xy 196.85891 -55.346635) (xy 196.908896 -55.253382) (xy 196.965792 -55.164176) (xy 197.029272 -55.079529)
			(xy 197.098972 -54.999925) (xy 197.174492 -54.925821) (xy 197.255401 -54.85764) (xy 197.341234 -54.795774)
			(xy 197.4315 -54.740576) (xy 197.525682 -54.692363) (xy 197.623241 -54.651411) (xy 197.723618 -54.617955)
			(xy 197.826237 -54.592185) (xy 197.930511 -54.574251) (xy 198.035844 -54.564254) (xy 198.14163 -54.562251)
			(xy 198.247265 -54.568255) (xy 198.352143 -54.582231) (xy 198.455664 -54.604099) (xy 198.557235 -54.633733)
			(xy 198.656274 -54.670964) (xy 198.752213 -54.715578) (xy 198.844503 -54.767321) (xy 198.932616 -54.825895)
			(xy 199.016047 -54.890965) (xy 199.094317 -54.962159) (xy 199.166979 -55.039068) (xy 199.233617 -55.121252)
			(xy 199.293848 -55.208241) (xy 199.347327 -55.299535) (xy 199.39375 -55.394613) (xy 199.432848 -55.492929)
			(xy 199.464399 -55.593921) (xy 199.488222 -55.69701) (xy 199.50418 -55.801605) (xy 199.512182 -55.907107)
			(xy 199.512682 -55.96001) (xy 207.893165 -55.96001) (xy 207.897169 -55.85428) (xy 207.909157 -55.749156)
			(xy 207.929062 -55.64524) (xy 207.956769 -55.543127) (xy 207.992119 -55.443401) (xy 208.03491 -55.346635)
			(xy 208.084896 -55.253382) (xy 208.141792 -55.164176) (xy 208.205272 -55.079529) (xy 208.274972 -54.999925)
			(xy 208.350492 -54.925821) (xy 208.431401 -54.85764) (xy 208.517234 -54.795774) (xy 208.6075 -54.740576)
			(xy 208.701682 -54.692363) (xy 208.799241 -54.651411) (xy 208.899618 -54.617955) (xy 209.002237 -54.592185)
			(xy 209.106511 -54.574251) (xy 209.211844 -54.564254) (xy 209.31763 -54.562251) (xy 209.423265 -54.568255)
			(xy 209.528143 -54.582231) (xy 209.631664 -54.604099) (xy 209.733235 -54.633733) (xy 209.832274 -54.670964)
			(xy 209.928213 -54.715578) (xy 210.020503 -54.767321) (xy 210.108616 -54.825895) (xy 210.192047 -54.890965)
			(xy 210.270317 -54.962159) (xy 210.342979 -55.039068) (xy 210.409617 -55.121252) (xy 210.469848 -55.208241)
			(xy 210.523327 -55.299535) (xy 210.56975 -55.394613) (xy 210.608848 -55.492929) (xy 210.640399 -55.593921)
			(xy 210.664222 -55.69701) (xy 210.68018 -55.801605) (xy 210.688182 -55.907107) (xy 210.688682 -55.96001)
			(xy 210.688182 -56.012913) (xy 210.68018 -56.118415) (xy 210.664222 -56.22301) (xy 210.640399 -56.326099)
			(xy 210.608848 -56.427091) (xy 210.56975 -56.525407) (xy 210.523327 -56.620485) (xy 210.469848 -56.711779)
			(xy 210.409617 -56.798768) (xy 210.342979 -56.880952) (xy 210.270317 -56.957861) (xy 210.192047 -57.029055)
			(xy 210.108616 -57.094125) (xy 210.020503 -57.152699) (xy 209.928213 -57.204442) (xy 209.832274 -57.249056)
			(xy 209.733235 -57.286287) (xy 209.631664 -57.315921) (xy 209.528143 -57.337789) (xy 209.423265 -57.351765)
			(xy 209.31763 -57.357769) (xy 209.211844 -57.355766) (xy 209.106511 -57.345769) (xy 209.002237 -57.327835)
			(xy 208.899618 -57.302065) (xy 208.799241 -57.268609) (xy 208.701682 -57.227657) (xy 208.6075 -57.179444)
			(xy 208.517234 -57.124246) (xy 208.431401 -57.06238) (xy 208.350492 -56.994199) (xy 208.274972 -56.920095)
			(xy 208.205272 -56.840491) (xy 208.141792 -56.755844) (xy 208.084896 -56.666638) (xy 208.03491 -56.573385)
			(xy 207.992119 -56.476619) (xy 207.956769 -56.376893) (xy 207.929062 -56.27478) (xy 207.909157 -56.170864)
			(xy 207.897169 -56.06574) (xy 207.893165 -55.96001) (xy 199.512682 -55.96001) (xy 199.512182 -56.012913)
			(xy 199.50418 -56.118415) (xy 199.488222 -56.22301) (xy 199.464399 -56.326099) (xy 199.432848 -56.427091)
			(xy 199.39375 -56.525407) (xy 199.347327 -56.620485) (xy 199.293848 -56.711779) (xy 199.233617 -56.798768)
			(xy 199.166979 -56.880952) (xy 199.094317 -56.957861) (xy 199.016047 -57.029055) (xy 198.932616 -57.094125)
			(xy 198.844503 -57.152699) (xy 198.752213 -57.204442) (xy 198.656274 -57.249056) (xy 198.557235 -57.286287)
			(xy 198.455664 -57.315921) (xy 198.352143 -57.337789) (xy 198.247265 -57.351765) (xy 198.14163 -57.357769)
			(xy 198.035844 -57.355766) (xy 197.930511 -57.345769) (xy 197.826237 -57.327835) (xy 197.723618 -57.302065)
			(xy 197.623241 -57.268609) (xy 197.525682 -57.227657) (xy 197.4315 -57.179444) (xy 197.341234 -57.124246)
			(xy 197.255401 -57.06238) (xy 197.174492 -56.994199) (xy 197.098972 -56.920095) (xy 197.029272 -56.840491)
			(xy 196.965792 -56.755844) (xy 196.908896 -56.666638) (xy 196.85891 -56.573385) (xy 196.816119 -56.476619)
			(xy 196.780769 -56.376893) (xy 196.753062 -56.27478) (xy 196.733157 -56.170864) (xy 196.721169 -56.06574)
			(xy 196.717165 -55.96001) (xy 188.336682 -55.96001) (xy 188.336182 -56.012913) (xy 188.32818 -56.118415)
			(xy 188.312222 -56.22301) (xy 188.288399 -56.326099) (xy 188.256848 -56.427091) (xy 188.21775 -56.525407)
			(xy 188.171327 -56.620485) (xy 188.117848 -56.711779) (xy 188.057617 -56.798768) (xy 187.990979 -56.880952)
			(xy 187.918317 -56.957861) (xy 187.840047 -57.029055) (xy 187.756616 -57.094125) (xy 187.668503 -57.152699)
			(xy 187.576213 -57.204442) (xy 187.480274 -57.249056) (xy 187.381235 -57.286287) (xy 187.279664 -57.315921)
			(xy 187.176143 -57.337789) (xy 187.071265 -57.351765) (xy 186.96563 -57.357769) (xy 186.859844 -57.355766)
			(xy 186.754511 -57.345769) (xy 186.650237 -57.327835) (xy 186.547618 -57.302065) (xy 186.447241 -57.268609)
			(xy 186.349682 -57.227657) (xy 186.2555 -57.179444) (xy 186.165234 -57.124246) (xy 186.079401 -57.06238)
			(xy 185.998492 -56.994199) (xy 185.922972 -56.920095) (xy 185.853272 -56.840491) (xy 185.789792 -56.755844)
			(xy 185.732896 -56.666638) (xy 185.68291 -56.573385) (xy 185.640119 -56.476619) (xy 185.604769 -56.376893)
			(xy 185.577062 -56.27478) (xy 185.557157 -56.170864) (xy 185.545169 -56.06574) (xy 185.541165 -55.96001)
			(xy 170.688508 -55.96001) (xy 170.688008 -56.012913) (xy 170.680006 -56.118415) (xy 170.664048 -56.22301)
			(xy 170.640225 -56.326099) (xy 170.608674 -56.427091) (xy 170.569576 -56.525407) (xy 170.523153 -56.620485)
			(xy 170.469674 -56.711779) (xy 170.409443 -56.798768) (xy 170.342805 -56.880952) (xy 170.270143 -56.957861)
			(xy 170.191873 -57.029055) (xy 170.108442 -57.094125) (xy 170.020329 -57.152699) (xy 169.928039 -57.204442)
			(xy 169.8321 -57.249056) (xy 169.733061 -57.286287) (xy 169.63149 -57.315921) (xy 169.527969 -57.337789)
			(xy 169.423091 -57.351765) (xy 169.317456 -57.357769) (xy 169.21167 -57.355766) (xy 169.106337 -57.345769)
			(xy 169.002063 -57.327835) (xy 168.899444 -57.302065) (xy 168.799067 -57.268609) (xy 168.701508 -57.227657)
			(xy 168.607326 -57.179444) (xy 168.51706 -57.124246) (xy 168.431227 -57.06238) (xy 168.350318 -56.994199)
			(xy 168.274798 -56.920095) (xy 168.205098 -56.840491) (xy 168.141618 -56.755844) (xy 168.084722 -56.666638)
			(xy 168.034736 -56.573385) (xy 167.991945 -56.476619) (xy 167.956595 -56.376893) (xy 167.928888 -56.27478)
			(xy 167.908983 -56.170864) (xy 167.896995 -56.06574) (xy 167.892991 -55.96001) (xy 159.512508 -55.96001)
			(xy 159.512008 -56.012913) (xy 159.504006 -56.118415) (xy 159.488048 -56.22301) (xy 159.464225 -56.326099)
			(xy 159.432674 -56.427091) (xy 159.393576 -56.525407) (xy 159.347153 -56.620485) (xy 159.293674 -56.711779)
			(xy 159.233443 -56.798768) (xy 159.166805 -56.880952) (xy 159.094143 -56.957861) (xy 159.015873 -57.029055)
			(xy 158.932442 -57.094125) (xy 158.844329 -57.152699) (xy 158.752039 -57.204442) (xy 158.6561 -57.249056)
			(xy 158.557061 -57.286287) (xy 158.45549 -57.315921) (xy 158.351969 -57.337789) (xy 158.247091 -57.351765)
			(xy 158.141456 -57.357769) (xy 158.03567 -57.355766) (xy 157.930337 -57.345769) (xy 157.826063 -57.327835)
			(xy 157.723444 -57.302065) (xy 157.623067 -57.268609) (xy 157.525508 -57.227657) (xy 157.431326 -57.179444)
			(xy 157.34106 -57.124246) (xy 157.255227 -57.06238) (xy 157.174318 -56.994199) (xy 157.098798 -56.920095)
			(xy 157.029098 -56.840491) (xy 156.965618 -56.755844) (xy 156.908722 -56.666638) (xy 156.858736 -56.573385)
			(xy 156.815945 -56.476619) (xy 156.780595 -56.376893) (xy 156.752888 -56.27478) (xy 156.732983 -56.170864)
			(xy 156.720995 -56.06574) (xy 156.716991 -55.96001) (xy 148.336508 -55.96001) (xy 148.336008 -56.012913)
			(xy 148.328006 -56.118415) (xy 148.312048 -56.22301) (xy 148.288225 -56.326099) (xy 148.256674 -56.427091)
			(xy 148.217576 -56.525407) (xy 148.171153 -56.620485) (xy 148.117674 -56.711779) (xy 148.057443 -56.798768)
			(xy 147.990805 -56.880952) (xy 147.918143 -56.957861) (xy 147.839873 -57.029055) (xy 147.756442 -57.094125)
			(xy 147.668329 -57.152699) (xy 147.576039 -57.204442) (xy 147.4801 -57.249056) (xy 147.381061 -57.286287)
			(xy 147.27949 -57.315921) (xy 147.175969 -57.337789) (xy 147.071091 -57.351765) (xy 146.965456 -57.357769)
			(xy 146.85967 -57.355766) (xy 146.754337 -57.345769) (xy 146.650063 -57.327835) (xy 146.547444 -57.302065)
			(xy 146.447067 -57.268609) (xy 146.349508 -57.227657) (xy 146.255326 -57.179444) (xy 146.16506 -57.124246)
			(xy 146.079227 -57.06238) (xy 145.998318 -56.994199) (xy 145.922798 -56.920095) (xy 145.853098 -56.840491)
			(xy 145.789618 -56.755844) (xy 145.732722 -56.666638) (xy 145.682736 -56.573385) (xy 145.639945 -56.476619)
			(xy 145.604595 -56.376893) (xy 145.576888 -56.27478) (xy 145.556983 -56.170864) (xy 145.544995 -56.06574)
			(xy 145.540991 -55.96001) (xy 132.588508 -55.96001) (xy 132.588008 -56.012913) (xy 132.580006 -56.118415)
			(xy 132.564048 -56.22301) (xy 132.540225 -56.326099) (xy 132.508674 -56.427091) (xy 132.469576 -56.525407)
			(xy 132.423153 -56.620485) (xy 132.369674 -56.711779) (xy 132.309443 -56.798768) (xy 132.242805 -56.880952)
			(xy 132.170143 -56.957861) (xy 132.091873 -57.029055) (xy 132.008442 -57.094125) (xy 131.920329 -57.152699)
			(xy 131.828039 -57.204442) (xy 131.7321 -57.249056) (xy 131.633061 -57.286287) (xy 131.53149 -57.315921)
			(xy 131.427969 -57.337789) (xy 131.323091 -57.351765) (xy 131.217456 -57.357769) (xy 131.11167 -57.355766)
			(xy 131.006337 -57.345769) (xy 130.902063 -57.327835) (xy 130.799444 -57.302065) (xy 130.699067 -57.268609)
			(xy 130.601508 -57.227657) (xy 130.507326 -57.179444) (xy 130.41706 -57.124246) (xy 130.331227 -57.06238)
			(xy 130.250318 -56.994199) (xy 130.174798 -56.920095) (xy 130.105098 -56.840491) (xy 130.041618 -56.755844)
			(xy 129.984722 -56.666638) (xy 129.934736 -56.573385) (xy 129.891945 -56.476619) (xy 129.856595 -56.376893)
			(xy 129.828888 -56.27478) (xy 129.808983 -56.170864) (xy 129.796995 -56.06574) (xy 129.792991 -55.96001)
			(xy 121.412508 -55.96001) (xy 121.412008 -56.012913) (xy 121.404006 -56.118415) (xy 121.388048 -56.22301)
			(xy 121.364225 -56.326099) (xy 121.332674 -56.427091) (xy 121.293576 -56.525407) (xy 121.247153 -56.620485)
			(xy 121.193674 -56.711779) (xy 121.133443 -56.798768) (xy 121.066805 -56.880952) (xy 120.994143 -56.957861)
			(xy 120.915873 -57.029055) (xy 120.832442 -57.094125) (xy 120.744329 -57.152699) (xy 120.652039 -57.204442)
			(xy 120.5561 -57.249056) (xy 120.457061 -57.286287) (xy 120.35549 -57.315921) (xy 120.251969 -57.337789)
			(xy 120.147091 -57.351765) (xy 120.041456 -57.357769) (xy 119.93567 -57.355766) (xy 119.830337 -57.345769)
			(xy 119.726063 -57.327835) (xy 119.623444 -57.302065) (xy 119.523067 -57.268609) (xy 119.425508 -57.227657)
			(xy 119.331326 -57.179444) (xy 119.24106 -57.124246) (xy 119.155227 -57.06238) (xy 119.074318 -56.994199)
			(xy 118.998798 -56.920095) (xy 118.929098 -56.840491) (xy 118.865618 -56.755844) (xy 118.808722 -56.666638)
			(xy 118.758736 -56.573385) (xy 118.715945 -56.476619) (xy 118.680595 -56.376893) (xy 118.652888 -56.27478)
			(xy 118.632983 -56.170864) (xy 118.620995 -56.06574) (xy 118.616991 -55.96001) (xy 110.236508 -55.96001)
			(xy 110.236008 -56.012913) (xy 110.228006 -56.118415) (xy 110.212048 -56.22301) (xy 110.188225 -56.326099)
			(xy 110.156674 -56.427091) (xy 110.117576 -56.525407) (xy 110.071153 -56.620485) (xy 110.017674 -56.711779)
			(xy 109.957443 -56.798768) (xy 109.890805 -56.880952) (xy 109.818143 -56.957861) (xy 109.739873 -57.029055)
			(xy 109.656442 -57.094125) (xy 109.568329 -57.152699) (xy 109.476039 -57.204442) (xy 109.3801 -57.249056)
			(xy 109.281061 -57.286287) (xy 109.17949 -57.315921) (xy 109.075969 -57.337789) (xy 108.971091 -57.351765)
			(xy 108.865456 -57.357769) (xy 108.75967 -57.355766) (xy 108.654337 -57.345769) (xy 108.550063 -57.327835)
			(xy 108.447444 -57.302065) (xy 108.347067 -57.268609) (xy 108.249508 -57.227657) (xy 108.155326 -57.179444)
			(xy 108.06506 -57.124246) (xy 107.979227 -57.06238) (xy 107.898318 -56.994199) (xy 107.822798 -56.920095)
			(xy 107.753098 -56.840491) (xy 107.689618 -56.755844) (xy 107.632722 -56.666638) (xy 107.582736 -56.573385)
			(xy 107.539945 -56.476619) (xy 107.504595 -56.376893) (xy 107.476888 -56.27478) (xy 107.456983 -56.170864)
			(xy 107.444995 -56.06574) (xy 107.440991 -55.96001) (xy 92.075508 -55.96001) (xy 92.075008 -56.012913)
			(xy 92.067006 -56.118415) (xy 92.051048 -56.22301) (xy 92.027225 -56.326099) (xy 91.995674 -56.427091)
			(xy 91.956576 -56.525407) (xy 91.910153 -56.620485) (xy 91.856674 -56.711779) (xy 91.796443 -56.798768)
			(xy 91.729805 -56.880952) (xy 91.657143 -56.957861) (xy 91.578873 -57.029055) (xy 91.495442 -57.094125)
			(xy 91.407329 -57.152699) (xy 91.315039 -57.204442) (xy 91.2191 -57.249056) (xy 91.120061 -57.286287)
			(xy 91.01849 -57.315921) (xy 90.914969 -57.337789) (xy 90.810091 -57.351765) (xy 90.704456 -57.357769)
			(xy 90.59867 -57.355766) (xy 90.493337 -57.345769) (xy 90.389063 -57.327835) (xy 90.286444 -57.302065)
			(xy 90.186067 -57.268609) (xy 90.088508 -57.227657) (xy 89.994326 -57.179444) (xy 89.90406 -57.124246)
			(xy 89.818227 -57.06238) (xy 89.737318 -56.994199) (xy 89.661798 -56.920095) (xy 89.592098 -56.840491)
			(xy 89.528618 -56.755844) (xy 89.471722 -56.666638) (xy 89.421736 -56.573385) (xy 89.378945 -56.476619)
			(xy 89.343595 -56.376893) (xy 89.315888 -56.27478) (xy 89.295983 -56.170864) (xy 89.283995 -56.06574)
			(xy 89.279991 -55.96001) (xy 80.772508 -55.96001) (xy 80.772008 -56.012913) (xy 80.764006 -56.118415)
			(xy 80.748048 -56.22301) (xy 80.724225 -56.326099) (xy 80.692674 -56.427091) (xy 80.653576 -56.525407)
			(xy 80.607153 -56.620485) (xy 80.553674 -56.711779) (xy 80.493443 -56.798768) (xy 80.426805 -56.880952)
			(xy 80.354143 -56.957861) (xy 80.275873 -57.029055) (xy 80.192442 -57.094125) (xy 80.104329 -57.152699)
			(xy 80.012039 -57.204442) (xy 79.9161 -57.249056) (xy 79.817061 -57.286287) (xy 79.71549 -57.315921)
			(xy 79.611969 -57.337789) (xy 79.507091 -57.351765) (xy 79.401456 -57.357769) (xy 79.29567 -57.355766)
			(xy 79.190337 -57.345769) (xy 79.086063 -57.327835) (xy 78.983444 -57.302065) (xy 78.883067 -57.268609)
			(xy 78.785508 -57.227657) (xy 78.691326 -57.179444) (xy 78.60106 -57.124246) (xy 78.515227 -57.06238)
			(xy 78.434318 -56.994199) (xy 78.358798 -56.920095) (xy 78.289098 -56.840491) (xy 78.225618 -56.755844)
			(xy 78.168722 -56.666638) (xy 78.118736 -56.573385) (xy 78.075945 -56.476619) (xy 78.040595 -56.376893)
			(xy 78.012888 -56.27478) (xy 77.992983 -56.170864) (xy 77.980995 -56.06574) (xy 77.976991 -55.96001)
			(xy 69.469508 -55.96001) (xy 69.469008 -56.012913) (xy 69.461006 -56.118415) (xy 69.445048 -56.22301)
			(xy 69.421225 -56.326099) (xy 69.389674 -56.427091) (xy 69.350576 -56.525407) (xy 69.304153 -56.620485)
			(xy 69.250674 -56.711779) (xy 69.190443 -56.798768) (xy 69.123805 -56.880952) (xy 69.051143 -56.957861)
			(xy 68.972873 -57.029055) (xy 68.889442 -57.094125) (xy 68.801329 -57.152699) (xy 68.709039 -57.204442)
			(xy 68.6131 -57.249056) (xy 68.514061 -57.286287) (xy 68.41249 -57.315921) (xy 68.308969 -57.337789)
			(xy 68.204091 -57.351765) (xy 68.098456 -57.357769) (xy 67.99267 -57.355766) (xy 67.887337 -57.345769)
			(xy 67.783063 -57.327835) (xy 67.680444 -57.302065) (xy 67.580067 -57.268609) (xy 67.482508 -57.227657)
			(xy 67.388326 -57.179444) (xy 67.29806 -57.124246) (xy 67.212227 -57.06238) (xy 67.131318 -56.994199)
			(xy 67.055798 -56.920095) (xy 66.986098 -56.840491) (xy 66.922618 -56.755844) (xy 66.865722 -56.666638)
			(xy 66.815736 -56.573385) (xy 66.772945 -56.476619) (xy 66.737595 -56.376893) (xy 66.709888 -56.27478)
			(xy 66.689983 -56.170864) (xy 66.677995 -56.06574) (xy 66.673991 -55.96001) (xy 47.7774 -55.96001)
			(xy 47.7774 -58.2168) (xy 44.5516 -61.4426) (xy 44.5516 -62.2554) (xy 47.309532 -62.2554) (xy 47.309532 -62.254892)
			(xy 47.310135 -62.20856) (xy 47.319807 -62.116402) (xy 47.339003 -62.025748) (xy 47.367516 -61.937579)
			(xy 47.385732 -61.894974) (xy 47.389552 -61.885034) (xy 47.389552 -61.863766) (xy 47.385732 -61.853826)
			(xy 47.367506 -61.811225) (xy 47.33899 -61.723056) (xy 47.319799 -61.632401) (xy 47.31014 -61.54024)
			(xy 47.309532 -61.493908) (xy 47.309532 -61.4934) (xy 47.309952 -61.452296) (xy 47.317538 -61.370438)
			(xy 47.332644 -61.289629) (xy 47.355142 -61.210559) (xy 47.38484 -61.133902) (xy 47.421485 -61.060312)
			(xy 47.464763 -60.990417) (xy 47.514306 -60.924814) (xy 47.569691 -60.864063) (xy 47.630445 -60.80868)
			(xy 47.69605 -60.75914) (xy 47.765947 -60.715865) (xy 47.839538 -60.679224) (xy 47.916197 -60.649529)
			(xy 47.995268 -60.627035) (xy 48.076077 -60.611932) (xy 48.157936 -60.60435) (xy 48.19904 -60.603892)
			(xy 48.199548 -60.603892) (xy 48.245879 -60.604519) (xy 48.338037 -60.614184) (xy 48.428691 -60.633374)
			(xy 48.51686 -60.66188) (xy 48.559466 -60.680092) (xy 48.569406 -60.683912) (xy 48.590674 -60.683912)
			(xy 48.600614 -60.680092) (xy 48.643271 -60.661834) (xy 48.731565 -60.633293) (xy 48.822352 -60.614104)
			(xy 48.914643 -60.604475) (xy 48.96104 -60.603892) (xy 49.007435 -60.604496) (xy 49.099723 -60.614135)
			(xy 49.190507 -60.633325) (xy 49.278801 -60.661857) (xy 49.321466 -60.680092) (xy 49.331406 -60.683912)
			(xy 49.352674 -60.683912) (xy 49.362614 -60.680092) (xy 49.405271 -60.661834) (xy 49.493565 -60.633293)
			(xy 49.584352 -60.614104) (xy 49.676643 -60.604475) (xy 49.72304 -60.603892) (xy 49.769435 -60.604496)
			(xy 49.861723 -60.614135) (xy 49.952507 -60.633325) (xy 50.040801 -60.661857) (xy 50.083466 -60.680092)
			(xy 50.093406 -60.683912) (xy 50.114674 -60.683912) (xy 50.124614 -60.680092) (xy 50.167271 -60.661834)
			(xy 50.255565 -60.633293) (xy 50.346352 -60.614104) (xy 50.438643 -60.604475) (xy 50.48504 -60.603892)
			(xy 50.531435 -60.604496) (xy 50.623723 -60.614135) (xy 50.714507 -60.633325) (xy 50.802801 -60.661857)
			(xy 50.845466 -60.680092) (xy 50.855406 -60.683912) (xy 50.876674 -60.683912) (xy 50.886614 -60.680092)
			(xy 50.929211 -60.661857) (xy 51.017381 -60.633343) (xy 51.108038 -60.614154) (xy 51.200199 -60.604498)
			(xy 51.246532 -60.603892) (xy 51.24704 -60.603892) (xy 51.288143 -60.604328) (xy 51.369998 -60.611917)
			(xy 51.450804 -60.627026) (xy 51.529872 -60.649525) (xy 51.606526 -60.679224) (xy 51.680113 -60.715869)
			(xy 51.750005 -60.759147) (xy 51.815606 -60.808689) (xy 51.876355 -60.864073) (xy 51.931736 -60.924825)
			(xy 51.981275 -60.990428) (xy 52.02455 -61.060322) (xy 52.061192 -61.133911) (xy 52.090887 -61.210566)
			(xy 52.113384 -61.289634) (xy 52.128489 -61.370441) (xy 52.136073 -61.452297) (xy 52.136548 -61.4934)
			(xy 52.136548 -61.493908) (xy 52.135939 -61.54024) (xy 52.126268 -61.632397) (xy 52.107073 -61.723052)
			(xy 52.078562 -61.81122) (xy 52.060348 -61.853826) (xy 52.05653 -61.863766) (xy 52.05653 -61.885034)
			(xy 52.060348 -61.894974) (xy 52.078573 -61.937576) (xy 52.107089 -62.025744) (xy 52.126281 -62.1164)
			(xy 52.13594 -62.20856) (xy 52.136548 -62.254892) (xy 52.136548 -62.2554) (xy 52.136033 -62.296501)
			(xy 52.128449 -62.378353) (xy 52.113345 -62.459156) (xy 52.090849 -62.538221) (xy 52.061155 -62.614873)
			(xy 52.024515 -62.688458) (xy 51.981242 -62.758349) (xy 51.931705 -62.823949) (xy 51.894284 -62.865)
			(xy 60.705492 -62.865) (xy 60.70599 -62.823495) (xy 60.713726 -62.740846) (xy 60.72913 -62.659277)
			(xy 60.752069 -62.579499) (xy 60.782343 -62.502206) (xy 60.819688 -62.428071) (xy 60.863779 -62.357738)
			(xy 60.888626 -62.324488) (xy 60.894965 -62.315288) (xy 60.899791 -62.2935) (xy 60.894965 -62.271712)
			(xy 60.888626 -62.262512) (xy 60.863779 -62.229262) (xy 60.819683 -62.158931) (xy 60.782333 -62.084796)
			(xy 60.752056 -62.007504) (xy 60.729115 -61.927725) (xy 60.713708 -61.846156) (xy 60.705972 -61.763506)
			(xy 60.705492 -61.722) (xy 60.705958 -61.680844) (xy 60.713545 -61.598883) (xy 60.728673 -61.517973)
			(xy 60.751212 -61.438808) (xy 60.780969 -61.362063) (xy 60.81769 -61.288397) (xy 60.86106 -61.218438)
			(xy 60.910709 -61.152786) (xy 60.966211 -61.092002) (xy 61.027093 -61.036607) (xy 61.092832 -60.987074)
			(xy 61.162867 -60.943827) (xy 61.236598 -60.907236) (xy 61.313395 -60.877614) (xy 61.392601 -60.855215)
			(xy 61.473537 -60.84023) (xy 61.514482 -60.836048) (xy 61.52515 -60.835286) (xy 61.543438 -60.825126)
			(xy 61.602112 -60.749688) (xy 61.607192 -60.729368) (xy 61.605668 -60.718954) (xy 61.600446 -60.684201)
			(xy 61.594853 -60.614141) (xy 61.594492 -60.579) (xy 61.595075 -60.532604) (xy 61.60472 -60.440316)
			(xy 61.623916 -60.349532) (xy 61.652454 -60.261239) (xy 61.670692 -60.218574) (xy 61.674597 -60.208652)
			(xy 61.674597 -60.187348) (xy 61.670692 -60.177426) (xy 61.652447 -60.134764) (xy 61.623903 -60.046471)
			(xy 61.60471 -59.955686) (xy 61.595077 -59.863396) (xy 61.594492 -59.817) (xy 61.594996 -59.774652)
			(xy 61.603047 -59.690338) (xy 61.619076 -59.607172) (xy 61.642937 -59.525905) (xy 61.674416 -59.447275)
			(xy 61.713227 -59.371994) (xy 61.759017 -59.300742) (xy 61.811373 -59.234166) (xy 61.869821 -59.172868)
			(xy 61.933831 -59.117403) (xy 62.002823 -59.068274) (xy 62.076173 -59.025925) (xy 62.153216 -58.990741)
			(xy 62.233255 -58.963039) (xy 62.315564 -58.943071) (xy 62.399399 -58.931018) (xy 62.484 -58.926988)
			(xy 62.568601 -58.931018) (xy 62.652436 -58.943071) (xy 62.734745 -58.963039) (xy 62.814784 -58.990741)
			(xy 62.891827 -59.025925) (xy 62.965177 -59.068274) (xy 63.034169 -59.117403) (xy 63.098179 -59.172868)
			(xy 63.156627 -59.234166) (xy 63.208983 -59.300742) (xy 63.254773 -59.371994) (xy 63.293584 -59.447275)
			(xy 63.325063 -59.525905) (xy 63.348924 -59.607172) (xy 63.364953 -59.690338) (xy 63.373004 -59.774652)
			(xy 63.373508 -59.817) (xy 63.372925 -59.863396) (xy 63.36328 -59.955684) (xy 63.344084 -60.046468)
			(xy 63.315546 -60.134761) (xy 63.297308 -60.177426) (xy 63.293403 -60.187348) (xy 63.293403 -60.208652)
			(xy 63.297308 -60.218574) (xy 63.315553 -60.261236) (xy 63.344097 -60.349529) (xy 63.36329 -60.440314)
			(xy 63.372923 -60.532604) (xy 63.373508 -60.579) (xy 63.373042 -60.620156) (xy 63.365455 -60.702117)
			(xy 63.350327 -60.783027) (xy 63.327788 -60.862192) (xy 63.298031 -60.938937) (xy 63.266422 -61.002348)
			(xy 67.182996 -61.002348) (xy 67.182996 -60.917652) (xy 67.191047 -60.833338) (xy 67.207076 -60.750172)
			(xy 67.230937 -60.668905) (xy 67.262416 -60.590275) (xy 67.301227 -60.514994) (xy 67.347017 -60.443742)
			(xy 67.399373 -60.377166) (xy 67.457821 -60.315868) (xy 67.521831 -60.260403) (xy 67.590823 -60.211274)
			(xy 67.664173 -60.168925) (xy 67.741216 -60.133741) (xy 67.821255 -60.106039) (xy 67.903564 -60.086071)
			(xy 67.987399 -60.074018) (xy 68.072 -60.069988) (xy 68.156601 -60.074018) (xy 68.240436 -60.086071)
			(xy 68.322745 -60.106039) (xy 68.402784 -60.133741) (xy 68.479827 -60.168925) (xy 68.553177 -60.211274)
			(xy 68.622169 -60.260403) (xy 68.686179 -60.315868) (xy 68.744627 -60.377166) (xy 68.796983 -60.443742)
			(xy 68.842773 -60.514994) (xy 68.881584 -60.590275) (xy 68.913063 -60.668905) (xy 68.936924 -60.750172)
			(xy 68.952953 -60.833338) (xy 68.961004 -60.917652) (xy 68.961508 -60.96) (xy 68.961004 -61.002348)
			(xy 78.485996 -61.002348) (xy 78.485996 -60.917652) (xy 78.494047 -60.833338) (xy 78.510076 -60.750172)
			(xy 78.533937 -60.668905) (xy 78.565416 -60.590275) (xy 78.604227 -60.514994) (xy 78.650017 -60.443742)
			(xy 78.702373 -60.377166) (xy 78.760821 -60.315868) (xy 78.824831 -60.260403) (xy 78.893823 -60.211274)
			(xy 78.967173 -60.168925) (xy 79.044216 -60.133741) (xy 79.124255 -60.106039) (xy 79.206564 -60.086071)
			(xy 79.290399 -60.074018) (xy 79.375 -60.069988) (xy 79.459601 -60.074018) (xy 79.543436 -60.086071)
			(xy 79.625745 -60.106039) (xy 79.705784 -60.133741) (xy 79.782827 -60.168925) (xy 79.856177 -60.211274)
			(xy 79.925169 -60.260403) (xy 79.989179 -60.315868) (xy 80.047627 -60.377166) (xy 80.099983 -60.443742)
			(xy 80.145773 -60.514994) (xy 80.184584 -60.590275) (xy 80.216063 -60.668905) (xy 80.239924 -60.750172)
			(xy 80.255953 -60.833338) (xy 80.264004 -60.917652) (xy 80.264508 -60.96) (xy 80.264004 -61.002348)
			(xy 89.788996 -61.002348) (xy 89.788996 -60.917652) (xy 89.797047 -60.833338) (xy 89.813076 -60.750172)
			(xy 89.836937 -60.668905) (xy 89.868416 -60.590275) (xy 89.907227 -60.514994) (xy 89.953017 -60.443742)
			(xy 90.005373 -60.377166) (xy 90.063821 -60.315868) (xy 90.127831 -60.260403) (xy 90.196823 -60.211274)
			(xy 90.270173 -60.168925) (xy 90.347216 -60.133741) (xy 90.427255 -60.106039) (xy 90.509564 -60.086071)
			(xy 90.593399 -60.074018) (xy 90.678 -60.069988) (xy 90.762601 -60.074018) (xy 90.846436 -60.086071)
			(xy 90.928745 -60.106039) (xy 91.008784 -60.133741) (xy 91.085827 -60.168925) (xy 91.159177 -60.211274)
			(xy 91.228169 -60.260403) (xy 91.292179 -60.315868) (xy 91.350627 -60.377166) (xy 91.402983 -60.443742)
			(xy 91.448773 -60.514994) (xy 91.487584 -60.590275) (xy 91.519063 -60.668905) (xy 91.542924 -60.750172)
			(xy 91.558953 -60.833338) (xy 91.567004 -60.917652) (xy 91.567508 -60.96) (xy 91.567004 -61.002348)
			(xy 91.558953 -61.086662) (xy 91.542924 -61.169828) (xy 91.519063 -61.251095) (xy 91.487584 -61.329725)
			(xy 91.448773 -61.405006) (xy 91.402983 -61.476258) (xy 91.350627 -61.542834) (xy 91.292179 -61.604132)
			(xy 91.228169 -61.659597) (xy 91.159177 -61.708726) (xy 91.085827 -61.751075) (xy 91.008784 -61.786259)
			(xy 90.928745 -61.813961) (xy 90.846436 -61.833929) (xy 90.762601 -61.845982) (xy 90.678 -61.850013)
			(xy 90.593399 -61.845982) (xy 90.509564 -61.833929) (xy 90.427255 -61.813961) (xy 90.347216 -61.786259)
			(xy 90.270173 -61.751075) (xy 90.196823 -61.708726) (xy 90.127831 -61.659597) (xy 90.063821 -61.604132)
			(xy 90.005373 -61.542834) (xy 89.953017 -61.476258) (xy 89.907227 -61.405006) (xy 89.868416 -61.329725)
			(xy 89.836937 -61.251095) (xy 89.813076 -61.169828) (xy 89.797047 -61.086662) (xy 89.788996 -61.002348)
			(xy 80.264004 -61.002348) (xy 80.255953 -61.086662) (xy 80.239924 -61.169828) (xy 80.216063 -61.251095)
			(xy 80.184584 -61.329725) (xy 80.145773 -61.405006) (xy 80.099983 -61.476258) (xy 80.047627 -61.542834)
			(xy 79.989179 -61.604132) (xy 79.925169 -61.659597) (xy 79.856177 -61.708726) (xy 79.782827 -61.751075)
			(xy 79.705784 -61.786259) (xy 79.625745 -61.813961) (xy 79.543436 -61.833929) (xy 79.459601 -61.845982)
			(xy 79.375 -61.850013) (xy 79.290399 -61.845982) (xy 79.206564 -61.833929) (xy 79.124255 -61.813961)
			(xy 79.044216 -61.786259) (xy 78.967173 -61.751075) (xy 78.893823 -61.708726) (xy 78.824831 -61.659597)
			(xy 78.760821 -61.604132) (xy 78.702373 -61.542834) (xy 78.650017 -61.476258) (xy 78.604227 -61.405006)
			(xy 78.565416 -61.329725) (xy 78.533937 -61.251095) (xy 78.510076 -61.169828) (xy 78.494047 -61.086662)
			(xy 78.485996 -61.002348) (xy 68.961004 -61.002348) (xy 68.952953 -61.086662) (xy 68.936924 -61.169828)
			(xy 68.913063 -61.251095) (xy 68.881584 -61.329725) (xy 68.842773 -61.405006) (xy 68.796983 -61.476258)
			(xy 68.744627 -61.542834) (xy 68.686179 -61.604132) (xy 68.622169 -61.659597) (xy 68.553177 -61.708726)
			(xy 68.479827 -61.751075) (xy 68.402784 -61.786259) (xy 68.322745 -61.813961) (xy 68.240436 -61.833929)
			(xy 68.156601 -61.845982) (xy 68.072 -61.850013) (xy 67.987399 -61.845982) (xy 67.903564 -61.833929)
			(xy 67.821255 -61.813961) (xy 67.741216 -61.786259) (xy 67.664173 -61.751075) (xy 67.590823 -61.708726)
			(xy 67.521831 -61.659597) (xy 67.457821 -61.604132) (xy 67.399373 -61.542834) (xy 67.347017 -61.476258)
			(xy 67.301227 -61.405006) (xy 67.262416 -61.329725) (xy 67.230937 -61.251095) (xy 67.207076 -61.169828)
			(xy 67.191047 -61.086662) (xy 67.182996 -61.002348) (xy 63.266422 -61.002348) (xy 63.26131 -61.012603)
			(xy 63.21794 -61.082562) (xy 63.168291 -61.148214) (xy 63.112789 -61.208998) (xy 63.051907 -61.264393)
			(xy 62.986168 -61.313926) (xy 62.916133 -61.357173) (xy 62.842402 -61.393764) (xy 62.765605 -61.423386)
			(xy 62.686399 -61.445785) (xy 62.605463 -61.46077) (xy 62.564518 -61.464952) (xy 62.55385 -61.465714)
			(xy 62.535562 -61.475874) (xy 62.476888 -61.551312) (xy 62.471808 -61.571632) (xy 62.473332 -61.582046)
			(xy 62.478554 -61.616799) (xy 62.484147 -61.686859) (xy 62.484508 -61.722) (xy 62.48401 -61.763505)
			(xy 62.476274 -61.846154) (xy 62.46087 -61.927723) (xy 62.437931 -62.007501) (xy 62.407657 -62.084794)
			(xy 62.370312 -62.158929) (xy 62.326221 -62.229262) (xy 62.301374 -62.262512) (xy 62.295035 -62.271712)
			(xy 62.290209 -62.2935) (xy 62.295035 -62.315288) (xy 62.301374 -62.324488) (xy 62.326221 -62.357738)
			(xy 62.370317 -62.428069) (xy 62.407667 -62.502204) (xy 62.437944 -62.579496) (xy 62.460885 -62.659275)
			(xy 62.475755 -62.738) (xy 100.329492 -62.738) (xy 100.32999 -62.696495) (xy 100.337726 -62.613846)
			(xy 100.35313 -62.532277) (xy 100.376069 -62.452499) (xy 100.406343 -62.375206) (xy 100.443688 -62.301071)
			(xy 100.487779 -62.230738) (xy 100.512626 -62.197488) (xy 100.518965 -62.188288) (xy 100.523791 -62.1665)
			(xy 100.518965 -62.144712) (xy 100.512626 -62.135512) (xy 100.487779 -62.102262) (xy 100.443683 -62.031931)
			(xy 100.406333 -61.957796) (xy 100.376056 -61.880504) (xy 100.353115 -61.800725) (xy 100.337708 -61.719156)
			(xy 100.329972 -61.636506) (xy 100.329492 -61.595) (xy 100.329958 -61.553844) (xy 100.337545 -61.471883)
			(xy 100.352673 -61.390973) (xy 100.375212 -61.311808) (xy 100.404969 -61.235063) (xy 100.44169 -61.161397)
			(xy 100.48506 -61.091438) (xy 100.534709 -61.025786) (xy 100.590211 -60.965002) (xy 100.651093 -60.909607)
			(xy 100.716832 -60.860074) (xy 100.786867 -60.816827) (xy 100.860598 -60.780236) (xy 100.937395 -60.750614)
			(xy 101.016601 -60.728215) (xy 101.097537 -60.71323) (xy 101.138482 -60.709048) (xy 101.14915 -60.708286)
			(xy 101.167438 -60.698126) (xy 101.226112 -60.622688) (xy 101.231192 -60.602368) (xy 101.229668 -60.591954)
			(xy 101.224446 -60.557201) (xy 101.218853 -60.487141) (xy 101.218492 -60.452) (xy 101.219075 -60.405604)
			(xy 101.22872 -60.313316) (xy 101.247916 -60.222532) (xy 101.276454 -60.134239) (xy 101.294692 -60.091574)
			(xy 101.298597 -60.081652) (xy 101.298597 -60.060348) (xy 101.294692 -60.050426) (xy 101.276447 -60.007764)
			(xy 101.247903 -59.919471) (xy 101.22871 -59.828686) (xy 101.219077 -59.736396) (xy 101.218492 -59.69)
			(xy 101.218996 -59.647652) (xy 101.227047 -59.563338) (xy 101.243076 -59.480172) (xy 101.266937 -59.398905)
			(xy 101.298416 -59.320275) (xy 101.337227 -59.244994) (xy 101.383017 -59.173742) (xy 101.435373 -59.107166)
			(xy 101.493821 -59.045868) (xy 101.557831 -58.990403) (xy 101.626823 -58.941274) (xy 101.700173 -58.898925)
			(xy 101.777216 -58.863741) (xy 101.857255 -58.836039) (xy 101.939564 -58.816071) (xy 102.023399 -58.804018)
			(xy 102.108 -58.799988) (xy 102.192601 -58.804018) (xy 102.276436 -58.816071) (xy 102.358745 -58.836039)
			(xy 102.438784 -58.863741) (xy 102.515827 -58.898925) (xy 102.589177 -58.941274) (xy 102.658169 -58.990403)
			(xy 102.722179 -59.045868) (xy 102.780627 -59.107166) (xy 102.832983 -59.173742) (xy 102.878773 -59.244994)
			(xy 102.917584 -59.320275) (xy 102.949063 -59.398905) (xy 102.972924 -59.480172) (xy 102.988953 -59.563338)
			(xy 102.997004 -59.647652) (xy 102.997508 -59.69) (xy 102.996925 -59.736396) (xy 102.98728 -59.828684)
			(xy 102.968084 -59.919468) (xy 102.939546 -60.007761) (xy 102.921308 -60.050426) (xy 102.917403 -60.060348)
			(xy 102.917403 -60.081652) (xy 102.921308 -60.091574) (xy 102.939553 -60.134236) (xy 102.968097 -60.222529)
			(xy 102.98729 -60.313314) (xy 102.996923 -60.405604) (xy 102.997508 -60.452) (xy 102.997042 -60.493156)
			(xy 102.989455 -60.575117) (xy 102.974327 -60.656027) (xy 102.951788 -60.735192) (xy 102.922031 -60.811937)
			(xy 102.88531 -60.885603) (xy 102.84194 -60.955562) (xy 102.806558 -61.002348) (xy 107.949996 -61.002348)
			(xy 107.949996 -60.917652) (xy 107.958047 -60.833338) (xy 107.974076 -60.750172) (xy 107.997937 -60.668905)
			(xy 108.029416 -60.590275) (xy 108.068227 -60.514994) (xy 108.114017 -60.443742) (xy 108.166373 -60.377166)
			(xy 108.224821 -60.315868) (xy 108.288831 -60.260403) (xy 108.357823 -60.211274) (xy 108.431173 -60.168925)
			(xy 108.508216 -60.133741) (xy 108.588255 -60.106039) (xy 108.670564 -60.086071) (xy 108.754399 -60.074018)
			(xy 108.839 -60.069988) (xy 108.923601 -60.074018) (xy 109.007436 -60.086071) (xy 109.089745 -60.106039)
			(xy 109.169784 -60.133741) (xy 109.246827 -60.168925) (xy 109.320177 -60.211274) (xy 109.389169 -60.260403)
			(xy 109.453179 -60.315868) (xy 109.511627 -60.377166) (xy 109.563983 -60.443742) (xy 109.609773 -60.514994)
			(xy 109.648584 -60.590275) (xy 109.680063 -60.668905) (xy 109.703924 -60.750172) (xy 109.719953 -60.833338)
			(xy 109.728004 -60.917652) (xy 109.728508 -60.96) (xy 109.728004 -61.002348) (xy 119.125996 -61.002348)
			(xy 119.125996 -60.917652) (xy 119.134047 -60.833338) (xy 119.150076 -60.750172) (xy 119.173937 -60.668905)
			(xy 119.205416 -60.590275) (xy 119.244227 -60.514994) (xy 119.290017 -60.443742) (xy 119.342373 -60.377166)
			(xy 119.400821 -60.315868) (xy 119.464831 -60.260403) (xy 119.533823 -60.211274) (xy 119.607173 -60.168925)
			(xy 119.684216 -60.133741) (xy 119.764255 -60.106039) (xy 119.846564 -60.086071) (xy 119.930399 -60.074018)
			(xy 120.015 -60.069988) (xy 120.099601 -60.074018) (xy 120.183436 -60.086071) (xy 120.265745 -60.106039)
			(xy 120.345784 -60.133741) (xy 120.422827 -60.168925) (xy 120.496177 -60.211274) (xy 120.565169 -60.260403)
			(xy 120.629179 -60.315868) (xy 120.687627 -60.377166) (xy 120.739983 -60.443742) (xy 120.785773 -60.514994)
			(xy 120.824584 -60.590275) (xy 120.856063 -60.668905) (xy 120.879924 -60.750172) (xy 120.895953 -60.833338)
			(xy 120.904004 -60.917652) (xy 120.904508 -60.96) (xy 120.904004 -61.002348) (xy 130.301996 -61.002348)
			(xy 130.301996 -60.917652) (xy 130.310047 -60.833338) (xy 130.326076 -60.750172) (xy 130.349937 -60.668905)
			(xy 130.381416 -60.590275) (xy 130.420227 -60.514994) (xy 130.466017 -60.443742) (xy 130.518373 -60.377166)
			(xy 130.576821 -60.315868) (xy 130.640831 -60.260403) (xy 130.709823 -60.211274) (xy 130.783173 -60.168925)
			(xy 130.860216 -60.133741) (xy 130.940255 -60.106039) (xy 131.022564 -60.086071) (xy 131.106399 -60.074018)
			(xy 131.191 -60.069988) (xy 131.275601 -60.074018) (xy 131.359436 -60.086071) (xy 131.441745 -60.106039)
			(xy 131.521784 -60.133741) (xy 131.598827 -60.168925) (xy 131.672177 -60.211274) (xy 131.741169 -60.260403)
			(xy 131.805179 -60.315868) (xy 131.863627 -60.377166) (xy 131.915983 -60.443742) (xy 131.961773 -60.514994)
			(xy 132.000584 -60.590275) (xy 132.032063 -60.668905) (xy 132.055924 -60.750172) (xy 132.071953 -60.833338)
			(xy 132.080004 -60.917652) (xy 132.080508 -60.96) (xy 132.080004 -61.002348) (xy 132.071953 -61.086662)
			(xy 132.055924 -61.169828) (xy 132.032063 -61.251095) (xy 132.000584 -61.329725) (xy 131.961773 -61.405006)
			(xy 131.915983 -61.476258) (xy 131.863627 -61.542834) (xy 131.805179 -61.604132) (xy 131.741169 -61.659597)
			(xy 131.672177 -61.708726) (xy 131.598827 -61.751075) (xy 131.521784 -61.786259) (xy 131.441745 -61.813961)
			(xy 131.359436 -61.833929) (xy 131.275601 -61.845982) (xy 131.191 -61.850013) (xy 131.106399 -61.845982)
			(xy 131.022564 -61.833929) (xy 130.940255 -61.813961) (xy 130.860216 -61.786259) (xy 130.783173 -61.751075)
			(xy 130.709823 -61.708726) (xy 130.640831 -61.659597) (xy 130.576821 -61.604132) (xy 130.518373 -61.542834)
			(xy 130.466017 -61.476258) (xy 130.420227 -61.405006) (xy 130.381416 -61.329725) (xy 130.349937 -61.251095)
			(xy 130.326076 -61.169828) (xy 130.310047 -61.086662) (xy 130.301996 -61.002348) (xy 120.904004 -61.002348)
			(xy 120.895953 -61.086662) (xy 120.879924 -61.169828) (xy 120.856063 -61.251095) (xy 120.824584 -61.329725)
			(xy 120.785773 -61.405006) (xy 120.739983 -61.476258) (xy 120.687627 -61.542834) (xy 120.629179 -61.604132)
			(xy 120.565169 -61.659597) (xy 120.496177 -61.708726) (xy 120.422827 -61.751075) (xy 120.345784 -61.786259)
			(xy 120.265745 -61.813961) (xy 120.183436 -61.833929) (xy 120.099601 -61.845982) (xy 120.015 -61.850013)
			(xy 119.930399 -61.845982) (xy 119.846564 -61.833929) (xy 119.764255 -61.813961) (xy 119.684216 -61.786259)
			(xy 119.607173 -61.751075) (xy 119.533823 -61.708726) (xy 119.464831 -61.659597) (xy 119.400821 -61.604132)
			(xy 119.342373 -61.542834) (xy 119.290017 -61.476258) (xy 119.244227 -61.405006) (xy 119.205416 -61.329725)
			(xy 119.173937 -61.251095) (xy 119.150076 -61.169828) (xy 119.134047 -61.086662) (xy 119.125996 -61.002348)
			(xy 109.728004 -61.002348) (xy 109.719953 -61.086662) (xy 109.703924 -61.169828) (xy 109.680063 -61.251095)
			(xy 109.648584 -61.329725) (xy 109.609773 -61.405006) (xy 109.563983 -61.476258) (xy 109.511627 -61.542834)
			(xy 109.453179 -61.604132) (xy 109.389169 -61.659597) (xy 109.320177 -61.708726) (xy 109.246827 -61.751075)
			(xy 109.169784 -61.786259) (xy 109.089745 -61.813961) (xy 109.007436 -61.833929) (xy 108.923601 -61.845982)
			(xy 108.839 -61.850013) (xy 108.754399 -61.845982) (xy 108.670564 -61.833929) (xy 108.588255 -61.813961)
			(xy 108.508216 -61.786259) (xy 108.431173 -61.751075) (xy 108.357823 -61.708726) (xy 108.288831 -61.659597)
			(xy 108.224821 -61.604132) (xy 108.166373 -61.542834) (xy 108.114017 -61.476258) (xy 108.068227 -61.405006)
			(xy 108.029416 -61.329725) (xy 107.997937 -61.251095) (xy 107.974076 -61.169828) (xy 107.958047 -61.086662)
			(xy 107.949996 -61.002348) (xy 102.806558 -61.002348) (xy 102.792291 -61.021214) (xy 102.736789 -61.081998)
			(xy 102.675907 -61.137393) (xy 102.610168 -61.186926) (xy 102.540133 -61.230173) (xy 102.466402 -61.266764)
			(xy 102.389605 -61.296386) (xy 102.310399 -61.318785) (xy 102.229463 -61.33377) (xy 102.188518 -61.337952)
			(xy 102.17785 -61.338714) (xy 102.159562 -61.348874) (xy 102.100888 -61.424312) (xy 102.095808 -61.444632)
			(xy 102.097332 -61.455046) (xy 102.102554 -61.489799) (xy 102.108147 -61.559859) (xy 102.108508 -61.595)
			(xy 102.10801 -61.636505) (xy 102.100274 -61.719154) (xy 102.08487 -61.800723) (xy 102.061931 -61.880501)
			(xy 102.031657 -61.957794) (xy 101.994312 -62.031929) (xy 101.950221 -62.102262) (xy 101.925374 -62.135512)
			(xy 101.919035 -62.144712) (xy 101.914209 -62.1665) (xy 101.919035 -62.188288) (xy 101.925374 -62.197488)
			(xy 101.950221 -62.230738) (xy 101.994317 -62.301069) (xy 102.031667 -62.375204) (xy 102.061944 -62.452496)
			(xy 102.084885 -62.532275) (xy 102.100292 -62.613844) (xy 102.108028 -62.696494) (xy 102.108508 -62.738)
			(xy 139.318492 -62.738) (xy 139.319052 -62.694207) (xy 139.327682 -62.607046) (xy 139.344828 -62.521154)
			(xy 139.370325 -62.43736) (xy 139.403926 -62.356475) (xy 139.424156 -62.31763) (xy 139.429577 -62.306164)
			(xy 139.429577 -62.280836) (xy 139.424156 -62.26937) (xy 139.403917 -62.230528) (xy 139.370281 -62.149652)
			(xy 139.344768 -62.065859) (xy 139.327623 -61.979963) (xy 139.319013 -61.892796) (xy 139.318492 -61.849)
			(xy 139.318958 -61.807844) (xy 139.326545 -61.725883) (xy 139.341673 -61.644973) (xy 139.364212 -61.565808)
			(xy 139.393969 -61.489063) (xy 139.43069 -61.415397) (xy 139.47406 -61.345438) (xy 139.523709 -61.279786)
			(xy 139.579211 -61.219002) (xy 139.640093 -61.163607) (xy 139.705832 -61.114074) (xy 139.775867 -61.070827)
			(xy 139.849598 -61.034236) (xy 139.926395 -61.004614) (xy 140.005601 -60.982215) (xy 140.086537 -60.96723)
			(xy 140.127482 -60.963048) (xy 140.13815 -60.962286) (xy 140.156438 -60.952126) (xy 140.215112 -60.876688)
			(xy 140.220192 -60.856368) (xy 140.218668 -60.845954) (xy 140.213446 -60.811201) (xy 140.207853 -60.741141)
			(xy 140.207492 -60.706) (xy 140.208075 -60.659604) (xy 140.21772 -60.567316) (xy 140.236916 -60.476532)
			(xy 140.265454 -60.388239) (xy 140.283692 -60.345574) (xy 140.287597 -60.335652) (xy 140.287597 -60.314348)
			(xy 140.283692 -60.304426) (xy 140.265447 -60.261764) (xy 140.236903 -60.173471) (xy 140.21771 -60.082686)
			(xy 140.208077 -59.990396) (xy 140.207492 -59.944) (xy 140.207996 -59.901652) (xy 140.216047 -59.817338)
			(xy 140.232076 -59.734172) (xy 140.255937 -59.652905) (xy 140.287416 -59.574275) (xy 140.326227 -59.498994)
			(xy 140.372017 -59.427742) (xy 140.424373 -59.361166) (xy 140.482821 -59.299868) (xy 140.546831 -59.244403)
			(xy 140.615823 -59.195274) (xy 140.689173 -59.152925) (xy 140.766216 -59.117741) (xy 140.846255 -59.090039)
			(xy 140.928564 -59.070071) (xy 141.012399 -59.058018) (xy 141.097 -59.053988) (xy 141.181601 -59.058018)
			(xy 141.265436 -59.070071) (xy 141.347745 -59.090039) (xy 141.427784 -59.117741) (xy 141.504827 -59.152925)
			(xy 141.578177 -59.195274) (xy 141.647169 -59.244403) (xy 141.711179 -59.299868) (xy 141.769627 -59.361166)
			(xy 141.821983 -59.427742) (xy 141.867773 -59.498994) (xy 141.906584 -59.574275) (xy 141.938063 -59.652905)
			(xy 141.961924 -59.734172) (xy 141.977953 -59.817338) (xy 141.986004 -59.901652) (xy 141.986508 -59.944)
			(xy 141.985925 -59.990396) (xy 141.97628 -60.082684) (xy 141.957084 -60.173468) (xy 141.928546 -60.261761)
			(xy 141.910308 -60.304426) (xy 141.906403 -60.314348) (xy 141.906403 -60.335652) (xy 141.910308 -60.345574)
			(xy 141.928553 -60.388236) (xy 141.957097 -60.476529) (xy 141.97629 -60.567314) (xy 141.985923 -60.659604)
			(xy 141.986508 -60.706) (xy 141.986042 -60.747156) (xy 141.978455 -60.829117) (xy 141.963327 -60.910027)
			(xy 141.940788 -60.989192) (xy 141.935687 -61.002348) (xy 146.049996 -61.002348) (xy 146.049996 -60.917652)
			(xy 146.058047 -60.833338) (xy 146.074076 -60.750172) (xy 146.097937 -60.668905) (xy 146.129416 -60.590275)
			(xy 146.168227 -60.514994) (xy 146.214017 -60.443742) (xy 146.266373 -60.377166) (xy 146.324821 -60.315868)
			(xy 146.388831 -60.260403) (xy 146.457823 -60.211274) (xy 146.531173 -60.168925) (xy 146.608216 -60.133741)
			(xy 146.688255 -60.106039) (xy 146.770564 -60.086071) (xy 146.854399 -60.074018) (xy 146.939 -60.069988)
			(xy 147.023601 -60.074018) (xy 147.107436 -60.086071) (xy 147.189745 -60.106039) (xy 147.269784 -60.133741)
			(xy 147.346827 -60.168925) (xy 147.420177 -60.211274) (xy 147.489169 -60.260403) (xy 147.553179 -60.315868)
			(xy 147.611627 -60.377166) (xy 147.663983 -60.443742) (xy 147.709773 -60.514994) (xy 147.748584 -60.590275)
			(xy 147.780063 -60.668905) (xy 147.803924 -60.750172) (xy 147.819953 -60.833338) (xy 147.828004 -60.917652)
			(xy 147.828508 -60.96) (xy 147.828004 -61.002348) (xy 157.225996 -61.002348) (xy 157.225996 -60.917652)
			(xy 157.234047 -60.833338) (xy 157.250076 -60.750172) (xy 157.273937 -60.668905) (xy 157.305416 -60.590275)
			(xy 157.344227 -60.514994) (xy 157.390017 -60.443742) (xy 157.442373 -60.377166) (xy 157.500821 -60.315868)
			(xy 157.564831 -60.260403) (xy 157.633823 -60.211274) (xy 157.707173 -60.168925) (xy 157.784216 -60.133741)
			(xy 157.864255 -60.106039) (xy 157.946564 -60.086071) (xy 158.030399 -60.074018) (xy 158.115 -60.069988)
			(xy 158.199601 -60.074018) (xy 158.283436 -60.086071) (xy 158.365745 -60.106039) (xy 158.445784 -60.133741)
			(xy 158.522827 -60.168925) (xy 158.596177 -60.211274) (xy 158.665169 -60.260403) (xy 158.729179 -60.315868)
			(xy 158.787627 -60.377166) (xy 158.839983 -60.443742) (xy 158.885773 -60.514994) (xy 158.924584 -60.590275)
			(xy 158.956063 -60.668905) (xy 158.979924 -60.750172) (xy 158.995953 -60.833338) (xy 159.004004 -60.917652)
			(xy 159.004508 -60.96) (xy 159.004004 -61.002348) (xy 168.401996 -61.002348) (xy 168.401996 -60.917652)
			(xy 168.410047 -60.833338) (xy 168.426076 -60.750172) (xy 168.449937 -60.668905) (xy 168.481416 -60.590275)
			(xy 168.520227 -60.514994) (xy 168.566017 -60.443742) (xy 168.618373 -60.377166) (xy 168.676821 -60.315868)
			(xy 168.740831 -60.260403) (xy 168.809823 -60.211274) (xy 168.883173 -60.168925) (xy 168.960216 -60.133741)
			(xy 169.040255 -60.106039) (xy 169.122564 -60.086071) (xy 169.206399 -60.074018) (xy 169.291 -60.069988)
			(xy 169.375601 -60.074018) (xy 169.459436 -60.086071) (xy 169.541745 -60.106039) (xy 169.621784 -60.133741)
			(xy 169.698827 -60.168925) (xy 169.772177 -60.211274) (xy 169.841169 -60.260403) (xy 169.905179 -60.315868)
			(xy 169.963627 -60.377166) (xy 170.015983 -60.443742) (xy 170.061773 -60.514994) (xy 170.100584 -60.590275)
			(xy 170.132063 -60.668905) (xy 170.155924 -60.750172) (xy 170.171953 -60.833338) (xy 170.180004 -60.917652)
			(xy 170.180508 -60.96) (xy 170.180004 -61.002348) (xy 170.171953 -61.086662) (xy 170.155924 -61.169828)
			(xy 170.132063 -61.251095) (xy 170.100584 -61.329725) (xy 170.061773 -61.405006) (xy 170.015983 -61.476258)
			(xy 169.963627 -61.542834) (xy 169.905179 -61.604132) (xy 169.841169 -61.659597) (xy 169.772177 -61.708726)
			(xy 169.698827 -61.751075) (xy 169.621784 -61.786259) (xy 169.541745 -61.813961) (xy 169.459436 -61.833929)
			(xy 169.375601 -61.845982) (xy 169.31226 -61.849) (xy 179.318666 -61.849) (xy 179.319156 -61.807845)
			(xy 179.326743 -61.725885) (xy 179.34187 -61.644977) (xy 179.364408 -61.565812) (xy 179.394164 -61.489069)
			(xy 179.430883 -61.415403) (xy 179.474252 -61.345445) (xy 179.523899 -61.279794) (xy 179.5794 -61.21901)
			(xy 179.640279 -61.163615) (xy 179.706017 -61.114081) (xy 179.77605 -61.070834) (xy 179.849779 -61.034242)
			(xy 179.926574 -61.004619) (xy 180.005777 -60.982218) (xy 180.086711 -60.967231) (xy 180.127656 -60.963048)
			(xy 180.138324 -60.962286) (xy 180.156612 -60.952126) (xy 180.215286 -60.876688) (xy 180.220366 -60.856368)
			(xy 180.218842 -60.845954) (xy 180.21362 -60.811201) (xy 180.208027 -60.741141) (xy 180.207666 -60.706)
			(xy 180.208251 -60.659604) (xy 180.217896 -60.567316) (xy 180.237091 -60.476533) (xy 180.265629 -60.388239)
			(xy 180.283866 -60.345574) (xy 180.287683 -60.335634) (xy 180.287683 -60.314366) (xy 180.283866 -60.304426)
			(xy 180.26562 -60.261764) (xy 180.237076 -60.173472) (xy 180.217884 -60.082687) (xy 180.208251 -59.990396)
			(xy 180.207666 -59.944) (xy 180.20817 -59.901652) (xy 180.216221 -59.817338) (xy 180.23225 -59.734172)
			(xy 180.256111 -59.652905) (xy 180.28759 -59.574275) (xy 180.326401 -59.498994) (xy 180.372191 -59.427742)
			(xy 180.424547 -59.361166) (xy 180.482995 -59.299868) (xy 180.547005 -59.244403) (xy 180.615997 -59.195274)
			(xy 180.689347 -59.152925) (xy 180.76639 -59.117741) (xy 180.846429 -59.090039) (xy 180.928738 -59.070071)
			(xy 181.012573 -59.058018) (xy 181.097174 -59.053988) (xy 181.181775 -59.058018) (xy 181.26561 -59.070071)
			(xy 181.347919 -59.090039) (xy 181.427958 -59.117741) (xy 181.505001 -59.152925) (xy 181.578351 -59.195274)
			(xy 181.647343 -59.244403) (xy 181.711353 -59.299868) (xy 181.769801 -59.361166) (xy 181.822157 -59.427742)
			(xy 181.867947 -59.498994) (xy 181.906758 -59.574275) (xy 181.938237 -59.652905) (xy 181.962098 -59.734172)
			(xy 181.978127 -59.817338) (xy 181.986178 -59.901652) (xy 181.986682 -59.944) (xy 181.986101 -59.990396)
			(xy 181.976456 -60.082684) (xy 181.957259 -60.173468) (xy 181.92872 -60.261761) (xy 181.910482 -60.304426)
			(xy 181.906662 -60.314366) (xy 181.906662 -60.335634) (xy 181.910482 -60.345574) (xy 181.928725 -60.388237)
			(xy 181.95727 -60.476529) (xy 181.976464 -60.567314) (xy 181.986097 -60.659604) (xy 181.986682 -60.706)
			(xy 181.986239 -60.747157) (xy 181.978652 -60.829119) (xy 181.963524 -60.91003) (xy 181.940984 -60.989197)
			(xy 181.935885 -61.002348) (xy 186.05017 -61.002348) (xy 186.05017 -60.917652) (xy 186.058221 -60.833338)
			(xy 186.07425 -60.750172) (xy 186.098111 -60.668905) (xy 186.12959 -60.590275) (xy 186.168401 -60.514994)
			(xy 186.214191 -60.443742) (xy 186.266547 -60.377166) (xy 186.324995 -60.315868) (xy 186.389005 -60.260403)
			(xy 186.457997 -60.211274) (xy 186.531347 -60.168925) (xy 186.60839 -60.133741) (xy 186.688429 -60.106039)
			(xy 186.770738 -60.086071) (xy 186.854573 -60.074018) (xy 186.939174 -60.069988) (xy 187.023775 -60.074018)
			(xy 187.10761 -60.086071) (xy 187.189919 -60.106039) (xy 187.269958 -60.133741) (xy 187.347001 -60.168925)
			(xy 187.420351 -60.211274) (xy 187.489343 -60.260403) (xy 187.553353 -60.315868) (xy 187.611801 -60.377166)
			(xy 187.664157 -60.443742) (xy 187.709947 -60.514994) (xy 187.748758 -60.590275) (xy 187.780237 -60.668905)
			(xy 187.804098 -60.750172) (xy 187.820127 -60.833338) (xy 187.828178 -60.917652) (xy 187.828682 -60.96)
			(xy 187.828178 -61.002348) (xy 197.22617 -61.002348) (xy 197.22617 -60.917652) (xy 197.234221 -60.833338)
			(xy 197.25025 -60.750172) (xy 197.274111 -60.668905) (xy 197.30559 -60.590275) (xy 197.344401 -60.514994)
			(xy 197.390191 -60.443742) (xy 197.442547 -60.377166) (xy 197.500995 -60.315868) (xy 197.565005 -60.260403)
			(xy 197.633997 -60.211274) (xy 197.707347 -60.168925) (xy 197.78439 -60.133741) (xy 197.864429 -60.106039)
			(xy 197.946738 -60.086071) (xy 198.030573 -60.074018) (xy 198.115174 -60.069988) (xy 198.199775 -60.074018)
			(xy 198.28361 -60.086071) (xy 198.365919 -60.106039) (xy 198.445958 -60.133741) (xy 198.523001 -60.168925)
			(xy 198.596351 -60.211274) (xy 198.665343 -60.260403) (xy 198.729353 -60.315868) (xy 198.787801 -60.377166)
			(xy 198.840157 -60.443742) (xy 198.885947 -60.514994) (xy 198.924758 -60.590275) (xy 198.956237 -60.668905)
			(xy 198.980098 -60.750172) (xy 198.996127 -60.833338) (xy 199.004178 -60.917652) (xy 199.004682 -60.96)
			(xy 199.004178 -61.002348) (xy 208.40217 -61.002348) (xy 208.40217 -60.917652) (xy 208.410221 -60.833338)
			(xy 208.42625 -60.750172) (xy 208.450111 -60.668905) (xy 208.48159 -60.590275) (xy 208.520401 -60.514994)
			(xy 208.566191 -60.443742) (xy 208.618547 -60.377166) (xy 208.676995 -60.315868) (xy 208.741005 -60.260403)
			(xy 208.809997 -60.211274) (xy 208.883347 -60.168925) (xy 208.96039 -60.133741) (xy 209.040429 -60.106039)
			(xy 209.122738 -60.086071) (xy 209.206573 -60.074018) (xy 209.291174 -60.069988) (xy 209.375775 -60.074018)
			(xy 209.45961 -60.086071) (xy 209.541919 -60.106039) (xy 209.621958 -60.133741) (xy 209.699001 -60.168925)
			(xy 209.772351 -60.211274) (xy 209.841343 -60.260403) (xy 209.905353 -60.315868) (xy 209.963801 -60.377166)
			(xy 210.016157 -60.443742) (xy 210.061947 -60.514994) (xy 210.100758 -60.590275) (xy 210.132237 -60.668905)
			(xy 210.156098 -60.750172) (xy 210.172127 -60.833338) (xy 210.180178 -60.917652) (xy 210.180682 -60.96)
			(xy 210.180178 -61.002348) (xy 210.172127 -61.086662) (xy 210.156098 -61.169828) (xy 210.132237 -61.251095)
			(xy 210.100758 -61.329725) (xy 210.061947 -61.405006) (xy 210.016157 -61.476258) (xy 209.963801 -61.542834)
			(xy 209.905353 -61.604132) (xy 209.841343 -61.659597) (xy 209.772351 -61.708726) (xy 209.699001 -61.751075)
			(xy 209.621958 -61.786259) (xy 209.541919 -61.813961) (xy 209.45961 -61.833929) (xy 209.375775 -61.845982)
			(xy 209.291174 -61.850013) (xy 209.206573 -61.845982) (xy 209.122738 -61.833929) (xy 209.040429 -61.813961)
			(xy 208.96039 -61.786259) (xy 208.883347 -61.751075) (xy 208.809997 -61.708726) (xy 208.741005 -61.659597)
			(xy 208.676995 -61.604132) (xy 208.618547 -61.542834) (xy 208.566191 -61.476258) (xy 208.520401 -61.405006)
			(xy 208.48159 -61.329725) (xy 208.450111 -61.251095) (xy 208.42625 -61.169828) (xy 208.410221 -61.086662)
			(xy 208.40217 -61.002348) (xy 199.004178 -61.002348) (xy 198.996127 -61.086662) (xy 198.980098 -61.169828)
			(xy 198.956237 -61.251095) (xy 198.924758 -61.329725) (xy 198.885947 -61.405006) (xy 198.840157 -61.476258)
			(xy 198.787801 -61.542834) (xy 198.729353 -61.604132) (xy 198.665343 -61.659597) (xy 198.596351 -61.708726)
			(xy 198.523001 -61.751075) (xy 198.445958 -61.786259) (xy 198.365919 -61.813961) (xy 198.28361 -61.833929)
			(xy 198.199775 -61.845982) (xy 198.115174 -61.850013) (xy 198.030573 -61.845982) (xy 197.946738 -61.833929)
			(xy 197.864429 -61.813961) (xy 197.78439 -61.786259) (xy 197.707347 -61.751075) (xy 197.633997 -61.708726)
			(xy 197.565005 -61.659597) (xy 197.500995 -61.604132) (xy 197.442547 -61.542834) (xy 197.390191 -61.476258)
			(xy 197.344401 -61.405006) (xy 197.30559 -61.329725) (xy 197.274111 -61.251095) (xy 197.25025 -61.169828)
			(xy 197.234221 -61.086662) (xy 197.22617 -61.002348) (xy 187.828178 -61.002348) (xy 187.820127 -61.086662)
			(xy 187.804098 -61.169828) (xy 187.780237 -61.251095) (xy 187.748758 -61.329725) (xy 187.709947 -61.405006)
			(xy 187.664157 -61.476258) (xy 187.611801 -61.542834) (xy 187.553353 -61.604132) (xy 187.489343 -61.659597)
			(xy 187.420351 -61.708726) (xy 187.347001 -61.751075) (xy 187.269958 -61.786259) (xy 187.189919 -61.813961)
			(xy 187.10761 -61.833929) (xy 187.023775 -61.845982) (xy 186.939174 -61.850013) (xy 186.854573 -61.845982)
			(xy 186.770738 -61.833929) (xy 186.688429 -61.813961) (xy 186.60839 -61.786259) (xy 186.531347 -61.751075)
			(xy 186.457997 -61.708726) (xy 186.389005 -61.659597) (xy 186.324995 -61.604132) (xy 186.266547 -61.542834)
			(xy 186.214191 -61.476258) (xy 186.168401 -61.405006) (xy 186.12959 -61.329725) (xy 186.098111 -61.251095)
			(xy 186.07425 -61.169828) (xy 186.058221 -61.086662) (xy 186.05017 -61.002348) (xy 181.935885 -61.002348)
			(xy 181.911226 -61.065942) (xy 181.874504 -61.13961) (xy 181.831132 -61.209569) (xy 181.781482 -61.275222)
			(xy 181.725977 -61.336006) (xy 181.665094 -61.391401) (xy 181.599352 -61.440934) (xy 181.529315 -61.48418)
			(xy 181.455582 -61.52077) (xy 181.378783 -61.550391) (xy 181.299576 -61.572788) (xy 181.218638 -61.587771)
			(xy 181.177692 -61.591952) (xy 181.167024 -61.592714) (xy 181.148736 -61.602874) (xy 181.090062 -61.678312)
			(xy 181.084982 -61.698632) (xy 181.086506 -61.709046) (xy 181.091728 -61.743799) (xy 181.097321 -61.813859)
			(xy 181.097682 -61.849) (xy 181.09718 -61.892332) (xy 181.088773 -61.978587) (xy 181.07201 -62.063613)
			(xy 181.047049 -62.146604) (xy 181.014128 -62.226772) (xy 180.994304 -62.265306) (xy 180.989053 -62.276759)
			(xy 180.989173 -62.301923) (xy 180.994558 -62.313312) (xy 181.015235 -62.352477) (xy 181.049579 -62.434116)
			(xy 181.075639 -62.518765) (xy 181.093157 -62.605585) (xy 181.101959 -62.693715) (xy 181.102508 -62.738)
			(xy 181.102004 -62.780348) (xy 181.093953 -62.864662) (xy 181.077924 -62.947828) (xy 181.054063 -63.029095)
			(xy 181.022584 -63.107725) (xy 180.983773 -63.183006) (xy 180.937983 -63.254258) (xy 180.885627 -63.320834)
			(xy 180.827179 -63.382132) (xy 180.763169 -63.437597) (xy 180.694177 -63.486726) (xy 180.620827 -63.529075)
			(xy 180.543784 -63.564259) (xy 180.463745 -63.591961) (xy 180.381436 -63.611929) (xy 180.297601 -63.623982)
			(xy 180.213 -63.628013) (xy 180.128399 -63.623982) (xy 180.044564 -63.611929) (xy 179.962255 -63.591961)
			(xy 179.882216 -63.564259) (xy 179.805173 -63.529075) (xy 179.731823 -63.486726) (xy 179.662831 -63.437597)
			(xy 179.598821 -63.382132) (xy 179.540373 -63.320834) (xy 179.488017 -63.254258) (xy 179.442227 -63.183006)
			(xy 179.403416 -63.107725) (xy 179.371937 -63.029095) (xy 179.348076 -62.947828) (xy 179.332047 -62.864662)
			(xy 179.323996 -62.780348) (xy 179.323492 -62.738) (xy 179.323997 -62.694668) (xy 179.332403 -62.608414)
			(xy 179.349166 -62.523387) (xy 179.374126 -62.440396) (xy 179.407046 -62.360229) (xy 179.42687 -62.321694)
			(xy 179.432123 -62.310241) (xy 179.432003 -62.285077) (xy 179.426616 -62.273688) (xy 179.405945 -62.23452)
			(xy 179.371599 -62.152882) (xy 179.345537 -62.068234) (xy 179.328018 -61.981415) (xy 179.319215 -61.893284)
			(xy 179.318666 -61.849) (xy 169.31226 -61.849) (xy 169.291 -61.850013) (xy 169.206399 -61.845982)
			(xy 169.122564 -61.833929) (xy 169.040255 -61.813961) (xy 168.960216 -61.786259) (xy 168.883173 -61.751075)
			(xy 168.809823 -61.708726) (xy 168.740831 -61.659597) (xy 168.676821 -61.604132) (xy 168.618373 -61.542834)
			(xy 168.566017 -61.476258) (xy 168.520227 -61.405006) (xy 168.481416 -61.329725) (xy 168.449937 -61.251095)
			(xy 168.426076 -61.169828) (xy 168.410047 -61.086662) (xy 168.401996 -61.002348) (xy 159.004004 -61.002348)
			(xy 158.995953 -61.086662) (xy 158.979924 -61.169828) (xy 158.956063 -61.251095) (xy 158.924584 -61.329725)
			(xy 158.885773 -61.405006) (xy 158.839983 -61.476258) (xy 158.787627 -61.542834) (xy 158.729179 -61.604132)
			(xy 158.665169 -61.659597) (xy 158.596177 -61.708726) (xy 158.522827 -61.751075) (xy 158.445784 -61.786259)
			(xy 158.365745 -61.813961) (xy 158.283436 -61.833929) (xy 158.199601 -61.845982) (xy 158.115 -61.850013)
			(xy 158.030399 -61.845982) (xy 157.946564 -61.833929) (xy 157.864255 -61.813961) (xy 157.784216 -61.786259)
			(xy 157.707173 -61.751075) (xy 157.633823 -61.708726) (xy 157.564831 -61.659597) (xy 157.500821 -61.604132)
			(xy 157.442373 -61.542834) (xy 157.390017 -61.476258) (xy 157.344227 -61.405006) (xy 157.305416 -61.329725)
			(xy 157.273937 -61.251095) (xy 157.250076 -61.169828) (xy 157.234047 -61.086662) (xy 157.225996 -61.002348)
			(xy 147.828004 -61.002348) (xy 147.819953 -61.086662) (xy 147.803924 -61.169828) (xy 147.780063 -61.251095)
			(xy 147.748584 -61.329725) (xy 147.709773 -61.405006) (xy 147.663983 -61.476258) (xy 147.611627 -61.542834)
			(xy 147.553179 -61.604132) (xy 147.489169 -61.659597) (xy 147.420177 -61.708726) (xy 147.346827 -61.751075)
			(xy 147.269784 -61.786259) (xy 147.189745 -61.813961) (xy 147.107436 -61.833929) (xy 147.023601 -61.845982)
			(xy 146.939 -61.850013) (xy 146.854399 -61.845982) (xy 146.770564 -61.833929) (xy 146.688255 -61.813961)
			(xy 146.608216 -61.786259) (xy 146.531173 -61.751075) (xy 146.457823 -61.708726) (xy 146.388831 -61.659597)
			(xy 146.324821 -61.604132) (xy 146.266373 -61.542834) (xy 146.214017 -61.476258) (xy 146.168227 -61.405006)
			(xy 146.129416 -61.329725) (xy 146.097937 -61.251095) (xy 146.074076 -61.169828) (xy 146.058047 -61.086662)
			(xy 146.049996 -61.002348) (xy 141.935687 -61.002348) (xy 141.911031 -61.065937) (xy 141.87431 -61.139603)
			(xy 141.83094 -61.209562) (xy 141.781291 -61.275214) (xy 141.725789 -61.335998) (xy 141.664907 -61.391393)
			(xy 141.599168 -61.440926) (xy 141.529133 -61.484173) (xy 141.455402 -61.520764) (xy 141.378605 -61.550386)
			(xy 141.299399 -61.572785) (xy 141.218463 -61.58777) (xy 141.177518 -61.591952) (xy 141.16685 -61.592714)
			(xy 141.148562 -61.602874) (xy 141.089888 -61.678312) (xy 141.084808 -61.698632) (xy 141.086332 -61.709046)
			(xy 141.091554 -61.743799) (xy 141.097147 -61.813859) (xy 141.097508 -61.849) (xy 141.096948 -61.892793)
			(xy 141.088318 -61.979954) (xy 141.071172 -62.065846) (xy 141.045675 -62.14964) (xy 141.012074 -62.230525)
			(xy 140.991844 -62.26937) (xy 140.986423 -62.280836) (xy 140.986423 -62.306164) (xy 140.991844 -62.31763)
			(xy 141.012083 -62.356472) (xy 141.045719 -62.437348) (xy 141.071232 -62.521141) (xy 141.088377 -62.607037)
			(xy 141.096987 -62.694204) (xy 141.097508 -62.738) (xy 141.097004 -62.780348) (xy 141.088953 -62.864662)
			(xy 141.072924 -62.947828) (xy 141.049063 -63.029095) (xy 141.017584 -63.107725) (xy 140.978773 -63.183006)
			(xy 140.932983 -63.254258) (xy 140.880627 -63.320834) (xy 140.822179 -63.382132) (xy 140.758169 -63.437597)
			(xy 140.689177 -63.486726) (xy 140.615827 -63.529075) (xy 140.538784 -63.564259) (xy 140.458745 -63.591961)
			(xy 140.376436 -63.611929) (xy 140.292601 -63.623982) (xy 140.208 -63.628013) (xy 140.123399 -63.623982)
			(xy 140.039564 -63.611929) (xy 139.957255 -63.591961) (xy 139.877216 -63.564259) (xy 139.800173 -63.529075)
			(xy 139.726823 -63.486726) (xy 139.657831 -63.437597) (xy 139.593821 -63.382132) (xy 139.535373 -63.320834)
			(xy 139.483017 -63.254258) (xy 139.437227 -63.183006) (xy 139.398416 -63.107725) (xy 139.366937 -63.029095)
			(xy 139.343076 -62.947828) (xy 139.327047 -62.864662) (xy 139.318996 -62.780348) (xy 139.318492 -62.738)
			(xy 102.108508 -62.738) (xy 102.108004 -62.780348) (xy 102.099953 -62.864662) (xy 102.083924 -62.947828)
			(xy 102.060063 -63.029095) (xy 102.028584 -63.107725) (xy 101.989773 -63.183006) (xy 101.943983 -63.254258)
			(xy 101.891627 -63.320834) (xy 101.833179 -63.382132) (xy 101.769169 -63.437597) (xy 101.700177 -63.486726)
			(xy 101.626827 -63.529075) (xy 101.549784 -63.564259) (xy 101.469745 -63.591961) (xy 101.387436 -63.611929)
			(xy 101.303601 -63.623982) (xy 101.219 -63.628013) (xy 101.134399 -63.623982) (xy 101.050564 -63.611929)
			(xy 100.968255 -63.591961) (xy 100.888216 -63.564259) (xy 100.811173 -63.529075) (xy 100.737823 -63.486726)
			(xy 100.668831 -63.437597) (xy 100.604821 -63.382132) (xy 100.546373 -63.320834) (xy 100.494017 -63.254258)
			(xy 100.448227 -63.183006) (xy 100.409416 -63.107725) (xy 100.377937 -63.029095) (xy 100.354076 -62.947828)
			(xy 100.338047 -62.864662) (xy 100.329996 -62.780348) (xy 100.329492 -62.738) (xy 62.475755 -62.738)
			(xy 62.476292 -62.740844) (xy 62.484028 -62.823494) (xy 62.484508 -62.865) (xy 62.484004 -62.907348)
			(xy 62.475953 -62.991662) (xy 62.459924 -63.074828) (xy 62.436063 -63.156095) (xy 62.404584 -63.234725)
			(xy 62.365773 -63.310006) (xy 62.319983 -63.381258) (xy 62.267627 -63.447834) (xy 62.209179 -63.509132)
			(xy 62.145169 -63.564597) (xy 62.076177 -63.613726) (xy 62.002827 -63.656075) (xy 61.925784 -63.691259)
			(xy 61.845745 -63.718961) (xy 61.763436 -63.738929) (xy 61.679601 -63.750982) (xy 61.595 -63.755013)
			(xy 61.510399 -63.750982) (xy 61.426564 -63.738929) (xy 61.344255 -63.718961) (xy 61.264216 -63.691259)
			(xy 61.187173 -63.656075) (xy 61.113823 -63.613726) (xy 61.044831 -63.564597) (xy 60.980821 -63.509132)
			(xy 60.922373 -63.447834) (xy 60.870017 -63.381258) (xy 60.824227 -63.310006) (xy 60.785416 -63.234725)
			(xy 60.753937 -63.156095) (xy 60.730076 -63.074828) (xy 60.714047 -62.991662) (xy 60.705996 -62.907348)
			(xy 60.705492 -62.865) (xy 51.894284 -62.865) (xy 51.876327 -62.884699) (xy 51.81558 -62.94008) (xy 51.749982 -62.98962)
			(xy 51.680093 -63.032896) (xy 51.60651 -63.069539) (xy 51.529859 -63.099237) (xy 51.450795 -63.121736)
			(xy 51.369993 -63.136843) (xy 51.288141 -63.144432) (xy 51.24704 -63.144908) (xy 51.246532 -63.144908)
			(xy 51.200201 -63.144288) (xy 51.108043 -63.134621) (xy 51.017389 -63.115429) (xy 50.92922 -63.086921)
			(xy 50.886614 -63.068708) (xy 50.876674 -63.064888) (xy 50.855406 -63.064888) (xy 50.845466 -63.068708)
			(xy 50.802798 -63.08694) (xy 50.714508 -63.115487) (xy 50.623725 -63.134684) (xy 50.531436 -63.144321)
			(xy 50.48504 -63.144908) (xy 50.438645 -63.144311) (xy 50.346357 -63.13467) (xy 50.255573 -63.115478)
			(xy 50.167279 -63.086944) (xy 50.124614 -63.068708) (xy 50.114674 -63.064888) (xy 50.093406 -63.064888)
			(xy 50.083466 -63.068708) (xy 50.040798 -63.08694) (xy 49.952508 -63.115487) (xy 49.861725 -63.134684)
			(xy 49.769436 -63.144321) (xy 49.72304 -63.144908) (xy 49.676645 -63.144311) (xy 49.584357 -63.13467)
			(xy 49.493573 -63.115478) (xy 49.405279 -63.086944) (xy 49.362614 -63.068708) (xy 49.352674 -63.064888)
			(xy 49.331406 -63.064888) (xy 49.321466 -63.068708) (xy 49.278798 -63.08694) (xy 49.190508 -63.115487)
			(xy 49.099725 -63.134684) (xy 49.007436 -63.144321) (xy 48.96104 -63.144908) (xy 48.914645 -63.144311)
			(xy 48.822357 -63.13467) (xy 48.731573 -63.115478) (xy 48.643279 -63.086944) (xy 48.600614 -63.068708)
			(xy 48.590674 -63.064888) (xy 48.569406 -63.064888) (xy 48.559466 -63.068708) (xy 48.516858 -63.086917)
			(xy 48.428692 -63.115438) (xy 48.338038 -63.134634) (xy 48.24588 -63.144298) (xy 48.199548 -63.144908)
			(xy 48.19904 -63.144908) (xy 48.157937 -63.14441) (xy 48.076083 -63.136828) (xy 47.995277 -63.121726)
			(xy 47.916209 -63.099233) (xy 47.839554 -63.06954) (xy 47.765966 -63.0329) (xy 47.696073 -62.989627)
			(xy 47.630471 -62.940089) (xy 47.569719 -62.884709) (xy 47.514337 -62.82396) (xy 47.464796 -62.75836)
			(xy 47.42152 -62.688469) (xy 47.384877 -62.614882) (xy 47.35518 -62.538229) (xy 47.332683 -62.459162)
			(xy 47.317577 -62.378357) (xy 47.309992 -62.296502) (xy 47.309532 -62.2554) (xy 44.5516 -62.2554)
			(xy 44.5516 -64.0842) (xy 40.64 -67.9958) (xy 40.64 -70.47621) (xy 43.222919 -70.47621) (xy 43.222919 -70.34343)
			(xy 43.230936 -70.210893) (xy 43.246941 -70.079082) (xy 43.270875 -69.948478) (xy 43.302651 -69.819557)
			(xy 43.342153 -69.69279) (xy 43.389238 -69.568639) (xy 43.443732 -69.447558) (xy 43.505437 -69.329988)
			(xy 43.574129 -69.216358) (xy 43.649556 -69.107083) (xy 43.731443 -69.002561) (xy 43.819492 -68.903174)
			(xy 43.913381 -68.809285) (xy 44.012768 -68.721236) (xy 44.117289 -68.639348) (xy 44.226564 -68.563921)
			(xy 44.340194 -68.495229) (xy 44.457764 -68.433524) (xy 44.578846 -68.379029) (xy 44.702996 -68.331945)
			(xy 44.829763 -68.292442) (xy 44.958684 -68.260666) (xy 45.089288 -68.236732) (xy 45.221099 -68.220727)
			(xy 45.353636 -68.212709) (xy 45.420026 -68.212208) (xy 45.487099 -68.212692) (xy 45.620995 -68.22087)
			(xy 45.754144 -68.237202) (xy 45.886048 -68.261625) (xy 46.016216 -68.294049) (xy 46.144164 -68.334353)
			(xy 46.269415 -68.382387) (xy 46.391503 -68.437972) (xy 46.509973 -68.500902) (xy 46.624383 -68.570941)
			(xy 46.734308 -68.647828) (xy 46.839337 -68.731278) (xy 46.939081 -68.82098) (xy 47.033167 -68.916599)
			(xy 47.121244 -69.01778) (xy 47.202986 -69.124145) (xy 47.240952 -69.17944) (xy 47.248064 -69.189854)
			(xy 47.270162 -69.201792) (xy 47.37989 -69.201792) (xy 47.401988 -69.189854) (xy 47.4091 -69.17944)
			(xy 47.447109 -69.124176) (xy 47.528852 -69.017816) (xy 47.61693 -68.91664) (xy 47.711015 -68.821025)
			(xy 47.810758 -68.731326) (xy 47.915785 -68.647879) (xy 48.025707 -68.570993) (xy 48.140114 -68.500954)
			(xy 48.25858 -68.438025) (xy 48.380663 -68.382438) (xy 48.50591 -68.334402) (xy 48.633854 -68.294094)
			(xy 48.764018 -68.261666) (xy 48.895918 -68.237237) (xy 49.029062 -68.220899) (xy 49.162955 -68.212712)
			(xy 49.230026 -68.212208) (xy 49.288881 -68.212621) (xy 49.406419 -68.218977) (xy 49.464976 -68.224908)
			(xy 49.476914 -68.226178) (xy 49.49952 -68.217542) (xy 49.571148 -68.140326) (xy 49.578006 -68.117212)
			(xy 49.57572 -68.105274) (xy 49.565604 -68.046936) (xy 49.55479 -67.929021) (xy 49.55413 -67.869816)
			(xy 49.554594 -67.818918) (xy 49.56258 -67.717436) (xy 49.578504 -67.616893) (xy 49.602267 -67.51791)
			(xy 49.633723 -67.421096) (xy 49.672679 -67.327049) (xy 49.718893 -67.236348) (xy 49.772081 -67.149553)
			(xy 49.831916 -67.067198) (xy 49.898028 -66.989793) (xy 49.970009 -66.917813) (xy 50.047416 -66.851702)
			(xy 50.129771 -66.791869) (xy 50.216567 -66.738682) (xy 50.307269 -66.692469) (xy 50.401317 -66.653516)
			(xy 50.498131 -66.622061) (xy 50.597115 -66.598299) (xy 50.697658 -66.582378) (xy 50.79914 -66.574394)
			(xy 50.850038 -66.573908) (xy 50.901718 -66.57442) (xy 51.00475 -66.582642) (xy 51.106799 -66.599048)
			(xy 51.207217 -66.623532) (xy 51.305364 -66.65594) (xy 51.400618 -66.696064) (xy 51.492371 -66.743651)
			(xy 51.580042 -66.798396) (xy 51.663071 -66.859953) (xy 51.740932 -66.92793) (xy 51.777392 -66.96456)
			(xy 51.784758 -66.97218) (xy 51.8033 -66.9798) (xy 51.896772 -66.9798) (xy 51.915314 -66.97218) (xy 51.92268 -66.96456)
			(xy 51.959141 -66.927931) (xy 52.037004 -66.859955) (xy 52.120034 -66.798397) (xy 52.207705 -66.74365)
			(xy 52.299458 -66.69606) (xy 52.39471 -66.655931) (xy 52.492857 -66.623517) (xy 52.593273 -66.599025)
			(xy 52.695322 -66.582609) (xy 52.798354 -66.574376) (xy 52.901714 -66.574376) (xy 53.004746 -66.582609)
			(xy 53.106795 -66.599025) (xy 53.207211 -66.623517) (xy 53.305358 -66.655931) (xy 53.40061 -66.69606)
			(xy 53.492363 -66.74365) (xy 53.580034 -66.798397) (xy 53.663064 -66.859955) (xy 53.740927 -66.927931)
			(xy 53.777388 -66.96456) (xy 53.784754 -66.97218) (xy 53.803296 -66.9798) (xy 53.896768 -66.9798)
			(xy 53.91531 -66.97218) (xy 53.922676 -66.96456) (xy 53.959137 -66.927931) (xy 54.037 -66.859955)
			(xy 54.12003 -66.798397) (xy 54.207701 -66.74365) (xy 54.299454 -66.69606) (xy 54.394706 -66.655931)
			(xy 54.492853 -66.623517) (xy 54.593269 -66.599025) (xy 54.695318 -66.582609) (xy 54.79835 -66.574376)
			(xy 54.90171 -66.574376) (xy 55.004742 -66.582609) (xy 55.106791 -66.599025) (xy 55.207207 -66.623517)
			(xy 55.305354 -66.655931) (xy 55.400606 -66.69606) (xy 55.492359 -66.74365) (xy 55.58003 -66.798397)
			(xy 55.66306 -66.859955) (xy 55.740923 -66.927931) (xy 55.777384 -66.96456) (xy 55.78475 -66.97218)
			(xy 55.803292 -66.9798) (xy 55.896764 -66.9798) (xy 55.915306 -66.97218) (xy 55.922672 -66.96456)
			(xy 55.959133 -66.927931) (xy 56.036996 -66.859955) (xy 56.120026 -66.798397) (xy 56.207697 -66.74365)
			(xy 56.29945 -66.69606) (xy 56.394702 -66.655931) (xy 56.492849 -66.623517) (xy 56.593265 -66.599025)
			(xy 56.695314 -66.582609) (xy 56.798346 -66.574376) (xy 56.901706 -66.574376) (xy 57.004738 -66.582609)
			(xy 57.106787 -66.599025) (xy 57.207203 -66.623517) (xy 57.30535 -66.655931) (xy 57.400602 -66.69606)
			(xy 57.492355 -66.74365) (xy 57.580026 -66.798397) (xy 57.663056 -66.859955) (xy 57.740919 -66.927931)
			(xy 57.77738 -66.96456) (xy 57.784746 -66.97218) (xy 57.803288 -66.9798) (xy 57.89676 -66.9798) (xy 57.915302 -66.97218)
			(xy 57.922668 -66.96456) (xy 57.959129 -66.927931) (xy 58.036992 -66.859955) (xy 58.120022 -66.798397)
			(xy 58.207693 -66.74365) (xy 58.299446 -66.69606) (xy 58.394698 -66.655931) (xy 58.492845 -66.623517)
			(xy 58.593261 -66.599025) (xy 58.69531 -66.582609) (xy 58.798342 -66.574376) (xy 58.901702 -66.574376)
			(xy 59.004734 -66.582609) (xy 59.106783 -66.599025) (xy 59.207199 -66.623517) (xy 59.305346 -66.655931)
			(xy 59.400598 -66.69606) (xy 59.492351 -66.74365) (xy 59.580022 -66.798397) (xy 59.663052 -66.859955)
			(xy 59.740915 -66.927931) (xy 59.777376 -66.96456) (xy 59.784742 -66.97218) (xy 59.803284 -66.9798)
			(xy 59.896756 -66.9798) (xy 59.915298 -66.97218) (xy 59.922664 -66.96456) (xy 59.959125 -66.927931)
			(xy 60.036988 -66.859955) (xy 60.120018 -66.798397) (xy 60.207689 -66.74365) (xy 60.299442 -66.69606)
			(xy 60.394694 -66.655931) (xy 60.492841 -66.623517) (xy 60.593257 -66.599025) (xy 60.695306 -66.582609)
			(xy 60.798338 -66.574376) (xy 60.901698 -66.574376) (xy 61.00473 -66.582609) (xy 61.106779 -66.599025)
			(xy 61.207195 -66.623517) (xy 61.305342 -66.655931) (xy 61.400594 -66.69606) (xy 61.492347 -66.74365)
			(xy 61.580018 -66.798397) (xy 61.663048 -66.859955) (xy 61.740911 -66.927931) (xy 61.777372 -66.96456)
			(xy 61.784738 -66.97218) (xy 61.80328 -66.9798) (xy 61.896752 -66.9798) (xy 61.915294 -66.97218)
			(xy 61.92266 -66.96456) (xy 61.959133 -66.927945) (xy 62.037 -66.859978) (xy 62.120032 -66.798429)
			(xy 62.207703 -66.743688) (xy 62.299455 -66.696103) (xy 62.394705 -66.655978) (xy 62.492849 -66.623565)
			(xy 62.593262 -66.599072) (xy 62.695307 -66.582654) (xy 62.798335 -66.574416) (xy 62.850014 -66.573908)
			(xy 62.900912 -66.574366) (xy 63.002394 -66.582353) (xy 63.102936 -66.598279) (xy 63.201919 -66.622044)
			(xy 63.298732 -66.653501) (xy 63.392778 -66.692458) (xy 63.483478 -66.738673) (xy 63.570273 -66.791862)
			(xy 63.652626 -66.851697) (xy 63.730032 -66.917809) (xy 63.802011 -66.98979) (xy 63.868121 -67.067197)
			(xy 63.927954 -67.149552) (xy 63.981141 -67.236348) (xy 64.027355 -67.327049) (xy 64.066309 -67.421097)
			(xy 64.097764 -67.51791) (xy 64.121527 -67.616894) (xy 64.13745 -67.717436) (xy 64.145436 -67.818918)
			(xy 64.145922 -67.869816) (xy 64.145429 -67.920307) (xy 64.137551 -68.020983) (xy 64.121861 -68.12074)
			(xy 64.098454 -68.218972) (xy 64.067471 -68.315085) (xy 64.0291 -68.408494) (xy 63.983575 -68.498633)
			(xy 63.931171 -68.584955) (xy 63.902082 -68.626228) (xy 63.892684 -68.639436) (xy 63.89243 -68.671694)
			(xy 63.96609 -68.77685) (xy 63.99657 -68.787772) (xy 64.012318 -68.783454) (xy 64.068227 -68.768224)
			(xy 64.181668 -68.744531) (xy 64.296466 -68.728667) (xy 64.412082 -68.720707) (xy 64.470026 -68.720208)
			(xy 64.528576 -68.720718) (xy 64.645394 -68.728829) (xy 64.76137 -68.745008) (xy 64.875948 -68.76918)
			(xy 64.988576 -68.801227) (xy 65.098716 -68.840996) (xy 65.205837 -68.888297) (xy 65.309426 -68.942901)
			(xy 65.408985 -69.004547) (xy 65.504036 -69.072939) (xy 65.594124 -69.147749) (xy 65.678815 -69.228617)
			(xy 65.757704 -69.315155) (xy 65.830411 -69.406949) (xy 65.896587 -69.503556) (xy 65.955915 -69.604514)
			(xy 66.008109 -69.709337) (xy 66.05292 -69.817523) (xy 66.090132 -69.928553) (xy 66.119567 -70.041892)
			(xy 66.141083 -70.156998) (xy 66.154577 -70.273317) (xy 66.159984 -70.390292) (xy 66.159533 -70.409816)
			(xy 66.589915 -70.409816) (xy 66.593942 -70.293213) (xy 66.606004 -70.177166) (xy 66.626043 -70.062228)
			(xy 66.653965 -69.948946) (xy 66.689635 -69.83786) (xy 66.732884 -69.7295) (xy 66.783507 -69.624382)
			(xy 66.84126 -69.523007) (xy 66.905871 -69.425858) (xy 66.977029 -69.333398) (xy 67.054397 -69.246067)
			(xy 67.137606 -69.164283) (xy 67.226259 -69.088434) (xy 67.319933 -69.018882) (xy 67.418183 -68.955958)
			(xy 67.52054 -68.899962) (xy 67.626516 -68.851162) (xy 67.735607 -68.80979) (xy 67.847291 -68.776042)
			(xy 67.961038 -68.75008) (xy 68.076306 -68.732027) (xy 68.192544 -68.72197) (xy 68.309198 -68.719956)
			(xy 68.425714 -68.725995) (xy 68.541536 -68.740059) (xy 68.656111 -68.762079) (xy 68.768894 -68.791952)
			(xy 68.879348 -68.829534) (xy 68.986945 -68.874648) (xy 69.091174 -68.927077) (xy 69.191537 -68.986572)
			(xy 69.287556 -69.052849) (xy 69.378774 -69.125593) (xy 69.464756 -69.204457) (xy 69.545093 -69.289065)
			(xy 69.6194 -69.379014) (xy 69.687325 -69.473875) (xy 69.748544 -69.573196) (xy 69.802764 -69.676504)
			(xy 69.849728 -69.783307) (xy 69.889211 -69.893095) (xy 69.921026 -70.005346) (xy 69.945021 -70.119524)
			(xy 69.961081 -70.235086) (xy 69.96913 -70.35148) (xy 69.969634 -70.409816) (xy 69.96913 -70.468152)
			(xy 69.968573 -70.47621) (xy 83.222839 -70.47621) (xy 83.222839 -70.34343) (xy 83.230856 -70.210893)
			(xy 83.246861 -70.079082) (xy 83.270795 -69.948478) (xy 83.302571 -69.819557) (xy 83.342073 -69.69279)
			(xy 83.389158 -69.568639) (xy 83.443652 -69.447558) (xy 83.505357 -69.329988) (xy 83.574049 -69.216358)
			(xy 83.649476 -69.107083) (xy 83.731363 -69.002561) (xy 83.819412 -68.903174) (xy 83.913301 -68.809285)
			(xy 84.012688 -68.721236) (xy 84.117209 -68.639348) (xy 84.226484 -68.563921) (xy 84.340114 -68.495229)
			(xy 84.457684 -68.433524) (xy 84.578766 -68.379029) (xy 84.702916 -68.331945) (xy 84.829683 -68.292442)
			(xy 84.958604 -68.260666) (xy 85.089208 -68.236732) (xy 85.221019 -68.220727) (xy 85.353556 -68.212709)
			(xy 85.419946 -68.212208) (xy 85.487019 -68.212676) (xy 85.620916 -68.220856) (xy 85.754065 -68.237188)
			(xy 85.885969 -68.261613) (xy 86.016137 -68.294038) (xy 86.144086 -68.334343) (xy 86.269337 -68.382378)
			(xy 86.391425 -68.437965) (xy 86.509894 -68.500895) (xy 86.624305 -68.570935) (xy 86.734229 -68.647823)
			(xy 86.839259 -68.731275) (xy 86.939002 -68.820977) (xy 87.033087 -68.916597) (xy 87.121165 -69.017778)
			(xy 87.202906 -69.124144) (xy 87.240872 -69.17944) (xy 87.247984 -69.189854) (xy 87.270082 -69.201792)
			(xy 87.37981 -69.201792) (xy 87.401908 -69.189854) (xy 87.40902 -69.17944) (xy 87.447016 -69.124166)
			(xy 87.52876 -69.017806) (xy 87.616839 -68.916631) (xy 87.710925 -68.821016) (xy 87.810668 -68.731317)
			(xy 87.915697 -68.64787) (xy 88.025619 -68.570985) (xy 88.140027 -68.500947) (xy 88.258494 -68.438018)
			(xy 88.380579 -68.382432) (xy 88.505826 -68.334396) (xy 88.633771 -68.29409) (xy 88.763936 -68.261662)
			(xy 88.895836 -68.237234) (xy 89.028981 -68.220897) (xy 89.162874 -68.212712) (xy 89.229946 -68.212208)
			(xy 89.288801 -68.212627) (xy 89.406339 -68.218979) (xy 89.464896 -68.224908) (xy 89.476834 -68.226178)
			(xy 89.49944 -68.217542) (xy 89.571068 -68.140326) (xy 89.577926 -68.117212) (xy 89.57564 -68.105274)
			(xy 89.565524 -68.046936) (xy 89.55471 -67.929021) (xy 89.55405 -67.869816) (xy 89.554607 -67.818921)
			(xy 89.562592 -67.717443) (xy 89.578514 -67.616905) (xy 89.602275 -67.517927) (xy 89.633729 -67.421117)
			(xy 89.672681 -67.327074) (xy 89.718891 -67.236377) (xy 89.772075 -67.149585) (xy 89.831905 -67.067233)
			(xy 89.898011 -66.989829) (xy 89.969986 -66.91785) (xy 90.047387 -66.851741) (xy 90.129736 -66.791907)
			(xy 90.216526 -66.73872) (xy 90.307221 -66.692505) (xy 90.401263 -66.653549) (xy 90.498071 -66.622091)
			(xy 90.597048 -66.598325) (xy 90.697586 -66.582399) (xy 90.799063 -66.574409) (xy 90.849958 -66.573908)
			(xy 90.901638 -66.574406) (xy 91.00467 -66.58263) (xy 91.10672 -66.599038) (xy 91.207138 -66.623523)
			(xy 91.305285 -66.655932) (xy 91.400539 -66.696058) (xy 91.492292 -66.743646) (xy 91.579962 -66.798393)
			(xy 91.662992 -66.859952) (xy 91.740852 -66.92793) (xy 91.777312 -66.96456) (xy 91.784678 -66.97218)
			(xy 91.80322 -66.9798) (xy 91.896692 -66.9798) (xy 91.915234 -66.97218) (xy 91.9226 -66.96456) (xy 91.959061 -66.927931)
			(xy 92.036924 -66.859955) (xy 92.119954 -66.798397) (xy 92.207625 -66.74365) (xy 92.299378 -66.69606)
			(xy 92.39463 -66.655931) (xy 92.492777 -66.623517) (xy 92.593193 -66.599025) (xy 92.695242 -66.582609)
			(xy 92.798274 -66.574376) (xy 92.901634 -66.574376) (xy 93.004666 -66.582609) (xy 93.106715 -66.599025)
			(xy 93.207131 -66.623517) (xy 93.305278 -66.655931) (xy 93.40053 -66.69606) (xy 93.492283 -66.74365)
			(xy 93.579954 -66.798397) (xy 93.662984 -66.859955) (xy 93.740847 -66.927931) (xy 93.777308 -66.96456)
			(xy 93.784674 -66.97218) (xy 93.803216 -66.9798) (xy 93.896688 -66.9798) (xy 93.91523 -66.97218)
			(xy 93.922596 -66.96456) (xy 93.959057 -66.927931) (xy 94.03692 -66.859955) (xy 94.11995 -66.798397)
			(xy 94.207621 -66.74365) (xy 94.299374 -66.69606) (xy 94.394626 -66.655931) (xy 94.492773 -66.623517)
			(xy 94.593189 -66.599025) (xy 94.695238 -66.582609) (xy 94.79827 -66.574376) (xy 94.90163 -66.574376)
			(xy 95.004662 -66.582609) (xy 95.106711 -66.599025) (xy 95.207127 -66.623517) (xy 95.305274 -66.655931)
			(xy 95.400526 -66.69606) (xy 95.492279 -66.74365) (xy 95.57995 -66.798397) (xy 95.66298 -66.859955)
			(xy 95.740843 -66.927931) (xy 95.777304 -66.96456) (xy 95.78467 -66.97218) (xy 95.803212 -66.9798)
			(xy 95.896684 -66.9798) (xy 95.915226 -66.97218) (xy 95.922592 -66.96456) (xy 95.959053 -66.927931)
			(xy 96.036916 -66.859955) (xy 96.119946 -66.798397) (xy 96.207617 -66.74365) (xy 96.29937 -66.69606)
			(xy 96.394622 -66.655931) (xy 96.492769 -66.623517) (xy 96.593185 -66.599025) (xy 96.695234 -66.582609)
			(xy 96.798266 -66.574376) (xy 96.901626 -66.574376) (xy 97.004658 -66.582609) (xy 97.106707 -66.599025)
			(xy 97.207123 -66.623517) (xy 97.30527 -66.655931) (xy 97.400522 -66.69606) (xy 97.492275 -66.74365)
			(xy 97.579946 -66.798397) (xy 97.662976 -66.859955) (xy 97.740839 -66.927931) (xy 97.7773 -66.96456)
			(xy 97.784666 -66.97218) (xy 97.803208 -66.9798) (xy 97.89668 -66.9798) (xy 97.915222 -66.97218)
			(xy 97.922588 -66.96456) (xy 97.959049 -66.927931) (xy 98.036912 -66.859955) (xy 98.119942 -66.798397)
			(xy 98.207613 -66.74365) (xy 98.299366 -66.69606) (xy 98.394618 -66.655931) (xy 98.492765 -66.623517)
			(xy 98.593181 -66.599025) (xy 98.69523 -66.582609) (xy 98.798262 -66.574376) (xy 98.901622 -66.574376)
			(xy 99.004654 -66.582609) (xy 99.106703 -66.599025) (xy 99.207119 -66.623517) (xy 99.305266 -66.655931)
			(xy 99.400518 -66.69606) (xy 99.492271 -66.74365) (xy 99.579942 -66.798397) (xy 99.662972 -66.859955)
			(xy 99.740835 -66.927931) (xy 99.777296 -66.96456) (xy 99.784662 -66.97218) (xy 99.803204 -66.9798)
			(xy 99.896676 -66.9798) (xy 99.915218 -66.97218) (xy 99.922584 -66.96456) (xy 99.959045 -66.927931)
			(xy 100.036908 -66.859955) (xy 100.119938 -66.798397) (xy 100.207609 -66.74365) (xy 100.299362 -66.69606)
			(xy 100.394614 -66.655931) (xy 100.492761 -66.623517) (xy 100.593177 -66.599025) (xy 100.695226 -66.582609)
			(xy 100.798258 -66.574376) (xy 100.901618 -66.574376) (xy 101.00465 -66.582609) (xy 101.106699 -66.599025)
			(xy 101.207115 -66.623517) (xy 101.305262 -66.655931) (xy 101.400514 -66.69606) (xy 101.492267 -66.74365)
			(xy 101.579938 -66.798397) (xy 101.662968 -66.859955) (xy 101.740831 -66.927931) (xy 101.777292 -66.96456)
			(xy 101.784658 -66.97218) (xy 101.8032 -66.9798) (xy 101.896672 -66.9798) (xy 101.915214 -66.97218)
			(xy 101.92258 -66.96456) (xy 101.959044 -66.927935) (xy 102.036912 -66.859969) (xy 102.119945 -66.79842)
			(xy 102.207617 -66.74368) (xy 102.29937 -66.696096) (xy 102.394622 -66.655971) (xy 102.492766 -66.62356)
			(xy 102.59318 -66.599068) (xy 102.695226 -66.582652) (xy 102.798255 -66.574415) (xy 102.849934 -66.573908)
			(xy 102.900832 -66.574359) (xy 103.002313 -66.582348) (xy 103.102854 -66.598275) (xy 103.201837 -66.622041)
			(xy 103.298649 -66.6535) (xy 103.392694 -66.692457) (xy 103.483394 -66.738673) (xy 103.570187 -66.791863)
			(xy 103.65254 -66.851698) (xy 103.729944 -66.917811) (xy 103.801923 -66.989792) (xy 103.868032 -67.067199)
			(xy 103.927865 -67.149554) (xy 103.981051 -67.23635) (xy 104.027264 -67.327051) (xy 104.066218 -67.421098)
			(xy 104.097673 -67.517912) (xy 104.121435 -67.616895) (xy 104.137358 -67.717437) (xy 104.145343 -67.818918)
			(xy 104.145842 -67.869816) (xy 104.145345 -67.920307) (xy 104.137468 -68.020983) (xy 104.121778 -68.120739)
			(xy 104.098371 -68.218972) (xy 104.067388 -68.315084) (xy 104.029018 -68.408494) (xy 103.983494 -68.498633)
			(xy 103.931091 -68.584955) (xy 103.902002 -68.626228) (xy 103.892604 -68.639436) (xy 103.89235 -68.671694)
			(xy 103.96601 -68.77685) (xy 103.99649 -68.787772) (xy 104.012238 -68.783454) (xy 104.068146 -68.76822)
			(xy 104.181588 -68.744528) (xy 104.296386 -68.728665) (xy 104.412002 -68.720707) (xy 104.469946 -68.720208)
			(xy 104.528495 -68.720739) (xy 104.645311 -68.728851) (xy 104.761286 -68.745031) (xy 104.875861 -68.769204)
			(xy 104.988488 -68.801252) (xy 105.098625 -68.841022) (xy 105.205744 -68.888323) (xy 105.309331 -68.942927)
			(xy 105.408888 -69.004574) (xy 105.503938 -69.072966) (xy 105.594023 -69.147775) (xy 105.678713 -69.228643)
			(xy 105.757599 -69.315181) (xy 105.830304 -69.406973) (xy 105.896478 -69.50358) (xy 105.955804 -69.604537)
			(xy 106.007997 -69.709359) (xy 106.052807 -69.817544) (xy 106.090017 -69.928573) (xy 106.119451 -70.041911)
			(xy 106.140966 -70.157015) (xy 106.154458 -70.273333) (xy 106.159865 -70.390306) (xy 106.159414 -70.409816)
			(xy 106.589835 -70.409816) (xy 106.593862 -70.293213) (xy 106.605924 -70.177166) (xy 106.625963 -70.062228)
			(xy 106.653885 -69.948946) (xy 106.689555 -69.83786) (xy 106.732804 -69.7295) (xy 106.783427 -69.624382)
			(xy 106.84118 -69.523007) (xy 106.905791 -69.425858) (xy 106.976949 -69.333398) (xy 107.054317 -69.246067)
			(xy 107.137526 -69.164283) (xy 107.226179 -69.088434) (xy 107.319853 -69.018882) (xy 107.418103 -68.955958)
			(xy 107.52046 -68.899962) (xy 107.626436 -68.851162) (xy 107.735527 -68.80979) (xy 107.847211 -68.776042)
			(xy 107.960958 -68.75008) (xy 108.076226 -68.732027) (xy 108.192464 -68.72197) (xy 108.309118 -68.719956)
			(xy 108.425634 -68.725995) (xy 108.541456 -68.740059) (xy 108.656031 -68.762079) (xy 108.768814 -68.791952)
			(xy 108.879268 -68.829534) (xy 108.986865 -68.874648) (xy 109.091094 -68.927077) (xy 109.191457 -68.986572)
			(xy 109.287476 -69.052849) (xy 109.378694 -69.125593) (xy 109.464676 -69.204457) (xy 109.545013 -69.289065)
			(xy 109.61932 -69.379014) (xy 109.687245 -69.473875) (xy 109.748464 -69.573196) (xy 109.802684 -69.676504)
			(xy 109.849648 -69.783307) (xy 109.889131 -69.893095) (xy 109.920946 -70.005346) (xy 109.944941 -70.119524)
			(xy 109.961001 -70.235086) (xy 109.96905 -70.35148) (xy 109.969554 -70.409816) (xy 109.96905 -70.468152)
			(xy 109.961001 -70.584546) (xy 109.944941 -70.700108) (xy 109.920946 -70.814286) (xy 109.889131 -70.926537)
			(xy 109.849648 -71.036325) (xy 109.802684 -71.143128) (xy 109.748464 -71.246436) (xy 109.687245 -71.345757)
			(xy 109.61932 -71.440618) (xy 109.545013 -71.530567) (xy 109.464676 -71.615175) (xy 109.378694 -71.694039)
			(xy 109.287476 -71.766783) (xy 109.191457 -71.83306) (xy 109.091094 -71.892555) (xy 108.986865 -71.944984)
			(xy 108.879268 -71.990098) (xy 108.768814 -72.02768) (xy 108.656031 -72.057553) (xy 108.541456 -72.079573)
			(xy 108.425634 -72.093637) (xy 108.309118 -72.099676) (xy 108.192464 -72.097662) (xy 108.076226 -72.087605)
			(xy 107.960958 -72.069552) (xy 107.847211 -72.04359) (xy 107.735527 -72.009842) (xy 107.626436 -71.96847)
			(xy 107.52046 -71.91967) (xy 107.418103 -71.863674) (xy 107.319853 -71.80075) (xy 107.226179 -71.731198)
			(xy 107.137526 -71.655349) (xy 107.054317 -71.573565) (xy 106.976949 -71.486234) (xy 106.905791 -71.393774)
			(xy 106.84118 -71.296625) (xy 106.783427 -71.19525) (xy 106.732804 -71.090132) (xy 106.689555 -70.981772)
			(xy 106.653885 -70.870686) (xy 106.625963 -70.757404) (xy 106.605924 -70.642466) (xy 106.593862 -70.526419)
			(xy 106.589835 -70.409816) (xy 106.159414 -70.409816) (xy 106.157158 -70.507372) (xy 106.146352 -70.62397)
			(xy 106.127498 -70.73954) (xy 106.100687 -70.853527) (xy 106.066047 -70.965384) (xy 106.023746 -71.074574)
			(xy 105.973984 -71.180572) (xy 105.917003 -71.282871) (xy 105.853075 -71.380978) (xy 105.782507 -71.474424)
			(xy 105.705638 -71.562758) (xy 105.622836 -71.645558) (xy 105.5345 -71.722426) (xy 105.441054 -71.792992)
			(xy 105.342945 -71.856919) (xy 105.240646 -71.913898) (xy 105.134646 -71.963657) (xy 105.025456 -72.005957)
			(xy 104.913598 -72.040595) (xy 104.799611 -72.067404) (xy 104.68404 -72.086256) (xy 104.567442 -72.09706)
			(xy 104.450376 -72.099764) (xy 104.333403 -72.094356) (xy 104.217085 -72.080861) (xy 104.101981 -72.059344)
			(xy 103.988644 -72.029909) (xy 103.877616 -71.992696) (xy 103.769432 -71.947885) (xy 103.66461 -71.89569)
			(xy 103.563655 -71.836362) (xy 103.467049 -71.770186) (xy 103.375258 -71.69748) (xy 103.288721 -71.618592)
			(xy 103.207855 -71.533901) (xy 103.133047 -71.443814) (xy 103.064657 -71.348763) (xy 103.003012 -71.249205)
			(xy 102.94841 -71.145617) (xy 102.901111 -71.038497) (xy 102.861343 -70.928359) (xy 102.829297 -70.815732)
			(xy 102.805126 -70.701156) (xy 102.788947 -70.585181) (xy 102.780838 -70.468365) (xy 102.780338 -70.409816)
			(xy 102.780879 -70.34986) (xy 102.789382 -70.23025) (xy 102.806345 -70.111544) (xy 102.831683 -69.99434)
			(xy 102.865268 -69.879228) (xy 102.906932 -69.766787) (xy 102.956465 -69.657584) (xy 103.013617 -69.552169)
			(xy 103.078101 -69.451071) (xy 103.149592 -69.354801) (xy 103.188262 -69.30898) (xy 103.19893 -69.296534)
			(xy 103.201724 -69.264276) (xy 103.137462 -69.153278) (xy 103.108252 -69.139816) (xy 103.09225 -69.142864)
			(xy 103.032244 -69.153572) (xy 102.910884 -69.165024) (xy 102.849934 -69.165724) (xy 102.798254 -69.165221)
			(xy 102.695222 -69.156997) (xy 102.593173 -69.14059) (xy 102.492755 -69.116104) (xy 102.394608 -69.083695)
			(xy 102.299355 -69.04357) (xy 102.207601 -68.995982) (xy 102.119931 -68.941236) (xy 102.036901 -68.879679)
			(xy 101.95904 -68.811702) (xy 101.92258 -68.775072) (xy 101.915214 -68.767452) (xy 101.896672 -68.759832)
			(xy 101.8032 -68.759832) (xy 101.784658 -68.767452) (xy 101.777292 -68.775072) (xy 101.740831 -68.811701)
			(xy 101.662968 -68.879677) (xy 101.579938 -68.941235) (xy 101.492267 -68.995982) (xy 101.400514 -69.043572)
			(xy 101.305262 -69.083701) (xy 101.207115 -69.116115) (xy 101.106699 -69.140607) (xy 101.00465 -69.157023)
			(xy 100.901618 -69.165256) (xy 100.798258 -69.165256) (xy 100.695226 -69.157023) (xy 100.593177 -69.140607)
			(xy 100.492761 -69.116115) (xy 100.394614 -69.083701) (xy 100.299362 -69.043572) (xy 100.207609 -68.995982)
			(xy 100.119938 -68.941235) (xy 100.036908 -68.879677) (xy 99.959045 -68.811701) (xy 99.922584 -68.775072)
			(xy 99.915218 -68.767452) (xy 99.896676 -68.759832) (xy 99.803204 -68.759832) (xy 99.784662 -68.767452)
			(xy 99.777296 -68.775072) (xy 99.740835 -68.811701) (xy 99.662972 -68.879677) (xy 99.579942 -68.941235)
			(xy 99.492271 -68.995982) (xy 99.400518 -69.043572) (xy 99.305266 -69.083701) (xy 99.207119 -69.116115)
			(xy 99.106703 -69.140607) (xy 99.004654 -69.157023) (xy 98.901622 -69.165256) (xy 98.798262 -69.165256)
			(xy 98.69523 -69.157023) (xy 98.593181 -69.140607) (xy 98.492765 -69.116115) (xy 98.394618 -69.083701)
			(xy 98.299366 -69.043572) (xy 98.207613 -68.995982) (xy 98.119942 -68.941235) (xy 98.036912 -68.879677)
			(xy 97.959049 -68.811701) (xy 97.922588 -68.775072) (xy 97.915222 -68.767452) (xy 97.89668 -68.759832)
			(xy 97.803208 -68.759832) (xy 97.784666 -68.767452) (xy 97.7773 -68.775072) (xy 97.740839 -68.811701)
			(xy 97.662976 -68.879677) (xy 97.579946 -68.941235) (xy 97.492275 -68.995982) (xy 97.400522 -69.043572)
			(xy 97.30527 -69.083701) (xy 97.207123 -69.116115) (xy 97.106707 -69.140607) (xy 97.004658 -69.157023)
			(xy 96.901626 -69.165256) (xy 96.798266 -69.165256) (xy 96.695234 -69.157023) (xy 96.593185 -69.140607)
			(xy 96.492769 -69.116115) (xy 96.394622 -69.083701) (xy 96.29937 -69.043572) (xy 96.207617 -68.995982)
			(xy 96.119946 -68.941235) (xy 96.036916 -68.879677) (xy 95.959053 -68.811701) (xy 95.922592 -68.775072)
			(xy 95.915226 -68.767452) (xy 95.896684 -68.759832) (xy 95.803212 -68.759832) (xy 95.78467 -68.767452)
			(xy 95.777304 -68.775072) (xy 95.740843 -68.811701) (xy 95.66298 -68.879677) (xy 95.57995 -68.941235)
			(xy 95.492279 -68.995982) (xy 95.400526 -69.043572) (xy 95.305274 -69.083701) (xy 95.207127 -69.116115)
			(xy 95.106711 -69.140607) (xy 95.004662 -69.157023) (xy 94.90163 -69.165256) (xy 94.79827 -69.165256)
			(xy 94.695238 -69.157023) (xy 94.593189 -69.140607) (xy 94.492773 -69.116115) (xy 94.394626 -69.083701)
			(xy 94.299374 -69.043572) (xy 94.207621 -68.995982) (xy 94.11995 -68.941235) (xy 94.03692 -68.879677)
			(xy 93.959057 -68.811701) (xy 93.922596 -68.775072) (xy 93.91523 -68.767452) (xy 93.896688 -68.759832)
			(xy 93.803216 -68.759832) (xy 93.784674 -68.767452) (xy 93.777308 -68.775072) (xy 93.740847 -68.811701)
			(xy 93.662984 -68.879677) (xy 93.579954 -68.941235) (xy 93.492283 -68.995982) (xy 93.40053 -69.043572)
			(xy 93.305278 -69.083701) (xy 93.207131 -69.116115) (xy 93.106715 -69.140607) (xy 93.004666 -69.157023)
			(xy 92.901634 -69.165256) (xy 92.798274 -69.165256) (xy 92.695242 -69.157023) (xy 92.593193 -69.140607)
			(xy 92.492777 -69.116115) (xy 92.39463 -69.083701) (xy 92.299378 -69.043572) (xy 92.207625 -68.995982)
			(xy 92.119954 -68.941235) (xy 92.036924 -68.879677) (xy 91.959061 -68.811701) (xy 91.9226 -68.775072)
			(xy 91.915234 -68.767452) (xy 91.896692 -68.759832) (xy 91.80322 -68.759832) (xy 91.784678 -68.767452)
			(xy 91.777312 -68.775072) (xy 91.741715 -68.810813) (xy 91.665831 -68.877289) (xy 91.585011 -68.937668)
			(xy 91.499743 -68.991584) (xy 91.410544 -69.03871) (xy 91.317952 -69.078763) (xy 91.222528 -69.1115)
			(xy 91.173808 -69.124576) (xy 91.162124 -69.127624) (xy 91.14409 -69.143372) (xy 91.103958 -69.241162)
			(xy 91.10599 -69.265038) (xy 91.112086 -69.275452) (xy 91.145861 -69.332421) (xy 91.207288 -69.449768)
			(xy 91.261534 -69.570603) (xy 91.308401 -69.694487) (xy 91.347719 -69.82097) (xy 91.379344 -69.949592)
			(xy 91.403163 -70.079885) (xy 91.419087 -70.211377) (xy 91.427061 -70.34359) (xy 91.427554 -70.409816)
			(xy 91.427022 -70.476205) (xy 91.419004 -70.60874) (xy 91.402999 -70.74055) (xy 91.379065 -70.871152)
			(xy 91.347289 -71.000072) (xy 91.307787 -71.126837) (xy 91.260703 -71.250987) (xy 91.206209 -71.372067)
			(xy 91.144505 -71.489636) (xy 91.075814 -71.603264) (xy 91.000388 -71.712539) (xy 90.918502 -71.817059)
			(xy 90.830455 -71.916445) (xy 90.736567 -72.010334) (xy 90.637182 -72.098383) (xy 90.532663 -72.18027)
			(xy 90.42339 -72.255698) (xy 90.309762 -72.32439) (xy 90.192194 -72.386096) (xy 90.071114 -72.440591)
			(xy 89.946966 -72.487677) (xy 89.820201 -72.527181) (xy 89.691282 -72.558959) (xy 89.560679 -72.582895)
			(xy 89.42887 -72.598902) (xy 89.296335 -72.606921) (xy 89.229946 -72.607424) (xy 89.162873 -72.606948)
			(xy 89.028977 -72.598768) (xy 88.895828 -72.582436) (xy 88.763925 -72.558011) (xy 88.633756 -72.525586)
			(xy 88.505808 -72.485281) (xy 88.380557 -72.437246) (xy 88.25847 -72.38166) (xy 88.14 -72.31873)
			(xy 88.02559 -72.248691) (xy 87.915666 -72.171803) (xy 87.810636 -72.088353) (xy 87.710892 -71.998651)
			(xy 87.616806 -71.903032) (xy 87.528729 -71.801852) (xy 87.446987 -71.695487) (xy 87.40902 -71.640192)
			(xy 87.401908 -71.629778) (xy 87.37981 -71.61784) (xy 87.270082 -71.61784) (xy 87.247984 -71.629778)
			(xy 87.240872 -71.640192) (xy 87.202892 -71.695477) (xy 87.121147 -71.801836) (xy 87.033066 -71.903011)
			(xy 86.938978 -71.998625) (xy 86.839234 -72.088323) (xy 86.734204 -72.171769) (xy 86.62428 -72.248654)
			(xy 86.509871 -72.318691) (xy 86.391403 -72.381619) (xy 86.269318 -72.437204) (xy 86.144069 -72.485239)
			(xy 86.016124 -72.525545) (xy 85.885958 -72.557972) (xy 85.754057 -72.582399) (xy 85.620912 -72.598736)
			(xy 85.487018 -72.606921) (xy 85.419946 -72.607424) (xy 85.353556 -72.606931) (xy 85.221019 -72.598913)
			(xy 85.089208 -72.582908) (xy 84.958604 -72.558974) (xy 84.829683 -72.527198) (xy 84.702916 -72.487695)
			(xy 84.578766 -72.440611) (xy 84.457684 -72.386116) (xy 84.340114 -72.324411) (xy 84.226484 -72.255719)
			(xy 84.117209 -72.180292) (xy 84.012688 -72.098404) (xy 83.913301 -72.010355) (xy 83.819412 -71.916466)
			(xy 83.731363 -71.817079) (xy 83.649476 -71.712557) (xy 83.574049 -71.603282) (xy 83.505357 -71.489652)
			(xy 83.443652 -71.372082) (xy 83.389158 -71.251001) (xy 83.342073 -71.12685) (xy 83.302571 -71.000083)
			(xy 83.270795 -70.871162) (xy 83.246861 -70.740558) (xy 83.230856 -70.608747) (xy 83.222839 -70.47621)
			(xy 69.968573 -70.47621) (xy 69.961081 -70.584546) (xy 69.945021 -70.700108) (xy 69.921026 -70.814286)
			(xy 69.889211 -70.926537) (xy 69.849728 -71.036325) (xy 69.802764 -71.143128) (xy 69.748544 -71.246436)
			(xy 69.687325 -71.345757) (xy 69.6194 -71.440618) (xy 69.545093 -71.530567) (xy 69.464756 -71.615175)
			(xy 69.378774 -71.694039) (xy 69.287556 -71.766783) (xy 69.191537 -71.83306) (xy 69.091174 -71.892555)
			(xy 68.986945 -71.944984) (xy 68.879348 -71.990098) (xy 68.768894 -72.02768) (xy 68.656111 -72.057553)
			(xy 68.541536 -72.079573) (xy 68.425714 -72.093637) (xy 68.309198 -72.099676) (xy 68.192544 -72.097662)
			(xy 68.076306 -72.087605) (xy 67.961038 -72.069552) (xy 67.847291 -72.04359) (xy 67.735607 -72.009842)
			(xy 67.626516 -71.96847) (xy 67.52054 -71.91967) (xy 67.418183 -71.863674) (xy 67.319933 -71.80075)
			(xy 67.226259 -71.731198) (xy 67.137606 -71.655349) (xy 67.054397 -71.573565) (xy 66.977029 -71.486234)
			(xy 66.905871 -71.393774) (xy 66.84126 -71.296625) (xy 66.783507 -71.19525) (xy 66.732884 -71.090132)
			(xy 66.689635 -70.981772) (xy 66.653965 -70.870686) (xy 66.626043 -70.757404) (xy 66.606004 -70.642466)
			(xy 66.593942 -70.526419) (xy 66.589915 -70.409816) (xy 66.159533 -70.409816) (xy 66.157279 -70.50736)
			(xy 66.146474 -70.62396) (xy 66.12762 -70.739532) (xy 66.10081 -70.85352) (xy 66.06617 -70.965379)
			(xy 66.023869 -71.074571) (xy 65.974107 -71.180571) (xy 65.917126 -71.282872) (xy 65.853197 -71.380981)
			(xy 65.782629 -71.474428) (xy 65.705759 -71.562764) (xy 65.622957 -71.645566) (xy 65.53462 -71.722435)
			(xy 65.441173 -71.793003) (xy 65.343063 -71.856931) (xy 65.240763 -71.913912) (xy 65.134762 -71.963672)
			(xy 65.02557 -72.005974) (xy 64.913711 -72.040612) (xy 64.799722 -72.067422) (xy 64.68415 -72.086275)
			(xy 64.56755 -72.097079) (xy 64.450482 -72.099784) (xy 64.333508 -72.094376) (xy 64.217188 -72.080882)
			(xy 64.102083 -72.059365) (xy 63.988743 -72.02993) (xy 63.877714 -71.992717) (xy 63.769528 -71.947905)
			(xy 63.664705 -71.89571) (xy 63.563748 -71.836381) (xy 63.467141 -71.770205) (xy 63.375348 -71.697497)
			(xy 63.28881 -71.618608) (xy 63.207942 -71.533917) (xy 63.133133 -71.443828) (xy 63.064742 -71.348777)
			(xy 63.003096 -71.249217) (xy 62.948492 -71.145628) (xy 62.901193 -71.038506) (xy 62.861424 -70.928367)
			(xy 62.829377 -70.815738) (xy 62.805207 -70.70116) (xy 62.789028 -70.585184) (xy 62.780918 -70.468366)
			(xy 62.780418 -70.409816) (xy 62.780964 -70.34986) (xy 62.789466 -70.230251) (xy 62.806429 -70.111545)
			(xy 62.831767 -69.994341) (xy 62.865352 -69.879229) (xy 62.907016 -69.766788) (xy 62.956548 -69.657585)
			(xy 63.013699 -69.552169) (xy 63.078182 -69.451072) (xy 63.149672 -69.354802) (xy 63.188342 -69.30898)
			(xy 63.19901 -69.296534) (xy 63.201804 -69.264276) (xy 63.137542 -69.153278) (xy 63.108332 -69.139816)
			(xy 63.09233 -69.142864) (xy 63.032325 -69.153575) (xy 62.910964 -69.165024) (xy 62.850014 -69.165724)
			(xy 62.798334 -69.165235) (xy 62.695301 -69.157009) (xy 62.593252 -69.1406) (xy 62.492834 -69.116113)
			(xy 62.394687 -69.083702) (xy 62.299433 -69.043575) (xy 62.20768 -68.995987) (xy 62.12001 -68.941239)
			(xy 62.036981 -68.879681) (xy 61.95912 -68.811702) (xy 61.92266 -68.775072) (xy 61.915294 -68.767452)
			(xy 61.896752 -68.759832) (xy 61.80328 -68.759832) (xy 61.784738 -68.767452) (xy 61.777372 -68.775072)
			(xy 61.740911 -68.811701) (xy 61.663048 -68.879677) (xy 61.580018 -68.941235) (xy 61.492347 -68.995982)
			(xy 61.400594 -69.043572) (xy 61.305342 -69.083701) (xy 61.207195 -69.116115) (xy 61.106779 -69.140607)
			(xy 61.00473 -69.157023) (xy 60.901698 -69.165256) (xy 60.798338 -69.165256) (xy 60.695306 -69.157023)
			(xy 60.593257 -69.140607) (xy 60.492841 -69.116115) (xy 60.394694 -69.083701) (xy 60.299442 -69.043572)
			(xy 60.207689 -68.995982) (xy 60.120018 -68.941235) (xy 60.036988 -68.879677) (xy 59.959125 -68.811701)
			(xy 59.922664 -68.775072) (xy 59.915298 -68.767452) (xy 59.896756 -68.759832) (xy 59.803284 -68.759832)
			(xy 59.784742 -68.767452) (xy 59.777376 -68.775072) (xy 59.740915 -68.811701) (xy 59.663052 -68.879677)
			(xy 59.580022 -68.941235) (xy 59.492351 -68.995982) (xy 59.400598 -69.043572) (xy 59.305346 -69.083701)
			(xy 59.207199 -69.116115) (xy 59.106783 -69.140607) (xy 59.004734 -69.157023) (xy 58.901702 -69.165256)
			(xy 58.798342 -69.165256) (xy 58.69531 -69.157023) (xy 58.593261 -69.140607) (xy 58.492845 -69.116115)
			(xy 58.394698 -69.083701) (xy 58.299446 -69.043572) (xy 58.207693 -68.995982) (xy 58.120022 -68.941235)
			(xy 58.036992 -68.879677) (xy 57.959129 -68.811701) (xy 57.922668 -68.775072) (xy 57.915302 -68.767452)
			(xy 57.89676 -68.759832) (xy 57.803288 -68.759832) (xy 57.784746 -68.767452) (xy 57.77738 -68.775072)
			(xy 57.740919 -68.811701) (xy 57.663056 -68.879677) (xy 57.580026 -68.941235) (xy 57.492355 -68.995982)
			(xy 57.400602 -69.043572) (xy 57.30535 -69.083701) (xy 57.207203 -69.116115) (xy 57.106787 -69.140607)
			(xy 57.004738 -69.157023) (xy 56.901706 -69.165256) (xy 56.798346 -69.165256) (xy 56.695314 -69.157023)
			(xy 56.593265 -69.140607) (xy 56.492849 -69.116115) (xy 56.394702 -69.083701) (xy 56.29945 -69.043572)
			(xy 56.207697 -68.995982) (xy 56.120026 -68.941235) (xy 56.036996 -68.879677) (xy 55.959133 -68.811701)
			(xy 55.922672 -68.775072) (xy 55.915306 -68.767452) (xy 55.896764 -68.759832) (xy 55.803292 -68.759832)
			(xy 55.78475 -68.767452) (xy 55.777384 -68.775072) (xy 55.740923 -68.811701) (xy 55.66306 -68.879677)
			(xy 55.58003 -68.941235) (xy 55.492359 -68.995982) (xy 55.400606 -69.043572) (xy 55.305354 -69.083701)
			(xy 55.207207 -69.116115) (xy 55.106791 -69.140607) (xy 55.004742 -69.157023) (xy 54.90171 -69.165256)
			(xy 54.79835 -69.165256) (xy 54.695318 -69.157023) (xy 54.593269 -69.140607) (xy 54.492853 -69.116115)
			(xy 54.394706 -69.083701) (xy 54.299454 -69.043572) (xy 54.207701 -68.995982) (xy 54.12003 -68.941235)
			(xy 54.037 -68.879677) (xy 53.959137 -68.811701) (xy 53.922676 -68.775072) (xy 53.91531 -68.767452)
			(xy 53.896768 -68.759832) (xy 53.803296 -68.759832) (xy 53.784754 -68.767452) (xy 53.777388 -68.775072)
			(xy 53.740927 -68.811701) (xy 53.663064 -68.879677) (xy 53.580034 -68.941235) (xy 53.492363 -68.995982)
			(xy 53.40061 -69.043572) (xy 53.305358 -69.083701) (xy 53.207211 -69.116115) (xy 53.106795 -69.140607)
			(xy 53.004746 -69.157023) (xy 52.901714 -69.165256) (xy 52.798354 -69.165256) (xy 52.695322 -69.157023)
			(xy 52.593273 -69.140607) (xy 52.492857 -69.116115) (xy 52.39471 -69.083701) (xy 52.299458 -69.043572)
			(xy 52.207705 -68.995982) (xy 52.120034 -68.941235) (xy 52.037004 -68.879677) (xy 51.959141 -68.811701)
			(xy 51.92268 -68.775072) (xy 51.915314 -68.767452) (xy 51.896772 -68.759832) (xy 51.8033 -68.759832)
			(xy 51.784758 -68.767452) (xy 51.777392 -68.775072) (xy 51.741801 -68.810819) (xy 51.665916 -68.877295)
			(xy 51.585095 -68.937673) (xy 51.499826 -68.991588) (xy 51.410626 -69.038713) (xy 51.318033 -69.078765)
			(xy 51.222608 -69.1115) (xy 51.173888 -69.124576) (xy 51.162204 -69.127624) (xy 51.14417 -69.143372)
			(xy 51.104038 -69.241162) (xy 51.10607 -69.265038) (xy 51.112166 -69.275452) (xy 51.145939 -69.332422)
			(xy 51.207367 -69.449769) (xy 51.261613 -69.570604) (xy 51.30848 -69.694488) (xy 51.347798 -69.82097)
			(xy 51.379424 -69.949592) (xy 51.403242 -70.079885) (xy 51.419167 -70.211377) (xy 51.427141 -70.34359)
			(xy 51.427634 -70.409816) (xy 51.427122 -70.476205) (xy 51.419104 -70.608741) (xy 51.403099 -70.740552)
			(xy 51.379164 -70.871155) (xy 51.347388 -71.000075) (xy 51.307885 -71.126841) (xy 51.260801 -71.250991)
			(xy 51.206307 -71.372072) (xy 51.144601 -71.489641) (xy 51.07591 -71.603271) (xy 51.000483 -71.712545)
			(xy 50.918596 -71.817066) (xy 50.830548 -71.916452) (xy 50.73666 -72.010341) (xy 50.637274 -72.09839)
			(xy 50.532753 -72.180277) (xy 50.423479 -72.255705) (xy 50.30985 -72.324396) (xy 50.192281 -72.386102)
			(xy 50.071201 -72.440597) (xy 49.947051 -72.487682) (xy 49.820285 -72.527185) (xy 49.691365 -72.558962)
			(xy 49.560762 -72.582897) (xy 49.428951 -72.598903) (xy 49.296415 -72.606922) (xy 49.230026 -72.607424)
			(xy 49.162953 -72.606964) (xy 49.029056 -72.598783) (xy 48.895908 -72.582449) (xy 48.764003 -72.558024)
			(xy 48.633835 -72.525597) (xy 48.505887 -72.485291) (xy 48.380636 -72.437255) (xy 48.258548 -72.381668)
			(xy 48.140079 -72.318737) (xy 48.025669 -72.248697) (xy 47.915744 -72.171808) (xy 47.810715 -72.088357)
			(xy 47.710971 -71.998654) (xy 47.616886 -71.903034) (xy 47.528808 -71.801853) (xy 47.447067 -71.695488)
			(xy 47.4091 -71.640192) (xy 47.401988 -71.629778) (xy 47.37989 -71.61784) (xy 47.270162 -71.61784)
			(xy 47.248064 -71.629778) (xy 47.240952 -71.640192) (xy 47.202985 -71.695486) (xy 47.121239 -71.801845)
			(xy 47.033158 -71.90302) (xy 46.939069 -71.998635) (xy 46.839323 -72.088332) (xy 46.734293 -72.171778)
			(xy 46.624368 -72.248662) (xy 46.509958 -72.318699) (xy 46.391489 -72.381626) (xy 46.269403 -72.43721)
			(xy 46.144153 -72.485245) (xy 46.016207 -72.52555) (xy 45.886041 -72.557976) (xy 45.754139 -72.582402)
			(xy 45.620993 -72.598738) (xy 45.487098 -72.606921) (xy 45.420026 -72.607424) (xy 45.353636 -72.606931)
			(xy 45.221099 -72.598913) (xy 45.089288 -72.582908) (xy 44.958684 -72.558974) (xy 44.829763 -72.527198)
			(xy 44.702996 -72.487695) (xy 44.578846 -72.440611) (xy 44.457764 -72.386116) (xy 44.340194 -72.324411)
			(xy 44.226564 -72.255719) (xy 44.117289 -72.180292) (xy 44.012768 -72.098404) (xy 43.913381 -72.010355)
			(xy 43.819492 -71.916466) (xy 43.731443 -71.817079) (xy 43.649556 -71.712557) (xy 43.574129 -71.603282)
			(xy 43.505437 -71.489652) (xy 43.443732 -71.372082) (xy 43.389238 -71.251001) (xy 43.342153 -71.12685)
			(xy 43.302651 -71.000083) (xy 43.270875 -70.871162) (xy 43.246941 -70.740558) (xy 43.230936 -70.608747)
			(xy 43.222919 -70.47621) (xy 40.64 -70.47621) (xy 40.64 -72.394826) (xy 40.640542 -72.404811) (xy 40.648262 -72.423237)
			(xy 40.654986 -72.43064) (xy 41.899332 -73.674986) (xy 41.906678 -73.681793) (xy 41.925141 -73.689516)
			(xy 41.935146 -73.689972)
		)
		(stroke
			(width 0)
			(type solid)
		)
		(fill yes)
		(layer "In7.Cu")
		(net "P12V_BRICK")
	)
	(gr_poly
		(pts
			(arc
				(start 298.302172 -132.452364)
				(mid 298.321695 -132.448463)
				(end 298.33824 -132.437378)
			)
			(arc
				(start 299.240448 -131.53517)
				(mid 299.251559 -131.518636)
				(end 299.255434 -131.499102)
			)
			(xy 299.255434 -122.167396) (xy 299.252894 -122.156474)
			(arc
				(start 299.250354 -122.15114)
				(mid 299.221372 -122.069537)
				(end 299.211492 -121.9835)
			)
			(arc
				(start 299.211492 -121.9835)
				(mid 299.221323 -121.897451)
				(end 299.250354 -121.81586)
			)
			(xy 299.252894 -121.810526) (xy 299.255434 -121.799604) (xy 299.255434 -121.278396) (xy 299.252894 -121.267474)
			(arc
				(start 299.250354 -121.26214)
				(mid 299.221372 -121.180537)
				(end 299.211492 -121.0945)
			)
			(arc
				(start 299.211492 -121.0945)
				(mid 299.221323 -121.008451)
				(end 299.250354 -120.92686)
			)
			(xy 299.252894 -120.921526) (xy 299.255434 -120.910604) (xy 299.255434 -120.389396) (xy 299.252894 -120.378474)
			(arc
				(start 299.250354 -120.37314)
				(mid 299.221372 -120.291537)
				(end 299.211492 -120.2055)
			)
			(arc
				(start 299.211492 -120.2055)
				(mid 299.221323 -120.119451)
				(end 299.250354 -120.03786)
			)
			(xy 299.252894 -120.032526) (xy 299.255434 -120.021604) (xy 299.255434 -119.500396) (xy 299.252894 -119.489474)
			(arc
				(start 299.250354 -119.48414)
				(mid 299.221372 -119.402537)
				(end 299.211492 -119.3165)
			)
			(arc
				(start 299.211492 -119.3165)
				(mid 299.221323 -119.230451)
				(end 299.250354 -119.14886)
			)
			(xy 299.252894 -119.143526) (xy 299.255434 -119.132604)
			(arc
				(start 299.255434 -98.091244)
				(mid 299.251533 -98.071721)
				(end 299.240448 -98.055176)
			)
			(arc
				(start 298.075858 -96.890586)
				(mid 298.059324 -96.879475)
				(end 298.03979 -96.8756)
			)
			(arc
				(start 279.923494 -96.8756)
				(mid 279.903971 -96.879501)
				(end 279.887426 -96.890586)
			)
			(arc
				(start 278.722836 -98.055176)
				(mid 278.711725 -98.07171)
				(end 278.70785 -98.091244)
			)
			(arc
				(start 278.70785 -131.362958)
				(mid 278.711751 -131.382481)
				(end 278.722836 -131.399026)
			)
			(arc
				(start 279.761188 -132.437378)
				(mid 279.777722 -132.448489)
				(end 279.797256 -132.452364)
			)
		)
		(stroke
			(width 0)
			(type solid)
		)
		(fill yes)
		(layer "In8.Cu")
		(net "P52V_HS1_DRAIN_1")
	)
	(gr_poly
		(pts
			(arc
				(start 298.03979 -95.8596)
				(mid 298.059313 -95.855699)
				(end 298.075858 -95.844614)
			)
			(arc
				(start 299.240448 -94.680024)
				(mid 299.251559 -94.66349)
				(end 299.255434 -94.643956)
			)
			(arc
				(start 299.255434 -86.018878)
				(mid 299.25339 -86.004863)
				(end 299.24756 -85.991954)
			)
			(arc
				(start 299.24756 -85.991954)
				(mid 299.203848 -85.894376)
				(end 299.188886 -85.7885)
			)
			(arc
				(start 299.188886 -85.7885)
				(mid 299.203802 -85.682611)
				(end 299.24756 -85.585046)
			)
			(arc
				(start 299.24756 -85.585046)
				(mid 299.253395 -85.572139)
				(end 299.255434 -85.558122)
			)
			(arc
				(start 299.255434 -85.129878)
				(mid 299.25339 -85.115863)
				(end 299.24756 -85.102954)
			)
			(arc
				(start 299.24756 -85.102954)
				(mid 299.203848 -85.005376)
				(end 299.188886 -84.8995)
			)
			(arc
				(start 299.188886 -84.8995)
				(mid 299.203802 -84.793611)
				(end 299.24756 -84.696046)
			)
			(arc
				(start 299.24756 -84.696046)
				(mid 299.253395 -84.683139)
				(end 299.255434 -84.669122)
			)
			(arc
				(start 299.255434 -84.240878)
				(mid 299.25339 -84.226863)
				(end 299.24756 -84.213954)
			)
			(arc
				(start 299.24756 -84.213954)
				(mid 299.203848 -84.116376)
				(end 299.188886 -84.0105)
			)
			(arc
				(start 299.188886 -84.0105)
				(mid 299.203802 -83.904611)
				(end 299.24756 -83.807046)
			)
			(arc
				(start 299.24756 -83.807046)
				(mid 299.253395 -83.794139)
				(end 299.255434 -83.780122)
			)
			(arc
				(start 299.255434 -83.351878)
				(mid 299.25339 -83.337863)
				(end 299.24756 -83.324954)
			)
			(arc
				(start 299.24756 -83.324954)
				(mid 299.203848 -83.227376)
				(end 299.188886 -83.1215)
			)
			(arc
				(start 299.188886 -83.1215)
				(mid 299.203802 -83.015611)
				(end 299.24756 -82.918046)
			)
			(arc
				(start 299.24756 -82.918046)
				(mid 299.253395 -82.905139)
				(end 299.255434 -82.891122)
			)
			(xy 299.255434 -78.790546)
			(arc
				(start 299.254672 -78.786482)
				(mid 299.251029 -78.755972)
				(end 299.249846 -78.725268)
			)
			(arc
				(start 299.249846 -78.725268)
				(mid 299.251022 -78.694563)
				(end 299.254672 -78.664054)
			)
			(xy 299.255434 -78.65999) (xy 299.255434 -77.774546)
			(arc
				(start 299.254672 -77.770482)
				(mid 299.251029 -77.739972)
				(end 299.249846 -77.709268)
			)
			(arc
				(start 299.249846 -77.709268)
				(mid 299.251022 -77.678563)
				(end 299.254672 -77.648054)
			)
			(xy 299.255434 -77.64399)
			(arc
				(start 299.255434 -61.186822)
				(mid 299.251533 -61.167299)
				(end 299.240448 -61.150754)
			)
			(arc
				(start 298.329858 -60.240164)
				(mid 298.313324 -60.229053)
				(end 298.29379 -60.225178)
			)
			(arc
				(start 279.88006 -60.225178)
				(mid 279.860537 -60.229079)
				(end 279.843992 -60.240164)
			)
			(arc
				(start 278.722836 -61.36132)
				(mid 278.711725 -61.377854)
				(end 278.70785 -61.397388)
			)
			(arc
				(start 278.70785 -94.643956)
				(mid 278.711751 -94.663479)
				(end 278.722836 -94.680024)
			)
			(arc
				(start 279.887426 -95.844614)
				(mid 279.90396 -95.855725)
				(end 279.923494 -95.8596)
			)
		)
		(stroke
			(width 0)
			(type solid)
		)
		(fill yes)
		(layer "In8.Cu")
		(net "P52V_HS1_DRAIN_2")
	)
	(gr_poly
		(pts
			(xy 319.402206 -121.6914) (xy 319.412276 -121.690976) (xy 319.430879 -121.68326) (xy 319.438274 -121.676414)
			(xy 320.406014 -120.708674) (xy 320.412866 -120.701278) (xy 320.420604 -120.682679) (xy 320.421 -120.672606)
			(xy 320.421 -77.091794) (xy 320.420576 -77.081724) (xy 320.41286 -77.063121) (xy 320.406014 -77.055726)
			(xy 319.692274 -76.341986) (xy 319.684878 -76.335134) (xy 319.666279 -76.327396) (xy 319.656206 -76.327)
			(xy 308.6608 -76.327) (xy 308.62754 -76.326479) (xy 308.56159 -76.317791) (xy 308.497339 -76.300566)
			(xy 308.435888 -76.275097) (xy 308.378289 -76.241821) (xy 308.325529 -76.201308) (xy 308.301644 -76.178156)
			(xy 306.185824 -74.062336) (xy 306.178423 -74.055498) (xy 306.159824 -74.047785) (xy 306.149756 -74.04735)
			(xy 300.86427 -74.04735) (xy 300.854203 -74.04778) (xy 300.835612 -74.055508) (xy 300.828202 -74.062336)
			(xy 300.28642 -74.604118) (xy 300.279574 -74.611517) (xy 300.271843 -74.630115) (xy 300.271434 -74.640186)
			(xy 300.271434 -88.45423) (xy 300.271729 -88.462103) (xy 300.276515 -88.477104) (xy 300.280832 -88.483694)
			(xy 300.295759 -88.505354) (xy 300.32016 -88.551955) (xy 300.337926 -88.601467) (xy 300.348721 -88.652951)
			(xy 300.352339 -88.705429) (xy 300.348712 -88.757907) (xy 300.33791 -88.809389) (xy 300.320136 -88.858899)
			(xy 300.295729 -88.905496) (xy 300.280832 -88.927178) (xy 300.276501 -88.933762) (xy 300.271707 -88.948766)
			(xy 300.271434 -88.956642) (xy 300.271434 -101.454966) (xy 307.269651 -101.454966) (xy 307.273647 -101.2731)
			(xy 307.285627 -101.091585) (xy 307.305569 -100.910772) (xy 307.333434 -100.731009) (xy 307.369168 -100.552644)
			(xy 307.412701 -100.37602) (xy 307.463951 -100.201479) (xy 307.522818 -100.029357) (xy 307.589189 -99.859987)
			(xy 307.662935 -99.693696) (xy 307.743914 -99.530805) (xy 307.831969 -99.371628) (xy 307.926932 -99.216472)
			(xy 308.028617 -99.065637) (xy 308.13683 -98.919415) (xy 308.251362 -98.778086) (xy 308.37199 -98.641925)
			(xy 308.498483 -98.511193) (xy 308.630596 -98.386144) (xy 308.768074 -98.267018) (xy 308.910652 -98.154046)
			(xy 309.058055 -98.047446) (xy 309.209998 -97.947423) (xy 309.366187 -97.854171) (xy 309.526322 -97.767869)
			(xy 309.690093 -97.688684) (xy 309.857184 -97.616769) (xy 310.027272 -97.552263) (xy 310.20003 -97.495291)
			(xy 310.375124 -97.445961) (xy 310.552215 -97.40437) (xy 310.730962 -97.370597) (xy 310.91102 -97.344709)
			(xy 311.092042 -97.326754) (xy 311.273677 -97.316768) (xy 311.455576 -97.31477) (xy 311.637387 -97.320764)
			(xy 311.818759 -97.334737) (xy 311.999343 -97.356664) (xy 312.178789 -97.386502) (xy 312.356751 -97.424193)
			(xy 312.532886 -97.469664) (xy 312.706854 -97.522828) (xy 312.878318 -97.583582) (xy 313.046949 -97.651809)
			(xy 313.21242 -97.727377) (xy 313.374412 -97.81014) (xy 313.532612 -97.899939) (xy 313.686715 -97.9966)
			(xy 313.836424 -98.099937) (xy 313.981449 -98.209749) (xy 314.121511 -98.325826) (xy 314.256339 -98.447943)
			(xy 314.385673 -98.575864) (xy 314.509264 -98.709343) (xy 314.626872 -98.848121) (xy 314.738271 -98.991932)
			(xy 314.843246 -99.140496) (xy 314.941594 -99.293528) (xy 315.033125 -99.450733) (xy 315.117663 -99.611806)
			(xy 315.195044 -99.776437) (xy 315.265119 -99.944308) (xy 315.327753 -100.115095) (xy 315.382824 -100.288468)
			(xy 315.430228 -100.464093) (xy 315.469871 -100.64163) (xy 315.501678 -100.820737) (xy 315.525587 -101.001069)
			(xy 315.541552 -101.182277) (xy 315.549542 -101.364011) (xy 315.550042 -101.454966) (xy 315.549542 -101.545921)
			(xy 315.541552 -101.727655) (xy 315.525587 -101.908863) (xy 315.501678 -102.089195) (xy 315.469871 -102.268302)
			(xy 315.430228 -102.445839) (xy 315.382824 -102.621464) (xy 315.327753 -102.794837) (xy 315.265119 -102.965624)
			(xy 315.195044 -103.133495) (xy 315.117663 -103.298126) (xy 315.033125 -103.459199) (xy 314.941594 -103.616404)
			(xy 314.843246 -103.769436) (xy 314.738271 -103.918) (xy 314.626872 -104.061811) (xy 314.509264 -104.200589)
			(xy 314.385673 -104.334068) (xy 314.256339 -104.461989) (xy 314.121511 -104.584106) (xy 313.981449 -104.700183)
			(xy 313.836424 -104.809995) (xy 313.686715 -104.913332) (xy 313.532612 -105.009993) (xy 313.374412 -105.099792)
			(xy 313.21242 -105.182555) (xy 313.046949 -105.258123) (xy 312.878318 -105.32635) (xy 312.706854 -105.387104)
			(xy 312.532886 -105.440268) (xy 312.356751 -105.485739) (xy 312.178789 -105.52343) (xy 311.999343 -105.553268)
			(xy 311.818759 -105.575195) (xy 311.637387 -105.589168) (xy 311.455576 -105.595162) (xy 311.273677 -105.593164)
			(xy 311.092042 -105.583178) (xy 310.91102 -105.565223) (xy 310.730962 -105.539335) (xy 310.552215 -105.505562)
			(xy 310.375124 -105.463971) (xy 310.20003 -105.414641) (xy 310.027272 -105.357669) (xy 309.857184 -105.293163)
			(xy 309.690093 -105.221248) (xy 309.526322 -105.142063) (xy 309.366187 -105.055761) (xy 309.209998 -104.962509)
			(xy 309.058055 -104.862486) (xy 308.910652 -104.755886) (xy 308.768074 -104.642914) (xy 308.630596 -104.523788)
			(xy 308.498483 -104.398739) (xy 308.37199 -104.268007) (xy 308.251362 -104.131846) (xy 308.13683 -103.990517)
			(xy 308.028617 -103.844295) (xy 307.926932 -103.69346) (xy 307.831969 -103.538304) (xy 307.743914 -103.379127)
			(xy 307.662935 -103.216236) (xy 307.589189 -103.049945) (xy 307.522818 -102.880575) (xy 307.463951 -102.708453)
			(xy 307.412701 -102.533912) (xy 307.369168 -102.357288) (xy 307.333434 -102.178923) (xy 307.305569 -101.99916)
			(xy 307.285627 -101.818347) (xy 307.273647 -101.636832) (xy 307.269651 -101.454966) (xy 300.271434 -101.454966)
			(xy 300.271434 -120.646698) (xy 300.271857 -120.656768) (xy 300.279575 -120.67537) (xy 300.28642 -120.682766)
			(xy 301.280068 -121.676414) (xy 301.287466 -121.683259) (xy 301.306065 -121.690982) (xy 301.316136 -121.6914)
		)
		(stroke
			(width 0)
			(type solid)
		)
		(fill yes)
		(layer "In8.Cu")
		(net "P52V_1")
	)
	(gr_poly
		(pts
			(xy 326.00011 -166.271956) (xy 326.055917 -166.271446) (xy 326.167218 -166.263105) (xy 326.277585 -166.246469)
			(xy 326.386399 -166.221631) (xy 326.493054 -166.188731) (xy 326.596951 -166.147953) (xy 326.697511 -166.099525)
			(xy 326.79417 -166.043717) (xy 326.886389 -165.980841) (xy 326.973651 -165.91125) (xy 327.055468 -165.835332)
			(xy 327.131383 -165.753513) (xy 327.200971 -165.666249) (xy 327.263843 -165.574028) (xy 327.319648 -165.477367)
			(xy 327.368073 -165.376806) (xy 327.408848 -165.272907) (xy 327.441744 -165.166251) (xy 327.466578 -165.057436)
			(xy 327.48321 -164.947068) (xy 327.491548 -164.835767) (xy 327.492106 -164.77996) (xy 327.492106 -150.999952)
			(xy 327.491583 -150.944146) (xy 327.483238 -150.832846) (xy 327.4666 -150.722481) (xy 327.441761 -150.613668)
			(xy 327.408861 -150.507016) (xy 327.368082 -150.40312) (xy 327.319653 -150.302562) (xy 327.263845 -150.205904)
			(xy 327.20097 -150.113687) (xy 327.13138 -150.026426) (xy 327.055463 -149.94461) (xy 326.973645 -149.868695)
			(xy 326.886382 -149.799107) (xy 326.794164 -149.736235) (xy 326.697504 -149.680429) (xy 326.596945 -149.632003)
			(xy 326.493048 -149.591227) (xy 326.386395 -149.558329) (xy 326.277581 -149.533493) (xy 326.167216 -149.516857)
			(xy 326.055916 -149.508516) (xy 326.00011 -149.507956) (xy 154.399996 -149.507956) (xy 154.344188 -149.508478)
			(xy 154.232885 -149.516819) (xy 154.122517 -149.533454) (xy 154.0137 -149.558291) (xy 153.907043 -149.591189)
			(xy 153.803144 -149.631966) (xy 153.702581 -149.680394) (xy 153.605919 -149.7362) (xy 153.513698 -149.799075)
			(xy 153.426433 -149.868664) (xy 153.344612 -149.944581) (xy 153.268693 -150.026399) (xy 153.199101 -150.113662)
			(xy 153.136224 -150.205882) (xy 153.080414 -150.302543) (xy 153.031984 -150.403103) (xy 152.991204 -150.507002)
			(xy 152.958302 -150.613657) (xy 152.933462 -150.722474) (xy 152.916824 -150.832842) (xy 152.908479 -150.944144)
			(xy 152.908 -150.999952) (xy 152.908 -161.844536) (xy 155.304225 -161.844536) (xy 155.304225 -161.715396)
			(xy 155.312175 -161.586501) (xy 155.328045 -161.458341) (xy 155.351774 -161.3314) (xy 155.383273 -161.206161)
			(xy 155.422422 -161.083098) (xy 155.469073 -160.962679) (xy 155.523048 -160.84536) (xy 155.584143 -160.731586)
			(xy 155.652126 -160.621789) (xy 155.72674 -160.516386) (xy 155.807701 -160.415776) (xy 155.894701 -160.320341)
			(xy 155.987412 -160.230442) (xy 156.085482 -160.146421) (xy 156.188537 -160.068597) (xy 156.296188 -159.997265)
			(xy 156.408027 -159.932695) (xy 156.523628 -159.875133) (xy 156.642553 -159.824796) (xy 156.764352 -159.781876)
			(xy 156.888562 -159.746535) (xy 157.014711 -159.718908) (xy 157.142323 -159.699099) (xy 157.270912 -159.687183)
			(xy 157.39999 -159.683207) (xy 157.529068 -159.687183) (xy 157.657657 -159.699099) (xy 157.785269 -159.718908)
			(xy 157.911418 -159.746535) (xy 158.035628 -159.781876) (xy 158.157427 -159.824796) (xy 158.276352 -159.875133)
			(xy 158.391953 -159.932695) (xy 158.503792 -159.997265) (xy 158.611443 -160.068597) (xy 158.714498 -160.146421)
			(xy 158.812568 -160.230442) (xy 158.905279 -160.320341) (xy 158.992279 -160.415776) (xy 159.07324 -160.516386)
			(xy 159.147854 -160.621789) (xy 159.215837 -160.731586) (xy 159.276932 -160.84536) (xy 159.330907 -160.962679)
			(xy 159.377558 -161.083098) (xy 159.416707 -161.206161) (xy 159.448206 -161.3314) (xy 159.471935 -161.458341)
			(xy 159.487805 -161.586501) (xy 159.495755 -161.715396) (xy 159.496252 -161.779966) (xy 159.495755 -161.844536)
			(xy 320.904351 -161.844536) (xy 320.904351 -161.715396) (xy 320.912301 -161.586501) (xy 320.928171 -161.458341)
			(xy 320.9519 -161.3314) (xy 320.983399 -161.206161) (xy 321.022548 -161.083098) (xy 321.069199 -160.962679)
			(xy 321.123174 -160.84536) (xy 321.184269 -160.731586) (xy 321.252252 -160.621789) (xy 321.326866 -160.516386)
			(xy 321.407827 -160.415776) (xy 321.494827 -160.320341) (xy 321.587538 -160.230442) (xy 321.685608 -160.146421)
			(xy 321.788663 -160.068597) (xy 321.896314 -159.997265) (xy 322.008153 -159.932695) (xy 322.123754 -159.875133)
			(xy 322.242679 -159.824796) (xy 322.364478 -159.781876) (xy 322.488688 -159.746535) (xy 322.614837 -159.718908)
			(xy 322.742449 -159.699099) (xy 322.871038 -159.687183) (xy 323.000116 -159.683207) (xy 323.129194 -159.687183)
			(xy 323.257783 -159.699099) (xy 323.385395 -159.718908) (xy 323.511544 -159.746535) (xy 323.635754 -159.781876)
			(xy 323.757553 -159.824796) (xy 323.876478 -159.875133) (xy 323.992079 -159.932695) (xy 324.103918 -159.997265)
			(xy 324.211569 -160.068597) (xy 324.314624 -160.146421) (xy 324.412694 -160.230442) (xy 324.505405 -160.320341)
			(xy 324.592405 -160.415776) (xy 324.673366 -160.516386) (xy 324.74798 -160.621789) (xy 324.815963 -160.731586)
			(xy 324.877058 -160.84536) (xy 324.931033 -160.962679) (xy 324.977684 -161.083098) (xy 325.016833 -161.206161)
			(xy 325.048332 -161.3314) (xy 325.072061 -161.458341) (xy 325.087931 -161.586501) (xy 325.095881 -161.715396)
			(xy 325.096378 -161.779966) (xy 325.095881 -161.844536) (xy 325.087931 -161.973431) (xy 325.072061 -162.101591)
			(xy 325.048332 -162.228532) (xy 325.016833 -162.353771) (xy 324.977684 -162.476834) (xy 324.931033 -162.597253)
			(xy 324.877058 -162.714572) (xy 324.815963 -162.828346) (xy 324.74798 -162.938143) (xy 324.673366 -163.043546)
			(xy 324.592405 -163.144156) (xy 324.505405 -163.239591) (xy 324.412694 -163.32949) (xy 324.314624 -163.413511)
			(xy 324.211569 -163.491335) (xy 324.103918 -163.562667) (xy 323.992079 -163.627237) (xy 323.876478 -163.684799)
			(xy 323.757553 -163.735136) (xy 323.635754 -163.778056) (xy 323.511544 -163.813397) (xy 323.385395 -163.841024)
			(xy 323.257783 -163.860833) (xy 323.129194 -163.872749) (xy 323.000116 -163.876726) (xy 322.871038 -163.872749)
			(xy 322.742449 -163.860833) (xy 322.614837 -163.841024) (xy 322.488688 -163.813397) (xy 322.364478 -163.778056)
			(xy 322.242679 -163.735136) (xy 322.123754 -163.684799) (xy 322.008153 -163.627237) (xy 321.896314 -163.562667)
			(xy 321.788663 -163.491335) (xy 321.685608 -163.413511) (xy 321.587538 -163.32949) (xy 321.494827 -163.239591)
			(xy 321.407827 -163.144156) (xy 321.326866 -163.043546) (xy 321.252252 -162.938143) (xy 321.184269 -162.828346)
			(xy 321.123174 -162.714572) (xy 321.069199 -162.597253) (xy 321.022548 -162.476834) (xy 320.983399 -162.353771)
			(xy 320.9519 -162.228532) (xy 320.928171 -162.101591) (xy 320.912301 -161.973431) (xy 320.904351 -161.844536)
			(xy 159.495755 -161.844536) (xy 159.487805 -161.973431) (xy 159.471935 -162.101591) (xy 159.448206 -162.228532)
			(xy 159.416707 -162.353771) (xy 159.377558 -162.476834) (xy 159.330907 -162.597253) (xy 159.276932 -162.714572)
			(xy 159.215837 -162.828346) (xy 159.147854 -162.938143) (xy 159.07324 -163.043546) (xy 158.992279 -163.144156)
			(xy 158.905279 -163.239591) (xy 158.812568 -163.32949) (xy 158.714498 -163.413511) (xy 158.611443 -163.491335)
			(xy 158.503792 -163.562667) (xy 158.391953 -163.627237) (xy 158.276352 -163.684799) (xy 158.157427 -163.735136)
			(xy 158.035628 -163.778056) (xy 157.911418 -163.813397) (xy 157.785269 -163.841024) (xy 157.657657 -163.860833)
			(xy 157.529068 -163.872749) (xy 157.39999 -163.876726) (xy 157.270912 -163.872749) (xy 157.142323 -163.860833)
			(xy 157.014711 -163.841024) (xy 156.888562 -163.813397) (xy 156.764352 -163.778056) (xy 156.642553 -163.735136)
			(xy 156.523628 -163.684799) (xy 156.408027 -163.627237) (xy 156.296188 -163.562667) (xy 156.188537 -163.491335)
			(xy 156.085482 -163.413511) (xy 155.987412 -163.32949) (xy 155.894701 -163.239591) (xy 155.807701 -163.144156)
			(xy 155.72674 -163.043546) (xy 155.652126 -162.938143) (xy 155.584143 -162.828346) (xy 155.523048 -162.714572)
			(xy 155.469073 -162.597253) (xy 155.422422 -162.476834) (xy 155.383273 -162.353771) (xy 155.351774 -162.228532)
			(xy 155.328045 -162.101591) (xy 155.312175 -161.973431) (xy 155.304225 -161.844536) (xy 152.908 -161.844536)
			(xy 152.908 -164.77996) (xy 152.908508 -164.835769) (xy 152.916846 -164.947074) (xy 152.933479 -165.057444)
			(xy 152.958314 -165.166264) (xy 152.991211 -165.272922) (xy 153.031987 -165.376825) (xy 153.080414 -165.477389)
			(xy 153.13622 -165.574053) (xy 153.199095 -165.666277) (xy 153.268686 -165.753543) (xy 153.344603 -165.835366)
			(xy 153.426423 -165.911286) (xy 153.513688 -165.980879) (xy 153.605909 -166.043756) (xy 153.702572 -166.099566)
			(xy 153.803135 -166.147995) (xy 153.907036 -166.188775) (xy 154.013694 -166.221675) (xy 154.122512 -166.246513)
			(xy 154.232883 -166.263149) (xy 154.344187 -166.271491) (xy 154.399996 -166.271956)
		)
		(stroke
			(width 0)
			(type solid)
		)
		(fill yes)
		(layer "In8.Cu")
		(net "GND3")
	)
	(gr_poly
		(pts
			(xy 266.666472 -146.490944) (xy 323.000116 -146.490944) (xy 323.095449 -146.490445) (xy 323.285943 -146.482352)
			(xy 323.475923 -146.466182) (xy 323.665044 -146.441963) (xy 323.852968 -146.409739) (xy 324.039354 -146.369569)
			(xy 324.223868 -146.321525) (xy 324.406177 -146.265693) (xy 324.585951 -146.202173) (xy 324.762868 -146.131082)
			(xy 324.936608 -146.052545) (xy 325.106858 -145.966706) (xy 325.273312 -145.873718) (xy 325.43567 -145.77375)
			(xy 325.593638 -145.666981) (xy 325.746932 -145.553604) (xy 325.895277 -145.433823) (xy 326.038404 -145.307853)
			(xy 326.176056 -145.175923) (xy 326.307985 -145.03827) (xy 326.433952 -144.895142) (xy 326.553732 -144.746796)
			(xy 326.667107 -144.5935) (xy 326.773875 -144.435531) (xy 326.873841 -144.273173) (xy 326.966827 -144.106718)
			(xy 327.052665 -143.936467) (xy 327.1312 -143.762726) (xy 327.20229 -143.585808) (xy 327.265807 -143.406033)
			(xy 327.321637 -143.223724) (xy 327.36968 -143.03921) (xy 327.409848 -142.852823) (xy 327.44207 -142.664899)
			(xy 327.466287 -142.475777) (xy 327.482455 -142.285798) (xy 327.490546 -142.095303) (xy 327.49109 -141.99997)
			(xy 327.49109 -4.99999) (xy 327.490584 -4.904657) (xy 327.482491 -4.714162) (xy 327.466321 -4.524182)
			(xy 327.442103 -4.335059) (xy 327.40988 -4.147135) (xy 327.36971 -3.960748) (xy 327.321666 -3.776234)
			(xy 327.265834 -3.593925) (xy 327.202315 -3.414149) (xy 327.131224 -3.237232) (xy 327.052688 -3.063491)
			(xy 326.966849 -2.89324) (xy 326.873862 -2.726785) (xy 326.773894 -2.564427) (xy 326.667125 -2.406457)
			(xy 326.553748 -2.253162) (xy 326.433968 -2.104816) (xy 326.307999 -1.961688) (xy 326.176069 -1.824035)
			(xy 326.038416 -1.692105) (xy 325.895288 -1.566136) (xy 325.746943 -1.446355) (xy 325.593648 -1.332978)
			(xy 325.435678 -1.22621) (xy 325.27332 -1.126241) (xy 325.106866 -1.033254) (xy 324.936615 -0.947415)
			(xy 324.762874 -0.868878) (xy 324.585956 -0.797787) (xy 324.406181 -0.734268) (xy 324.223872 -0.678436)
			(xy 324.039358 -0.630391) (xy 323.852971 -0.590221) (xy 323.665046 -0.557998) (xy 323.475924 -0.533779)
			(xy 323.285944 -0.517609) (xy 323.095449 -0.509516) (xy 323.000116 -0.509016) (xy 4.99999 -0.509016)
			(xy 4.904657 -0.509522) (xy 4.714162 -0.517614) (xy 4.524182 -0.533784) (xy 4.335059 -0.558002) (xy 4.147135 -0.590225)
			(xy 3.960748 -0.630394) (xy 3.776233 -0.678438) (xy 3.593924 -0.73427) (xy 3.414149 -0.797788) (xy 3.237231 -0.86888)
			(xy 3.06349 -0.947415) (xy 2.893239 -1.033254) (xy 2.726784 -1.126242) (xy 2.564426 -1.22621) (xy 2.406456 -1.332978)
			(xy 2.253161 -1.446355) (xy 2.104815 -1.566136) (xy 1.961687 -1.692104) (xy 1.824034 -1.824034) (xy 1.692104 -1.961687)
			(xy 1.566136 -2.104815) (xy 1.446355 -2.253161) (xy 1.332978 -2.406456) (xy 1.22621 -2.564426) (xy 1.126242 -2.726784)
			(xy 1.033254 -2.893239) (xy 0.947415 -3.06349) (xy 0.86888 -3.237231) (xy 0.797788 -3.414149) (xy 0.73427 -3.593924)
			(xy 0.678438 -3.776233) (xy 0.630394 -3.960748) (xy 0.590225 -4.147135) (xy 0.558002 -4.335059) (xy 0.553544 -4.36987)
			(xy 242.877075 -4.36987) (xy 242.877075 -4.24073) (xy 242.885025 -4.111835) (xy 242.900895 -3.983675)
			(xy 242.924624 -3.856734) (xy 242.956123 -3.731495) (xy 242.995272 -3.608432) (xy 243.041923 -3.488013)
			(xy 243.095898 -3.370694) (xy 243.156993 -3.25692) (xy 243.224976 -3.147123) (xy 243.29959 -3.04172)
			(xy 243.380551 -2.94111) (xy 243.467551 -2.845675) (xy 243.560262 -2.755776) (xy 243.658332 -2.671755)
			(xy 243.761387 -2.593931) (xy 243.869038 -2.522599) (xy 243.980877 -2.458029) (xy 244.096478 -2.400467)
			(xy 244.215403 -2.35013) (xy 244.337202 -2.30721) (xy 244.461412 -2.271869) (xy 244.587561 -2.244242)
			(xy 244.715173 -2.224433) (xy 244.843762 -2.212517) (xy 244.97284 -2.208541) (xy 245.101918 -2.212517)
			(xy 245.230507 -2.224433) (xy 245.358119 -2.244242) (xy 245.484268 -2.271869) (xy 245.608478 -2.30721)
			(xy 245.730277 -2.35013) (xy 245.849202 -2.400467) (xy 245.964803 -2.458029) (xy 246.076642 -2.522599)
			(xy 246.184293 -2.593931) (xy 246.287348 -2.671755) (xy 246.385418 -2.755776) (xy 246.478129 -2.845675)
			(xy 246.565129 -2.94111) (xy 246.64609 -3.04172) (xy 246.720704 -3.147123) (xy 246.788687 -3.25692)
			(xy 246.849782 -3.370694) (xy 246.903757 -3.488013) (xy 246.950408 -3.608432) (xy 246.989557 -3.731495)
			(xy 247.021056 -3.856734) (xy 247.044785 -3.983675) (xy 247.060655 -4.111835) (xy 247.068605 -4.24073)
			(xy 247.069102 -4.3053) (xy 247.068605 -4.36987) (xy 247.060655 -4.498765) (xy 247.044785 -4.626925)
			(xy 247.021056 -4.753866) (xy 246.989557 -4.879105) (xy 246.950408 -5.002168) (xy 246.903757 -5.122587)
			(xy 246.849782 -5.239906) (xy 246.788687 -5.35368) (xy 246.720704 -5.463477) (xy 246.64609 -5.56888)
			(xy 246.565129 -5.66949) (xy 246.478129 -5.764925) (xy 246.385418 -5.854824) (xy 246.287348 -5.938845)
			(xy 246.184293 -6.016669) (xy 246.076642 -6.088001) (xy 245.964803 -6.152571) (xy 245.849202 -6.210133)
			(xy 245.730277 -6.26047) (xy 245.608478 -6.30339) (xy 245.484268 -6.338731) (xy 245.358119 -6.366358)
			(xy 245.230507 -6.386167) (xy 245.101918 -6.398083) (xy 244.97284 -6.40206) (xy 244.843762 -6.398083)
			(xy 244.715173 -6.386167) (xy 244.587561 -6.366358) (xy 244.461412 -6.338731) (xy 244.337202 -6.30339)
			(xy 244.215403 -6.26047) (xy 244.096478 -6.210133) (xy 243.980877 -6.152571) (xy 243.869038 -6.088001)
			(xy 243.761387 -6.016669) (xy 243.658332 -5.938845) (xy 243.560262 -5.854824) (xy 243.467551 -5.764925)
			(xy 243.380551 -5.66949) (xy 243.29959 -5.56888) (xy 243.224976 -5.463477) (xy 243.156993 -5.35368)
			(xy 243.095898 -5.239906) (xy 243.041923 -5.122587) (xy 242.995272 -5.002168) (xy 242.956123 -4.879105)
			(xy 242.924624 -4.753866) (xy 242.900895 -4.626925) (xy 242.885025 -4.498765) (xy 242.877075 -4.36987)
			(xy 0.553544 -4.36987) (xy 0.533784 -4.524182) (xy 0.517614 -4.714162) (xy 0.509522 -4.904657) (xy 0.509016 -4.99999)
			(xy 0.509016 -11.811) (xy 161.213292 -11.811) (xy 161.21368 -11.772716) (xy 161.220219 -11.696427)
			(xy 161.2333 -11.620985) (xy 161.252827 -11.546948) (xy 161.265362 -11.510772) (xy 161.268013 -11.502335)
			(xy 161.268013 -11.484665) (xy 161.265362 -11.476228) (xy 161.252837 -11.44005) (xy 161.233329 -11.36601)
			(xy 161.220249 -11.290569) (xy 161.213694 -11.214283) (xy 161.213292 -11.176) (xy 161.213787 -11.132867)
			(xy 161.222145 -11.047006) (xy 161.238773 -10.962358) (xy 161.263515 -10.879715) (xy 161.296139 -10.799856)
			(xy 161.336337 -10.723528) (xy 161.383734 -10.651448) (xy 161.437884 -10.584294) (xy 161.498278 -10.522696)
			(xy 161.564351 -10.467231) (xy 161.63548 -10.41842) (xy 161.711 -10.376723) (xy 161.7902 -10.342529)
			(xy 161.872338 -10.316161) (xy 161.956642 -10.297865) (xy 161.999422 -10.292334) (xy 162.010643 -10.290369)
			(xy 162.029893 -10.278242) (xy 162.036506 -10.268966) (xy 162.058636 -10.234762) (xy 162.108294 -10.170172)
			(xy 162.163649 -10.110392) (xy 162.224237 -10.055923) (xy 162.289549 -10.007219) (xy 162.35904 -9.964689)
			(xy 162.432128 -9.928689) (xy 162.508201 -9.899521) (xy 162.586621 -9.877428) (xy 162.666732 -9.862596)
			(xy 162.747864 -9.855149) (xy 162.7886 -9.854692) (xy 162.829702 -9.855167) (xy 162.911557 -9.862752)
			(xy 162.992362 -9.877857) (xy 163.071429 -9.900353) (xy 163.148083 -9.930049) (xy 163.22167 -9.966691)
			(xy 163.291562 -10.009966) (xy 163.357163 -10.059506) (xy 163.417913 -10.114887) (xy 163.473294 -10.175637)
			(xy 163.522834 -10.241238) (xy 163.566109 -10.31113) (xy 163.602751 -10.384717) (xy 163.632447 -10.461371)
			(xy 163.654943 -10.540438) (xy 163.670048 -10.621243) (xy 163.677633 -10.703098) (xy 163.678108 -10.7442)
			(xy 163.677552 -10.788906) (xy 163.668575 -10.877868) (xy 163.650722 -10.96548) (xy 163.624174 -11.050861)
			(xy 163.589197 -11.133148) (xy 163.546144 -11.211513) (xy 163.495449 -11.285166) (xy 163.437624 -11.353364)
			(xy 163.40582 -11.384788) (xy 163.397946 -11.392408) (xy 163.390072 -11.41222) (xy 163.393374 -11.509502)
			(xy 163.402772 -11.528806) (xy 163.411154 -11.535918) (xy 163.44386 -11.564051) (xy 163.50427 -11.625646)
			(xy 163.558433 -11.692801) (xy 163.605841 -11.764883) (xy 163.646049 -11.841217) (xy 163.678677 -11.921084)
			(xy 163.703421 -12.003735) (xy 163.720046 -12.088393) (xy 163.728399 -12.174262) (xy 163.728908 -12.2174)
			(xy 163.728433 -12.258502) (xy 163.720848 -12.340357) (xy 163.705743 -12.421162) (xy 163.683247 -12.500229)
			(xy 163.653551 -12.576883) (xy 163.616909 -12.65047) (xy 163.573634 -12.720362) (xy 163.524094 -12.785963)
			(xy 163.468713 -12.846713) (xy 163.407963 -12.902094) (xy 163.342362 -12.951634) (xy 163.27247 -12.994909)
			(xy 163.198883 -13.031551) (xy 163.122229 -13.061247) (xy 163.043162 -13.083743) (xy 162.962357 -13.098848)
			(xy 162.880502 -13.106433) (xy 162.8394 -13.106908) (xy 162.79634 -13.10644) (xy 162.710622 -13.098119)
			(xy 162.626109 -13.081554) (xy 162.543592 -13.056902) (xy 162.463843 -13.024392) (xy 162.387608 -12.984328)
			(xy 162.315601 -12.937087) (xy 162.248496 -12.883108) (xy 162.18692 -12.822899) (xy 162.131449 -12.757022)
			(xy 162.10661 -12.721844) (xy 162.099372 -12.712425) (xy 162.078566 -12.701028) (xy 162.066732 -12.7)
			(xy 162.02424 -12.697737) (xy 161.939934 -12.686166) (xy 161.857118 -12.666598) (xy 161.776548 -12.639212)
			(xy 161.698961 -12.604258) (xy 161.625066 -12.562056) (xy 161.555538 -12.512991) (xy 161.491013 -12.457512)
			(xy 161.432079 -12.396125) (xy 161.379276 -12.329392) (xy 161.333087 -12.257922) (xy 161.293932 -12.182368)
			(xy 161.26217 -12.103421) (xy 161.23809 -12.021802) (xy 161.221914 -11.938257) (xy 161.213789 -11.853548)
			(xy 161.213292 -11.811) (xy 0.509016 -11.811) (xy 0.509016 -16.070072) (xy 0.509506 -16.139948) (xy 0.517342 -16.279481)
			(xy 0.53299 -16.418355) (xy 0.556399 -16.556133) (xy 0.587497 -16.692382) (xy 0.626186 -16.826673)
			(xy 0.672343 -16.958583) (xy 0.725824 -17.087698) (xy 0.78646 -17.21361) (xy 0.854061 -17.335925)
			(xy 0.928414 -17.454257) (xy 1.009285 -17.568234) (xy 1.09642 -17.677497) (xy 1.189543 -17.781703)
			(xy 1.288363 -17.880523) (xy 1.392569 -17.973646) (xy 1.501832 -18.060781) (xy 1.615809 -18.141652)
			(xy 1.734141 -18.216005) (xy 1.856456 -18.283606) (xy 1.982368 -18.344242) (xy 2.111483 -18.397723)
			(xy 2.243393 -18.44388) (xy 2.377684 -18.482569) (xy 2.513933 -18.513667) (xy 2.651711 -18.537076)
			(xy 2.790585 -18.552724) (xy 2.930118 -18.56056) (xy 2.999994 -18.56105) (xy 9.600184 -18.56105)
			(xy 9.644215 -18.561509) (xy 9.731942 -18.569171) (xy 9.818668 -18.584451) (xy 9.903731 -18.607233)
			(xy 9.986485 -18.637344) (xy 10.066298 -18.674554) (xy 10.142564 -18.71858) (xy 10.214702 -18.769087)
			(xy 10.282162 -18.825691) (xy 10.344431 -18.88796) (xy 10.401034 -18.95542) (xy 10.451541 -19.027557)
			(xy 10.495567 -19.103823) (xy 10.532777 -19.183637) (xy 10.562888 -19.266391) (xy 10.58567 -19.351454)
			(xy 10.60095 -19.43818) (xy 10.608611 -19.525907) (xy 10.609072 -19.569938) (xy 10.609072 -20.997361)
			(xy 276.478742 -20.997361) (xy 276.478742 -20.912639) (xy 276.486795 -20.828302) (xy 276.502829 -20.745112)
			(xy 276.526697 -20.663822) (xy 276.558185 -20.58517) (xy 276.597007 -20.509867) (xy 276.64281 -20.438595)
			(xy 276.695181 -20.371999) (xy 276.753646 -20.310684) (xy 276.817674 -20.255203) (xy 276.886686 -20.20606)
			(xy 276.960056 -20.1637) (xy 277.037121 -20.128505) (xy 277.117183 -20.100796) (xy 277.199516 -20.080822)
			(xy 277.283375 -20.068765) (xy 277.368 -20.064734) (xy 277.452625 -20.068765) (xy 277.536484 -20.080822)
			(xy 277.618817 -20.100796) (xy 277.698879 -20.128505) (xy 277.775944 -20.1637) (xy 277.849314 -20.20606)
			(xy 277.918326 -20.255203) (xy 277.982354 -20.310684) (xy 278.040819 -20.371999) (xy 278.09319 -20.438595)
			(xy 278.138993 -20.509867) (xy 278.177815 -20.58517) (xy 278.209303 -20.663822) (xy 278.233171 -20.745112)
			(xy 278.249205 -20.828302) (xy 278.257258 -20.912639) (xy 278.257762 -20.955) (xy 278.257258 -20.997361)
			(xy 278.249205 -21.081698) (xy 278.233171 -21.164888) (xy 278.209303 -21.246178) (xy 278.177815 -21.32483)
			(xy 278.138993 -21.400133) (xy 278.09319 -21.471405) (xy 278.040819 -21.538001) (xy 277.982354 -21.599316)
			(xy 277.918326 -21.654797) (xy 277.849314 -21.70394) (xy 277.775944 -21.7463) (xy 277.698879 -21.781495)
			(xy 277.618817 -21.809204) (xy 277.536484 -21.829178) (xy 277.452625 -21.841235) (xy 277.368 -21.845267)
			(xy 277.283375 -21.841235) (xy 277.199516 -21.829178) (xy 277.117183 -21.809204) (xy 277.037121 -21.781495)
			(xy 276.960056 -21.7463) (xy 276.886686 -21.70394) (xy 276.817674 -21.654797) (xy 276.753646 -21.599316)
			(xy 276.695181 -21.538001) (xy 276.64281 -21.471405) (xy 276.597007 -21.400133) (xy 276.558185 -21.32483)
			(xy 276.526697 -21.246178) (xy 276.502829 -21.164888) (xy 276.486795 -21.081698) (xy 276.478742 -20.997361)
			(xy 10.609072 -20.997361) (xy 10.609072 -25.329903) (xy 12.90965 -25.329903) (xy 12.913613 -25.189472)
			(xy 12.925487 -25.049488) (xy 12.945237 -24.910397) (xy 12.972799 -24.77264) (xy 13.008084 -24.636657)
			(xy 13.050982 -24.50288) (xy 13.101355 -24.371734) (xy 13.159043 -24.243638) (xy 13.223863 -24.118999)
			(xy 13.295608 -23.998213) (xy 13.374049 -23.881665) (xy 13.458938 -23.769726) (xy 13.550004 -23.662752)
			(xy 13.646958 -23.561083) (xy 13.74949 -23.465043) (xy 13.857275 -23.374937) (xy 13.969969 -23.291053)
			(xy 14.087214 -23.213657) (xy 14.208637 -23.142996) (xy 14.333851 -23.079294) (xy 14.462458 -23.022755)
			(xy 14.594049 -22.973557) (xy 14.728204 -22.931858) (xy 14.864498 -22.89779) (xy 15.002496 -22.871462)
			(xy 15.141758 -22.852958) (xy 15.281843 -22.842336) (xy 15.422304 -22.83963) (xy 15.562693 -22.844849)
			(xy 15.702565 -22.857976) (xy 15.841475 -22.87897) (xy 15.978979 -22.907763) (xy 16.114641 -22.944264)
			(xy 16.248029 -22.988357) (xy 16.378718 -23.039902) (xy 16.506293 -23.098734) (xy 16.630347 -23.164666)
			(xy 16.750486 -23.237489) (xy 16.866328 -23.316971) (xy 16.977503 -23.402858) (xy 17.083658 -23.494878)
			(xy 17.184455 -23.592737) (xy 17.232376 -23.644098) (xy 17.241266 -23.65375) (xy 17.264888 -23.661878)
			(xy 17.3736 -23.645368) (xy 17.393666 -23.630382) (xy 17.399 -23.618698) (xy 17.438143 -23.536826)
			(xy 17.522872 -23.376323) (xy 17.614769 -23.219815) (xy 17.713645 -23.067619) (xy 17.819299 -22.920048)
			(xy 17.931515 -22.777404) (xy 18.050063 -22.639976) (xy 18.174701 -22.508047) (xy 18.305175 -22.381886)
			(xy 18.441218 -22.261751) (xy 18.582551 -22.147887) (xy 18.728885 -22.040528) (xy 18.879923 -21.939892)
			(xy 19.035355 -21.846185) (xy 19.194863 -21.759599) (xy 19.358121 -21.68031) (xy 19.524796 -21.608481)
			(xy 19.694548 -21.544259) (xy 19.867028 -21.487775) (xy 20.041885 -21.439144) (xy 20.218761 -21.398465)
			(xy 20.397295 -21.365823) (xy 20.577122 -21.341282) (xy 20.757875 -21.324895) (xy 20.939183 -21.316693)
			(xy 21.02993 -21.316188) (xy 21.120001 -21.316693) (xy 21.299962 -21.324775) (xy 21.479379 -21.340923)
			(xy 21.657891 -21.365104) (xy 21.835139 -21.39727) (xy 22.010765 -21.437355) (xy 22.184415 -21.48528)
			(xy 22.355741 -21.540947) (xy 22.524396 -21.604244) (xy 22.690042 -21.675045) (xy 22.852345 -21.753206)
			(xy 23.010977 -21.838569) (xy 23.16562 -21.930964) (xy 23.315962 -22.030204) (xy 23.461701 -22.136089)
			(xy 23.602542 -22.248406) (xy 23.738202 -22.366929) (xy 23.868408 -22.491418) (xy 23.992897 -22.621624)
			(xy 24.11142 -22.757284) (xy 24.223737 -22.898125) (xy 24.329622 -23.043864) (xy 24.428862 -23.194206)
			(xy 24.521257 -23.348849) (xy 24.60662 -23.507481) (xy 24.684781 -23.669784) (xy 24.755582 -23.83543)
			(xy 24.818879 -24.004085) (xy 24.874546 -24.175411) (xy 24.922471 -24.349061) (xy 24.962556 -24.524687)
			(xy 24.994722 -24.701935) (xy 25.018903 -24.880447) (xy 25.035051 -25.059864) (xy 25.043133 -25.239825)
			(xy 25.043133 -25.329896) (xy 25.159471 -25.329896) (xy 25.16346 -25.188998) (xy 25.175414 -25.048551)
			(xy 25.195294 -24.909006) (xy 25.223037 -24.770809) (xy 25.258555 -24.634403) (xy 25.301732 -24.500224)
			(xy 25.352432 -24.368704) (xy 25.410492 -24.240262) (xy 25.475724 -24.115311) (xy 25.547922 -23.99425)
			(xy 25.626853 -23.877468) (xy 25.712264 -23.765339) (xy 25.803883 -23.658221) (xy 25.901415 -23.556458)
			(xy 26.004547 -23.460376) (xy 26.112951 -23.370283) (xy 26.226278 -23.286466) (xy 26.344165 -23.209196)
			(xy 26.466235 -23.138719) (xy 26.592097 -23.07526) (xy 26.721347 -23.019025) (xy 26.853572 -22.970191)
			(xy 26.988348 -22.928916) (xy 27.125243 -22.895333) (xy 27.263819 -22.869548) (xy 27.403632 -22.851644)
			(xy 27.544234 -22.841679) (xy 27.685174 -22.839684) (xy 27.826002 -22.845667) (xy 27.966265 -22.859607)
			(xy 28.105515 -22.88146) (xy 28.243306 -22.911156) (xy 28.379196 -22.9486) (xy 28.51275 -22.993672)
			(xy 28.64354 -23.046228) (xy 28.73385 -23.0886) (xy 271.702788 -23.0886) (xy 271.706818 -23.003999)
			(xy 271.718871 -22.920164) (xy 271.738839 -22.837855) (xy 271.766541 -22.757816) (xy 271.801725 -22.680773)
			(xy 271.844074 -22.607423) (xy 271.893203 -22.538431) (xy 271.948668 -22.474421) (xy 272.009966 -22.415973)
			(xy 272.076542 -22.363617) (xy 272.147794 -22.317827) (xy 272.223075 -22.279016) (xy 272.301705 -22.247537)
			(xy 272.382972 -22.223676) (xy 272.466138 -22.207647) (xy 272.550452 -22.199596) (xy 272.5928 -22.199092)
			(xy 272.635108 -22.199589) (xy 272.719344 -22.207592) (xy 272.80244 -22.223553) (xy 272.883646 -22.24733)
			(xy 272.962229 -22.278706) (xy 273.037479 -22.317399) (xy 273.073368 -22.339808) (xy 273.081757 -22.344691)
			(xy 273.1008 -22.348362) (xy 273.119843 -22.344691) (xy 273.128232 -22.339808) (xy 273.164109 -22.317376)
			(xy 273.239354 -22.278665) (xy 273.317937 -22.247279) (xy 273.399147 -22.223503) (xy 273.482249 -22.20755)
			(xy 273.56649 -22.199566) (xy 273.6088 -22.199092) (xy 273.651148 -22.199596) (xy 273.735462 -22.207647)
			(xy 273.818628 -22.223676) (xy 273.899895 -22.247537) (xy 273.978525 -22.279016) (xy 274.053806 -22.317827)
			(xy 274.125058 -22.363617) (xy 274.191634 -22.415973) (xy 274.252932 -22.474421) (xy 274.308397 -22.538431)
			(xy 274.357526 -22.607423) (xy 274.399875 -22.680773) (xy 274.435059 -22.757816) (xy 274.462761 -22.837855)
			(xy 274.482729 -22.920164) (xy 274.494782 -23.003999) (xy 274.498813 -23.0886) (xy 274.494782 -23.173201)
			(xy 274.482729 -23.257036) (xy 274.462761 -23.339345) (xy 274.435059 -23.419384) (xy 274.399875 -23.496427)
			(xy 274.357526 -23.569777) (xy 274.308397 -23.638769) (xy 274.252932 -23.702779) (xy 274.191634 -23.761227)
			(xy 274.125058 -23.813583) (xy 274.053806 -23.859373) (xy 273.978525 -23.898184) (xy 273.899895 -23.929663)
			(xy 273.818628 -23.953524) (xy 273.735462 -23.969553) (xy 273.651148 -23.977604) (xy 273.6088 -23.978108)
			(xy 273.566492 -23.977611) (xy 273.482256 -23.969608) (xy 273.39916 -23.953647) (xy 273.317954 -23.92987)
			(xy 273.239371 -23.898494) (xy 273.164121 -23.859801) (xy 273.128232 -23.837392) (xy 273.119843 -23.832509)
			(xy 273.1008 -23.828838) (xy 273.081757 -23.832509) (xy 273.073368 -23.837392) (xy 273.037491 -23.859824)
			(xy 272.962246 -23.898535) (xy 272.883663 -23.929921) (xy 272.802453 -23.953697) (xy 272.719351 -23.96965)
			(xy 272.63511 -23.977634) (xy 272.5928 -23.978108) (xy 272.550452 -23.977604) (xy 272.466138 -23.969553)
			(xy 272.382972 -23.953524) (xy 272.301705 -23.929663) (xy 272.223075 -23.898184) (xy 272.147794 -23.859373)
			(xy 272.076542 -23.813583) (xy 272.009966 -23.761227) (xy 271.948668 -23.702779) (xy 271.893203 -23.638769)
			(xy 271.844074 -23.569777) (xy 271.801725 -23.496427) (xy 271.766541 -23.419384) (xy 271.738839 -23.339345)
			(xy 271.718871 -23.257036) (xy 271.706818 -23.173201) (xy 271.702788 -23.0886) (xy 28.73385 -23.0886)
			(xy 28.771147 -23.106099) (xy 28.895163 -23.173094) (xy 29.015189 -23.246997) (xy 29.130843 -23.327573)
			(xy 29.241752 -23.414562) (xy 29.347563 -23.507687) (xy 29.447935 -23.606649) (xy 29.542548 -23.711131)
			(xy 29.631099 -23.820799) (xy 29.713303 -23.935301) (xy 29.788897 -24.05427) (xy 29.85764 -24.177325)
			(xy 29.919311 -24.304072) (xy 29.973712 -24.434105) (xy 30.02067 -24.567008) (xy 30.060033 -24.702354)
			(xy 30.091676 -24.839711) (xy 30.115498 -24.978638) (xy 30.131421 -25.11869) (xy 30.139396 -25.259419)
			(xy 30.139894 -25.329896) (xy 30.139396 -25.400373) (xy 30.131421 -25.541102) (xy 30.125683 -25.59157)
			(xy 42.354235 -25.59157) (xy 42.354235 -25.46243) (xy 42.362185 -25.333535) (xy 42.378055 -25.205375)
			(xy 42.401784 -25.078434) (xy 42.433283 -24.953195) (xy 42.472432 -24.830132) (xy 42.519083 -24.709713)
			(xy 42.573058 -24.592394) (xy 42.634153 -24.47862) (xy 42.702136 -24.368823) (xy 42.77675 -24.26342)
			(xy 42.857711 -24.16281) (xy 42.944711 -24.067375) (xy 43.037422 -23.977476) (xy 43.135492 -23.893455)
			(xy 43.238547 -23.815631) (xy 43.346198 -23.744299) (xy 43.458037 -23.679729) (xy 43.573638 -23.622167)
			(xy 43.692563 -23.57183) (xy 43.814362 -23.52891) (xy 43.938572 -23.493569) (xy 44.064721 -23.465942)
			(xy 44.192333 -23.446133) (xy 44.320922 -23.434217) (xy 44.45 -23.430241) (xy 44.579078 -23.434217)
			(xy 44.707667 -23.446133) (xy 44.835279 -23.465942) (xy 44.961428 -23.493569) (xy 45.085638 -23.52891)
			(xy 45.207437 -23.57183) (xy 45.326362 -23.622167) (xy 45.441963 -23.679729) (xy 45.553802 -23.744299)
			(xy 45.661453 -23.815631) (xy 45.764508 -23.893455) (xy 45.862578 -23.977476) (xy 45.955289 -24.067375)
			(xy 46.042289 -24.16281) (xy 46.12325 -24.26342) (xy 46.197864 -24.368823) (xy 46.265847 -24.47862)
			(xy 46.326942 -24.592394) (xy 46.380917 -24.709713) (xy 46.427568 -24.830132) (xy 46.466717 -24.953195)
			(xy 46.498216 -25.078434) (xy 46.521945 -25.205375) (xy 46.537815 -25.333535) (xy 46.545765 -25.46243)
			(xy 46.546262 -25.527) (xy 46.545765 -25.59157) (xy 46.537815 -25.720465) (xy 46.521945 -25.848625)
			(xy 46.498216 -25.975566) (xy 46.466717 -26.100805) (xy 46.427568 -26.223868) (xy 46.380917 -26.344287)
			(xy 46.326942 -26.461606) (xy 46.265847 -26.57538) (xy 46.197864 -26.685177) (xy 46.12325 -26.79058)
			(xy 46.042289 -26.89119) (xy 45.955289 -26.986625) (xy 45.862578 -27.076524) (xy 45.764508 -27.160545)
			(xy 45.661453 -27.238369) (xy 45.553802 -27.309701) (xy 45.441963 -27.374271) (xy 45.326362 -27.431833)
			(xy 45.207437 -27.48217) (xy 45.085638 -27.52509) (xy 44.961428 -27.560431) (xy 44.835279 -27.588058)
			(xy 44.707667 -27.607867) (xy 44.579078 -27.619783) (xy 44.45 -27.62376) (xy 44.320922 -27.619783)
			(xy 44.192333 -27.607867) (xy 44.064721 -27.588058) (xy 43.938572 -27.560431) (xy 43.814362 -27.52509)
			(xy 43.692563 -27.48217) (xy 43.573638 -27.431833) (xy 43.458037 -27.374271) (xy 43.346198 -27.309701)
			(xy 43.238547 -27.238369) (xy 43.135492 -27.160545) (xy 43.037422 -27.076524) (xy 42.944711 -26.986625)
			(xy 42.857711 -26.89119) (xy 42.77675 -26.79058) (xy 42.702136 -26.685177) (xy 42.634153 -26.57538)
			(xy 42.573058 -26.461606) (xy 42.519083 -26.344287) (xy 42.472432 -26.223868) (xy 42.433283 -26.100805)
			(xy 42.401784 -25.975566) (xy 42.378055 -25.848625) (xy 42.362185 -25.720465) (xy 42.354235 -25.59157)
			(xy 30.125683 -25.59157) (xy 30.115498 -25.681154) (xy 30.091676 -25.820081) (xy 30.060033 -25.957438)
			(xy 30.02067 -26.092784) (xy 29.973712 -26.225687) (xy 29.919311 -26.35572) (xy 29.85764 -26.482467)
			(xy 29.788897 -26.605522) (xy 29.713303 -26.724491) (xy 29.631099 -26.838993) (xy 29.542548 -26.948661)
			(xy 29.447935 -27.053143) (xy 29.347563 -27.152105) (xy 29.241752 -27.24523) (xy 29.130843 -27.332219)
			(xy 29.015189 -27.412795) (xy 28.895163 -27.486698) (xy 28.771147 -27.553693) (xy 28.64354 -27.613564)
			(xy 28.51275 -27.66612) (xy 28.379196 -27.711192) (xy 28.243306 -27.748636) (xy 28.105515 -27.778332)
			(xy 27.966265 -27.800185) (xy 27.826002 -27.814125) (xy 27.685174 -27.820108) (xy 27.544234 -27.818113)
			(xy 27.403632 -27.808148) (xy 27.263819 -27.790244) (xy 27.125243 -27.764459) (xy 26.988348 -27.730876)
			(xy 26.853572 -27.689601) (xy 26.721347 -27.640767) (xy 26.592097 -27.584532) (xy 26.466235 -27.521073)
			(xy 26.344165 -27.450596) (xy 26.226278 -27.373326) (xy 26.112951 -27.289509) (xy 26.004547 -27.199416)
			(xy 25.901415 -27.103334) (xy 25.803883 -27.001571) (xy 25.712264 -26.894453) (xy 25.626853 -26.782324)
			(xy 25.547922 -26.665542) (xy 25.475724 -26.544481) (xy 25.410492 -26.41953) (xy 25.352432 -26.291088)
			(xy 25.301732 -26.159568) (xy 25.258555 -26.025389) (xy 25.223037 -25.888983) (xy 25.195294 -25.750786)
			(xy 25.175414 -25.611241) (xy 25.16346 -25.470794) (xy 25.159471 -25.329896) (xy 25.043133 -25.329896)
			(xy 25.043133 -25.419967) (xy 25.035051 -25.599928) (xy 25.018903 -25.779345) (xy 24.994722 -25.957857)
			(xy 24.962556 -26.135105) (xy 24.922471 -26.310731) (xy 24.874546 -26.484381) (xy 24.818879 -26.655707)
			(xy 24.755582 -26.824362) (xy 24.684781 -26.990008) (xy 24.60662 -27.152311) (xy 24.521257 -27.310943)
			(xy 24.428862 -27.465586) (xy 24.329622 -27.615928) (xy 24.223737 -27.761667) (xy 24.11142 -27.902508)
			(xy 23.992897 -28.038168) (xy 23.868408 -28.168374) (xy 23.738202 -28.292863) (xy 23.602542 -28.411386)
			(xy 23.461701 -28.523703) (xy 23.315962 -28.629588) (xy 23.16562 -28.728828) (xy 23.010977 -28.821223)
			(xy 22.852345 -28.906586) (xy 22.690042 -28.984747) (xy 22.524396 -29.055548) (xy 22.355741 -29.118845)
			(xy 22.184415 -29.174512) (xy 22.010765 -29.222437) (xy 21.835139 -29.262522) (xy 21.657891 -29.294688)
			(xy 21.479379 -29.318869) (xy 21.299962 -29.335017) (xy 21.120001 -29.343099) (xy 21.02993 -29.343604)
			(xy 20.939184 -29.343097) (xy 20.757877 -29.334889) (xy 20.577127 -29.318497) (xy 20.397302 -29.293952)
			(xy 20.21877 -29.261305) (xy 20.041895 -29.220623) (xy 19.867041 -29.171989) (xy 19.694562 -29.115502)
			(xy 19.524813 -29.051278) (xy 19.35814 -28.979448) (xy 19.194884 -28.900158) (xy 19.035377 -28.813572)
			(xy 18.879947 -28.719865) (xy 18.728911 -28.61923) (xy 18.582577 -28.511871) (xy 18.441244 -28.398009)
			(xy 18.305202 -28.277876) (xy 18.174728 -28.151717) (xy 18.050089 -28.01979) (xy 17.93154 -27.882366)
			(xy 17.819322 -27.739724) (xy 17.713666 -27.592156) (xy 17.614787 -27.439964) (xy 17.522887 -27.283459)
			(xy 17.438154 -27.12296) (xy 17.399 -27.041094) (xy 17.393666 -27.02941) (xy 17.3736 -27.014424)
			(xy 17.264888 -26.997914) (xy 17.241266 -27.006042) (xy 17.232376 -27.015694) (xy 17.184459 -27.067059)
			(xy 17.083662 -27.164918) (xy 16.977507 -27.256938) (xy 16.866332 -27.342826) (xy 16.750491 -27.422308)
			(xy 16.630352 -27.495131) (xy 16.506298 -27.561063) (xy 16.378724 -27.619896) (xy 16.248035 -27.671441)
			(xy 16.114647 -27.715534) (xy 15.978985 -27.752036) (xy 15.841481 -27.780829) (xy 15.702571 -27.801823)
			(xy 15.562699 -27.814951) (xy 15.42231 -27.82017) (xy 15.281849 -27.817465) (xy 15.141764 -27.806843)
			(xy 15.002501 -27.788339) (xy 14.864504 -27.762011) (xy 14.72821 -27.727944) (xy 14.594054 -27.686245)
			(xy 14.462464 -27.637048) (xy 14.333856 -27.580508) (xy 14.208642 -27.516807) (xy 14.087219 -27.446146)
			(xy 13.969974 -27.36875) (xy 13.857279 -27.284866) (xy 13.749494 -27.194761) (xy 13.646962 -27.098721)
			(xy 13.550008 -26.997053) (xy 13.458942 -26.890079) (xy 13.374053 -26.77814) (xy 13.295611 -26.661592)
			(xy 13.223866 -26.540806) (xy 13.159046 -26.416167) (xy 13.101357 -26.288071) (xy 13.050984 -26.156926)
			(xy 13.008086 -26.023149) (xy 12.9728 -25.887166) (xy 12.945238 -25.749409) (xy 12.925488 -25.610318)
			(xy 12.913613 -25.470334) (xy 12.90965 -25.329903) (xy 10.609072 -25.329903) (xy 10.609072 -31.070042)
			(xy 10.608582 -31.114068) (xy 10.600889 -31.201783) (xy 10.585583 -31.288494) (xy 10.562781 -31.373542)
			(xy 10.532655 -31.456279) (xy 10.495435 -31.536078) (xy 10.451404 -31.61233) (xy 10.400897 -31.684456)
			(xy 10.344298 -31.751907) (xy 10.282038 -31.81417) (xy 10.214589 -31.870772) (xy 10.142465 -31.921282)
			(xy 10.066215 -31.965316) (xy 9.986418 -32.002539) (xy 9.903682 -32.032668) (xy 9.818635 -32.055474)
			(xy 9.731924 -32.070783) (xy 9.64421 -32.07848) (xy 9.600184 -32.07893) (xy 2.999994 -32.07893) (xy 2.930118 -32.07942)
			(xy 2.790585 -32.087256) (xy 2.651711 -32.102904) (xy 2.513933 -32.126313) (xy 2.377684 -32.157411)
			(xy 2.243393 -32.1961) (xy 2.111483 -32.242257) (xy 1.982368 -32.295738) (xy 1.856456 -32.356374)
			(xy 1.734141 -32.423975) (xy 1.615809 -32.498328) (xy 1.501832 -32.579199) (xy 1.392569 -32.666334)
			(xy 1.288363 -32.759457) (xy 1.189543 -32.858277) (xy 1.09642 -32.962483) (xy 1.04643 -33.025168)
			(xy 59.677545 -33.025168) (xy 59.677545 -32.854812) (xy 59.68553 -32.684644) (xy 59.701482 -32.515037)
			(xy 59.725367 -32.346365) (xy 59.757131 -32.178997) (xy 59.796706 -32.013302) (xy 59.844003 -31.849644)
			(xy 59.89892 -31.688383) (xy 59.961335 -31.529873) (xy 60.031111 -31.374463) (xy 60.108094 -31.222495)
			(xy 60.192116 -31.074301) (xy 60.282992 -30.930209) (xy 60.380522 -30.790535) (xy 60.484492 -30.655586)
			(xy 60.594673 -30.525658) (xy 60.710822 -30.401038) (xy 60.832686 -30.281999) (xy 60.959994 -30.168803)
			(xy 61.092469 -30.061698) (xy 61.229819 -29.960921) (xy 61.371741 -29.866692) (xy 61.517923 -29.779219)
			(xy 61.668046 -29.698694) (xy 61.821777 -29.625294) (xy 61.97878 -29.55918) (xy 62.13871 -29.500498)
			(xy 62.301214 -29.449377) (xy 62.465935 -29.405929) (xy 62.632513 -29.37025) (xy 62.800579 -29.342418)
			(xy 62.969765 -29.322494) (xy 63.139699 -29.310522) (xy 63.310008 -29.306529) (xy 63.480317 -29.310522)
			(xy 63.650251 -29.322494) (xy 63.819437 -29.342418) (xy 63.987503 -29.37025) (xy 64.154081 -29.405929)
			(xy 64.318802 -29.449377) (xy 64.481306 -29.500498) (xy 64.641236 -29.55918) (xy 64.798239 -29.625294)
			(xy 64.95197 -29.698694) (xy 65.102093 -29.779219) (xy 65.248275 -29.866692) (xy 65.390197 -29.960921)
			(xy 65.527547 -30.061698) (xy 65.660022 -30.168803) (xy 65.78733 -30.281999) (xy 65.909194 -30.401038)
			(xy 66.025343 -30.525658) (xy 66.135524 -30.655586) (xy 66.239494 -30.790535) (xy 66.337024 -30.930209)
			(xy 66.4279 -31.074301) (xy 66.511922 -31.222495) (xy 66.588905 -31.374463) (xy 66.658681 -31.529873)
			(xy 66.721096 -31.688383) (xy 66.776013 -31.849644) (xy 66.82331 -32.013302) (xy 66.862885 -32.178997)
			(xy 66.894649 -32.346365) (xy 66.918534 -32.515037) (xy 66.934486 -32.684644) (xy 66.942471 -32.854812)
			(xy 66.94297 -32.93999) (xy 66.942471 -33.025168) (xy 66.934486 -33.195336) (xy 66.918534 -33.364943)
			(xy 66.894649 -33.533615) (xy 66.862885 -33.700983) (xy 66.82331 -33.866678) (xy 66.776013 -34.030336)
			(xy 66.721096 -34.191597) (xy 66.658681 -34.350107) (xy 66.588905 -34.505517) (xy 66.511922 -34.657485)
			(xy 66.4279 -34.805679) (xy 66.337024 -34.949771) (xy 66.239494 -35.089445) (xy 66.135524 -35.224394)
			(xy 66.025343 -35.354322) (xy 65.909194 -35.478942) (xy 65.78733 -35.597981) (xy 65.660022 -35.711177)
			(xy 65.527547 -35.818282) (xy 65.390197 -35.919059) (xy 65.248275 -36.013288) (xy 65.102093 -36.100761)
			(xy 64.95197 -36.181286) (xy 64.798239 -36.254686) (xy 64.641236 -36.3208) (xy 64.481306 -36.379482)
			(xy 64.318802 -36.430603) (xy 64.154081 -36.474051) (xy 63.987503 -36.50973) (xy 63.819437 -36.537562)
			(xy 63.650251 -36.557486) (xy 63.480317 -36.569458) (xy 63.310008 -36.573452) (xy 63.139699 -36.569458)
			(xy 62.969765 -36.557486) (xy 62.800579 -36.537562) (xy 62.632513 -36.50973) (xy 62.465935 -36.474051)
			(xy 62.301214 -36.430603) (xy 62.13871 -36.379482) (xy 61.97878 -36.3208) (xy 61.821777 -36.254686)
			(xy 61.668046 -36.181286) (xy 61.517923 -36.100761) (xy 61.371741 -36.013288) (xy 61.229819 -35.919059)
			(xy 61.092469 -35.818282) (xy 60.959994 -35.711177) (xy 60.832686 -35.597981) (xy 60.710822 -35.478942)
			(xy 60.594673 -35.354322) (xy 60.484492 -35.224394) (xy 60.380522 -35.089445) (xy 60.282992 -34.949771)
			(xy 60.192116 -34.805679) (xy 60.108094 -34.657485) (xy 60.031111 -34.505517) (xy 59.961335 -34.350107)
			(xy 59.89892 -34.191597) (xy 59.844003 -34.030336) (xy 59.796706 -33.866678) (xy 59.757131 -33.700983)
			(xy 59.725367 -33.533615) (xy 59.701482 -33.364943) (xy 59.68553 -33.195336) (xy 59.677545 -33.025168)
			(xy 1.04643 -33.025168) (xy 1.009285 -33.071746) (xy 0.928414 -33.185723) (xy 0.854061 -33.304055)
			(xy 0.78646 -33.42637) (xy 0.725824 -33.552282) (xy 0.672343 -33.681397) (xy 0.626186 -33.813307)
			(xy 0.587497 -33.947598) (xy 0.556399 -34.083847) (xy 0.53299 -34.221625) (xy 0.517342 -34.360499)
			(xy 0.509506 -34.500032) (xy 0.509016 -34.569908) (xy 0.509016 -38.019995) (xy 100.644968 -38.019995)
			(xy 100.648872 -37.915504) (xy 100.660563 -37.811596) (xy 100.679974 -37.708849) (xy 100.706998 -37.607838)
			(xy 100.741484 -37.509125) (xy 100.783239 -37.41326) (xy 100.832032 -37.320778) (xy 100.887589 -37.232195)
			(xy 100.949602 -37.148005) (xy 101.017724 -37.068676) (xy 101.091575 -36.994652) (xy 101.170744 -36.926345)
			(xy 101.254789 -36.864136) (xy 101.298756 -36.835842) (xy 101.309932 -36.82873) (xy 101.322378 -36.806378)
			(xy 101.322378 -36.693602) (xy 101.309932 -36.67125) (xy 101.298756 -36.664138) (xy 101.25478 -36.635858)
			(xy 101.170735 -36.573648) (xy 101.091567 -36.505341) (xy 101.017716 -36.431316) (xy 100.949595 -36.351987)
			(xy 100.887583 -36.267796) (xy 100.832027 -36.179212) (xy 100.783235 -36.08673) (xy 100.74148 -35.990865)
			(xy 100.706995 -35.892152) (xy 100.679971 -35.79114) (xy 100.660561 -35.688394) (xy 100.648871 -35.584486)
			(xy 100.644968 -35.479995) (xy 100.648872 -35.375504) (xy 100.660563 -35.271596) (xy 100.679974 -35.168849)
			(xy 100.706998 -35.067838) (xy 100.741484 -34.969125) (xy 100.783239 -34.87326) (xy 100.832032 -34.780778)
			(xy 100.887589 -34.692195) (xy 100.949602 -34.608005) (xy 101.017724 -34.528676) (xy 101.091575 -34.454652)
			(xy 101.170744 -34.386345) (xy 101.254789 -34.324136) (xy 101.298756 -34.295842) (xy 101.309932 -34.28873)
			(xy 101.322378 -34.266378) (xy 101.322378 -34.153602) (xy 101.309932 -34.13125) (xy 101.298756 -34.124138)
			(xy 101.253105 -34.094744) (xy 101.166014 -34.02989) (xy 101.084209 -33.958484) (xy 101.008183 -33.880954)
			(xy 100.938393 -33.797766) (xy 100.875258 -33.70942) (xy 100.819159 -33.616449) (xy 100.770431 -33.51941)
			(xy 100.72937 -33.418887) (xy 100.69622 -33.315485) (xy 100.671182 -33.209825) (xy 100.654406 -33.102543)
			(xy 100.645993 -32.994283) (xy 100.645468 -32.93999) (xy 100.645985 -32.887639) (xy 100.653809 -32.783228)
			(xy 100.669413 -32.679695) (xy 100.692709 -32.577616) (xy 100.723568 -32.477564) (xy 100.761816 -32.380097)
			(xy 100.807239 -32.28576) (xy 100.859585 -32.195082) (xy 100.91856 -32.108567) (xy 100.983834 -32.026702)
			(xy 101.055043 -31.949942) (xy 101.131788 -31.878718) (xy 101.213641 -31.813427) (xy 101.300143 -31.754435)
			(xy 101.390811 -31.702071) (xy 101.485138 -31.656629) (xy 101.582598 -31.618361) (xy 101.682644 -31.587482)
			(xy 101.784717 -31.564166) (xy 101.888248 -31.548541) (xy 101.992657 -31.540696) (xy 102.045008 -31.540196)
			(xy 102.099308 -31.540684) (xy 102.207582 -31.549102) (xy 102.314878 -31.565887) (xy 102.42055 -31.590938)
			(xy 102.523962 -31.624104) (xy 102.624493 -31.665187) (xy 102.721537 -31.713937) (xy 102.81451 -31.770063)
			(xy 102.902853 -31.833226) (xy 102.986035 -31.903047) (xy 103.063555 -31.979105) (xy 103.134946 -32.060943)
			(xy 103.199779 -32.148068) (xy 103.229156 -32.193738) (xy 103.236268 -32.204914) (xy 103.25862 -32.21736)
			(xy 103.371396 -32.21736) (xy 103.393748 -32.204914) (xy 103.40086 -32.193738) (xy 103.430248 -32.148075)
			(xy 103.49508 -32.060952) (xy 103.566471 -31.979116) (xy 103.643991 -31.903059) (xy 103.727172 -31.83324)
			(xy 103.815514 -31.770078) (xy 103.908487 -31.713954) (xy 104.00553 -31.665205) (xy 104.106059 -31.624125)
			(xy 104.20947 -31.59096) (xy 104.315141 -31.56591) (xy 104.422436 -31.549126) (xy 104.530708 -31.540709)
			(xy 104.585008 -31.540196) (xy 104.637364 -31.54063) (xy 104.741784 -31.548457) (xy 104.845326 -31.564066)
			(xy 104.947413 -31.58737) (xy 105.047472 -31.618239) (xy 105.144944 -31.6565) (xy 105.239283 -31.701939)
			(xy 105.329963 -31.754302) (xy 105.416476 -31.813296) (xy 105.498337 -31.878591) (xy 105.57509 -31.949821)
			(xy 105.646304 -32.026588) (xy 105.711581 -32.108464) (xy 105.770557 -32.194989) (xy 105.8229 -32.28568)
			(xy 105.868319 -32.38003) (xy 105.906559 -32.47751) (xy 105.937407 -32.577575) (xy 105.960689 -32.679667)
			(xy 105.976277 -32.783212) (xy 105.984081 -32.887634) (xy 105.984548 -32.93999) (xy 105.984054 -32.994284)
			(xy 105.975641 -33.102545) (xy 105.958864 -33.209828) (xy 105.933825 -33.315489) (xy 105.900673 -33.418892)
			(xy 105.859609 -33.519415) (xy 105.810879 -33.616455) (xy 105.754776 -33.709426) (xy 105.691638 -33.797771)
			(xy 105.621844 -33.880957) (xy 105.545813 -33.958486) (xy 105.464005 -34.029889) (xy 105.376909 -34.094739)
			(xy 105.33126 -34.124138) (xy 105.320084 -34.13125) (xy 105.307638 -34.153602) (xy 105.307638 -34.266378)
			(xy 105.320084 -34.28873) (xy 105.33126 -34.295842) (xy 105.37522 -34.324148) (xy 105.459268 -34.386354)
			(xy 105.538441 -34.454658) (xy 105.612295 -34.52868) (xy 105.68042 -34.608006) (xy 105.742436 -34.692195)
			(xy 105.797996 -34.780777) (xy 105.846791 -34.873258) (xy 105.888549 -34.969123) (xy 105.923037 -35.067836)
			(xy 105.950062 -35.168848) (xy 105.969475 -35.271594) (xy 105.981166 -35.375503) (xy 105.98507 -35.479995)
			(xy 105.981167 -35.584486) (xy 105.969476 -35.688395) (xy 105.950065 -35.791142) (xy 105.92304 -35.892154)
			(xy 105.888553 -35.990867) (xy 105.846796 -36.086732) (xy 105.798001 -36.179214) (xy 105.742442 -36.267796)
			(xy 105.680427 -36.351986) (xy 105.612303 -36.431313) (xy 105.538449 -36.505335) (xy 105.459277 -36.57364)
			(xy 105.375229 -36.635846) (xy 105.33126 -36.664138) (xy 105.320084 -36.67125) (xy 105.307638 -36.693602)
			(xy 105.307638 -36.806378) (xy 105.320084 -36.82873) (xy 105.33126 -36.835842) (xy 105.37522 -36.864148)
			(xy 105.459268 -36.926354) (xy 105.538441 -36.994658) (xy 105.612295 -37.06868) (xy 105.68042 -37.148006)
			(xy 105.742436 -37.232195) (xy 105.797996 -37.320777) (xy 105.846791 -37.413258) (xy 105.888549 -37.509123)
			(xy 105.923037 -37.607836) (xy 105.950062 -37.708848) (xy 105.969475 -37.811594) (xy 105.981166 -37.915503)
			(xy 105.98507 -38.019995) (xy 109.534968 -38.019995) (xy 109.538872 -37.915504) (xy 109.550563 -37.811596)
			(xy 109.569974 -37.708849) (xy 109.596998 -37.607838) (xy 109.631484 -37.509125) (xy 109.673239 -37.41326)
			(xy 109.722032 -37.320778) (xy 109.777589 -37.232195) (xy 109.839602 -37.148005) (xy 109.907724 -37.068676)
			(xy 109.981575 -36.994652) (xy 110.060744 -36.926345) (xy 110.144789 -36.864136) (xy 110.188756 -36.835842)
			(xy 110.199932 -36.82873) (xy 110.212378 -36.806378) (xy 110.212378 -36.693602) (xy 110.199932 -36.67125)
			(xy 110.188756 -36.664138) (xy 110.14478 -36.635858) (xy 110.060735 -36.573648) (xy 109.981567 -36.505341)
			(xy 109.907716 -36.431316) (xy 109.839595 -36.351987) (xy 109.777583 -36.267796) (xy 109.722027 -36.179212)
			(xy 109.673235 -36.08673) (xy 109.63148 -35.990865) (xy 109.596995 -35.892152) (xy 109.569971 -35.79114)
			(xy 109.550561 -35.688394) (xy 109.538871 -35.584486) (xy 109.534968 -35.479995) (xy 109.538872 -35.375504)
			(xy 109.550563 -35.271596) (xy 109.569974 -35.168849) (xy 109.596998 -35.067838) (xy 109.631484 -34.969125)
			(xy 109.673239 -34.87326) (xy 109.722032 -34.780778) (xy 109.777589 -34.692195) (xy 109.839602 -34.608005)
			(xy 109.907724 -34.528676) (xy 109.981575 -34.454652) (xy 110.060744 -34.386345) (xy 110.144789 -34.324136)
			(xy 110.188756 -34.295842) (xy 110.199932 -34.28873) (xy 110.212378 -34.266378) (xy 110.212378 -34.153602)
			(xy 110.199932 -34.13125) (xy 110.188756 -34.124138) (xy 110.143105 -34.094744) (xy 110.056014 -34.02989)
			(xy 109.974209 -33.958484) (xy 109.898183 -33.880954) (xy 109.828393 -33.797766) (xy 109.765258 -33.70942)
			(xy 109.709159 -33.616449) (xy 109.660431 -33.51941) (xy 109.61937 -33.418887) (xy 109.58622 -33.315485)
			(xy 109.561182 -33.209825) (xy 109.544406 -33.102543) (xy 109.535993 -32.994283) (xy 109.535468 -32.93999)
			(xy 109.535985 -32.887639) (xy 109.543809 -32.783228) (xy 109.559413 -32.679695) (xy 109.582709 -32.577616)
			(xy 109.613568 -32.477564) (xy 109.651816 -32.380097) (xy 109.697239 -32.28576) (xy 109.749585 -32.195082)
			(xy 109.80856 -32.108567) (xy 109.873834 -32.026702) (xy 109.945043 -31.949942) (xy 110.021788 -31.878718)
			(xy 110.103641 -31.813427) (xy 110.190143 -31.754435) (xy 110.280811 -31.702071) (xy 110.375138 -31.656629)
			(xy 110.472598 -31.618361) (xy 110.572644 -31.587482) (xy 110.674717 -31.564166) (xy 110.778248 -31.548541)
			(xy 110.882657 -31.540696) (xy 110.935008 -31.540196) (xy 110.989308 -31.540684) (xy 111.097582 -31.549102)
			(xy 111.204878 -31.565887) (xy 111.31055 -31.590938) (xy 111.413962 -31.624104) (xy 111.514493 -31.665187)
			(xy 111.611537 -31.713937) (xy 111.70451 -31.770063) (xy 111.792853 -31.833226) (xy 111.876035 -31.903047)
			(xy 111.953555 -31.979105) (xy 112.024946 -32.060943) (xy 112.089779 -32.148068) (xy 112.119156 -32.193738)
			(xy 112.126268 -32.204914) (xy 112.14862 -32.21736) (xy 112.261396 -32.21736) (xy 112.283748 -32.204914)
			(xy 112.29086 -32.193738) (xy 112.320248 -32.148075) (xy 112.38508 -32.060952) (xy 112.456471 -31.979116)
			(xy 112.533991 -31.903059) (xy 112.617172 -31.83324) (xy 112.705514 -31.770078) (xy 112.798487 -31.713954)
			(xy 112.89553 -31.665205) (xy 112.996059 -31.624125) (xy 113.09947 -31.59096) (xy 113.205141 -31.56591)
			(xy 113.312436 -31.549126) (xy 113.420708 -31.540709) (xy 113.475008 -31.540196) (xy 113.527364 -31.54063)
			(xy 113.631784 -31.548457) (xy 113.735326 -31.564066) (xy 113.837413 -31.58737) (xy 113.937472 -31.618239)
			(xy 114.034944 -31.6565) (xy 114.129283 -31.701939) (xy 114.219963 -31.754302) (xy 114.306476 -31.813296)
			(xy 114.388337 -31.878591) (xy 114.46509 -31.949821) (xy 114.536304 -32.026588) (xy 114.601581 -32.108464)
			(xy 114.660557 -32.194989) (xy 114.7129 -32.28568) (xy 114.758319 -32.38003) (xy 114.796559 -32.47751)
			(xy 114.827407 -32.577575) (xy 114.850689 -32.679667) (xy 114.866277 -32.783212) (xy 114.874081 -32.887634)
			(xy 114.874548 -32.93999) (xy 114.874054 -32.994284) (xy 114.865641 -33.102545) (xy 114.848864 -33.209828)
			(xy 114.823825 -33.315489) (xy 114.790673 -33.418892) (xy 114.749609 -33.519415) (xy 114.700879 -33.616455)
			(xy 114.644776 -33.709426) (xy 114.581638 -33.797771) (xy 114.511844 -33.880957) (xy 114.435813 -33.958486)
			(xy 114.354005 -34.029889) (xy 114.266909 -34.094739) (xy 114.22126 -34.124138) (xy 114.210084 -34.13125)
			(xy 114.197638 -34.153602) (xy 114.197638 -34.266378) (xy 114.210084 -34.28873) (xy 114.22126 -34.295842)
			(xy 114.26522 -34.324148) (xy 114.349268 -34.386354) (xy 114.428441 -34.454658) (xy 114.502295 -34.52868)
			(xy 114.57042 -34.608006) (xy 114.632436 -34.692195) (xy 114.687996 -34.780777) (xy 114.736791 -34.873258)
			(xy 114.778549 -34.969123) (xy 114.813037 -35.067836) (xy 114.840062 -35.168848) (xy 114.859475 -35.271594)
			(xy 114.871166 -35.375503) (xy 114.87507 -35.479995) (xy 114.871167 -35.584486) (xy 114.859476 -35.688395)
			(xy 114.840065 -35.791142) (xy 114.81304 -35.892154) (xy 114.778553 -35.990867) (xy 114.736796 -36.086732)
			(xy 114.688001 -36.179214) (xy 114.632442 -36.267796) (xy 114.570427 -36.351986) (xy 114.502303 -36.431313)
			(xy 114.428449 -36.505335) (xy 114.349277 -36.57364) (xy 114.265229 -36.635846) (xy 114.22126 -36.664138)
			(xy 114.210084 -36.67125) (xy 114.197638 -36.693602) (xy 114.197638 -36.806378) (xy 114.210084 -36.82873)
			(xy 114.22126 -36.835842) (xy 114.26522 -36.864148) (xy 114.349268 -36.926354) (xy 114.428441 -36.994658)
			(xy 114.502295 -37.06868) (xy 114.57042 -37.148006) (xy 114.632436 -37.232195) (xy 114.687996 -37.320777)
			(xy 114.736791 -37.413258) (xy 114.778549 -37.509123) (xy 114.813037 -37.607836) (xy 114.840062 -37.708848)
			(xy 114.859475 -37.811594) (xy 114.871166 -37.915503) (xy 114.87507 -38.019995) (xy 118.424968 -38.019995)
			(xy 118.428872 -37.915504) (xy 118.440563 -37.811596) (xy 118.459974 -37.708849) (xy 118.486998 -37.607838)
			(xy 118.521484 -37.509125) (xy 118.563239 -37.41326) (xy 118.612032 -37.320778) (xy 118.667589 -37.232195)
			(xy 118.729602 -37.148005) (xy 118.797724 -37.068676) (xy 118.871575 -36.994652) (xy 118.950744 -36.926345)
			(xy 119.034789 -36.864136) (xy 119.078756 -36.835842) (xy 119.089932 -36.82873) (xy 119.102378 -36.806378)
			(xy 119.102378 -36.693602) (xy 119.089932 -36.67125) (xy 119.078756 -36.664138) (xy 119.03478 -36.635858)
			(xy 118.950735 -36.573648) (xy 118.871567 -36.505341) (xy 118.797716 -36.431316) (xy 118.729595 -36.351987)
			(xy 118.667583 -36.267796) (xy 118.612027 -36.179212) (xy 118.563235 -36.08673) (xy 118.52148 -35.990865)
			(xy 118.486995 -35.892152) (xy 118.459971 -35.79114) (xy 118.440561 -35.688394) (xy 118.428871 -35.584486)
			(xy 118.424968 -35.479995) (xy 118.428872 -35.375504) (xy 118.440563 -35.271596) (xy 118.459974 -35.168849)
			(xy 118.486998 -35.067838) (xy 118.521484 -34.969125) (xy 118.563239 -34.87326) (xy 118.612032 -34.780778)
			(xy 118.667589 -34.692195) (xy 118.729602 -34.608005) (xy 118.797724 -34.528676) (xy 118.871575 -34.454652)
			(xy 118.950744 -34.386345) (xy 119.034789 -34.324136) (xy 119.078756 -34.295842) (xy 119.089932 -34.28873)
			(xy 119.102378 -34.266378) (xy 119.102378 -34.153602) (xy 119.089932 -34.13125) (xy 119.078756 -34.124138)
			(xy 119.033105 -34.094744) (xy 118.946014 -34.02989) (xy 118.864209 -33.958484) (xy 118.788183 -33.880954)
			(xy 118.718393 -33.797766) (xy 118.655258 -33.70942) (xy 118.599159 -33.616449) (xy 118.550431 -33.51941)
			(xy 118.50937 -33.418887) (xy 118.47622 -33.315485) (xy 118.451182 -33.209825) (xy 118.434406 -33.102543)
			(xy 118.425993 -32.994283) (xy 118.425468 -32.93999) (xy 118.425985 -32.887639) (xy 118.433809 -32.783228)
			(xy 118.449413 -32.679695) (xy 118.472709 -32.577616) (xy 118.503568 -32.477564) (xy 118.541816 -32.380097)
			(xy 118.587239 -32.28576) (xy 118.639585 -32.195082) (xy 118.69856 -32.108567) (xy 118.763834 -32.026702)
			(xy 118.835043 -31.949942) (xy 118.911788 -31.878718) (xy 118.993641 -31.813427) (xy 119.080143 -31.754435)
			(xy 119.170811 -31.702071) (xy 119.265138 -31.656629) (xy 119.362598 -31.618361) (xy 119.462644 -31.587482)
			(xy 119.564717 -31.564166) (xy 119.668248 -31.548541) (xy 119.772657 -31.540696) (xy 119.825008 -31.540196)
			(xy 119.879308 -31.540684) (xy 119.987582 -31.549102) (xy 120.094878 -31.565887) (xy 120.20055 -31.590938)
			(xy 120.303962 -31.624104) (xy 120.404493 -31.665187) (xy 120.501537 -31.713937) (xy 120.59451 -31.770063)
			(xy 120.682853 -31.833226) (xy 120.766035 -31.903047) (xy 120.843555 -31.979105) (xy 120.914946 -32.060943)
			(xy 120.979779 -32.148068) (xy 121.009156 -32.193738) (xy 121.016268 -32.204914) (xy 121.03862 -32.21736)
			(xy 121.151396 -32.21736) (xy 121.173748 -32.204914) (xy 121.18086 -32.193738) (xy 121.210248 -32.148075)
			(xy 121.27508 -32.060952) (xy 121.346471 -31.979116) (xy 121.423991 -31.903059) (xy 121.507172 -31.83324)
			(xy 121.595514 -31.770078) (xy 121.688487 -31.713954) (xy 121.78553 -31.665205) (xy 121.886059 -31.624125)
			(xy 121.98947 -31.59096) (xy 122.095141 -31.56591) (xy 122.202436 -31.549126) (xy 122.310708 -31.540709)
			(xy 122.365008 -31.540196) (xy 122.417364 -31.54063) (xy 122.521784 -31.548457) (xy 122.625326 -31.564066)
			(xy 122.727413 -31.58737) (xy 122.827472 -31.618239) (xy 122.924944 -31.6565) (xy 123.019283 -31.701939)
			(xy 123.109963 -31.754302) (xy 123.196476 -31.813296) (xy 123.278337 -31.878591) (xy 123.35509 -31.949821)
			(xy 123.426304 -32.026588) (xy 123.491581 -32.108464) (xy 123.550557 -32.194989) (xy 123.6029 -32.28568)
			(xy 123.648319 -32.38003) (xy 123.686559 -32.47751) (xy 123.717407 -32.577575) (xy 123.740689 -32.679667)
			(xy 123.756277 -32.783212) (xy 123.764081 -32.887634) (xy 123.764548 -32.93999) (xy 123.764054 -32.994284)
			(xy 123.761654 -33.025168) (xy 130.797545 -33.025168) (xy 130.797545 -32.854812) (xy 130.80553 -32.684644)
			(xy 130.821482 -32.515037) (xy 130.845367 -32.346365) (xy 130.877131 -32.178997) (xy 130.916706 -32.013302)
			(xy 130.964003 -31.849644) (xy 131.01892 -31.688383) (xy 131.081335 -31.529873) (xy 131.151111 -31.374463)
			(xy 131.228094 -31.222495) (xy 131.312116 -31.074301) (xy 131.402992 -30.930209) (xy 131.500522 -30.790535)
			(xy 131.604492 -30.655586) (xy 131.714673 -30.525658) (xy 131.830822 -30.401038) (xy 131.952686 -30.281999)
			(xy 132.079994 -30.168803) (xy 132.212469 -30.061698) (xy 132.349819 -29.960921) (xy 132.491741 -29.866692)
			(xy 132.637923 -29.779219) (xy 132.788046 -29.698694) (xy 132.941777 -29.625294) (xy 133.09878 -29.55918)
			(xy 133.25871 -29.500498) (xy 133.421214 -29.449377) (xy 133.585935 -29.405929) (xy 133.752513 -29.37025)
			(xy 133.920579 -29.342418) (xy 134.089765 -29.322494) (xy 134.259699 -29.310522) (xy 134.430008 -29.306529)
			(xy 134.600317 -29.310522) (xy 134.770251 -29.322494) (xy 134.939437 -29.342418) (xy 135.107503 -29.37025)
			(xy 135.274081 -29.405929) (xy 135.438802 -29.449377) (xy 135.601306 -29.500498) (xy 135.761236 -29.55918)
			(xy 135.918239 -29.625294) (xy 136.07197 -29.698694) (xy 136.222093 -29.779219) (xy 136.368275 -29.866692)
			(xy 136.510197 -29.960921) (xy 136.647547 -30.061698) (xy 136.780022 -30.168803) (xy 136.90733 -30.281999)
			(xy 137.029194 -30.401038) (xy 137.145343 -30.525658) (xy 137.255524 -30.655586) (xy 137.359494 -30.790535)
			(xy 137.457024 -30.930209) (xy 137.5479 -31.074301) (xy 137.631922 -31.222495) (xy 137.708905 -31.374463)
			(xy 137.778681 -31.529873) (xy 137.841096 -31.688383) (xy 137.896013 -31.849644) (xy 137.94331 -32.013302)
			(xy 137.982885 -32.178997) (xy 138.014649 -32.346365) (xy 138.038534 -32.515037) (xy 138.054486 -32.684644)
			(xy 138.062471 -32.854812) (xy 138.06297 -32.93999) (xy 138.062471 -33.025168) (xy 138.054486 -33.195336)
			(xy 138.038534 -33.364943) (xy 138.014649 -33.533615) (xy 137.982885 -33.700983) (xy 137.94331 -33.866678)
			(xy 137.896013 -34.030336) (xy 137.841096 -34.191597) (xy 137.778681 -34.350107) (xy 137.708905 -34.505517)
			(xy 137.631922 -34.657485) (xy 137.5479 -34.805679) (xy 137.457024 -34.949771) (xy 137.359494 -35.089445)
			(xy 137.255524 -35.224394) (xy 137.145343 -35.354322) (xy 137.029194 -35.478942) (xy 136.90733 -35.597981)
			(xy 136.780022 -35.711177) (xy 136.647547 -35.818282) (xy 136.510197 -35.919059) (xy 136.368275 -36.013288)
			(xy 136.222093 -36.100761) (xy 136.07197 -36.181286) (xy 135.918239 -36.254686) (xy 135.761236 -36.3208)
			(xy 135.601306 -36.379482) (xy 135.438802 -36.430603) (xy 135.274081 -36.474051) (xy 135.107503 -36.50973)
			(xy 134.939437 -36.537562) (xy 134.770251 -36.557486) (xy 134.600317 -36.569458) (xy 134.430008 -36.573452)
			(xy 134.259699 -36.569458) (xy 134.089765 -36.557486) (xy 133.920579 -36.537562) (xy 133.752513 -36.50973)
			(xy 133.585935 -36.474051) (xy 133.421214 -36.430603) (xy 133.25871 -36.379482) (xy 133.09878 -36.3208)
			(xy 132.941777 -36.254686) (xy 132.788046 -36.181286) (xy 132.637923 -36.100761) (xy 132.491741 -36.013288)
			(xy 132.349819 -35.919059) (xy 132.212469 -35.818282) (xy 132.079994 -35.711177) (xy 131.952686 -35.597981)
			(xy 131.830822 -35.478942) (xy 131.714673 -35.354322) (xy 131.604492 -35.224394) (xy 131.500522 -35.089445)
			(xy 131.402992 -34.949771) (xy 131.312116 -34.805679) (xy 131.228094 -34.657485) (xy 131.151111 -34.505517)
			(xy 131.081335 -34.350107) (xy 131.01892 -34.191597) (xy 130.964003 -34.030336) (xy 130.916706 -33.866678)
			(xy 130.877131 -33.700983) (xy 130.845367 -33.533615) (xy 130.821482 -33.364943) (xy 130.80553 -33.195336)
			(xy 130.797545 -33.025168) (xy 123.761654 -33.025168) (xy 123.755641 -33.102545) (xy 123.738864 -33.209828)
			(xy 123.713825 -33.315489) (xy 123.680673 -33.418892) (xy 123.639609 -33.519415) (xy 123.590879 -33.616455)
			(xy 123.534776 -33.709426) (xy 123.471638 -33.797771) (xy 123.401844 -33.880957) (xy 123.325813 -33.958486)
			(xy 123.244005 -34.029889) (xy 123.156909 -34.094739) (xy 123.11126 -34.124138) (xy 123.100084 -34.13125)
			(xy 123.087638 -34.153602) (xy 123.087638 -34.266378) (xy 123.100084 -34.28873) (xy 123.11126 -34.295842)
			(xy 123.15522 -34.324148) (xy 123.239268 -34.386354) (xy 123.318441 -34.454658) (xy 123.392295 -34.52868)
			(xy 123.46042 -34.608006) (xy 123.522436 -34.692195) (xy 123.577996 -34.780777) (xy 123.626791 -34.873258)
			(xy 123.668549 -34.969123) (xy 123.703037 -35.067836) (xy 123.730062 -35.168848) (xy 123.749475 -35.271594)
			(xy 123.761166 -35.375503) (xy 123.76507 -35.479995) (xy 123.761167 -35.584486) (xy 123.749476 -35.688395)
			(xy 123.730065 -35.791142) (xy 123.70304 -35.892154) (xy 123.668553 -35.990867) (xy 123.626796 -36.086732)
			(xy 123.578001 -36.179214) (xy 123.522442 -36.267796) (xy 123.460427 -36.351986) (xy 123.392303 -36.431313)
			(xy 123.318449 -36.505335) (xy 123.239277 -36.57364) (xy 123.155229 -36.635846) (xy 123.11126 -36.664138)
			(xy 123.100084 -36.67125) (xy 123.087638 -36.693602) (xy 123.087638 -36.806378) (xy 123.100084 -36.82873)
			(xy 123.11126 -36.835842) (xy 123.15522 -36.864148) (xy 123.239268 -36.926354) (xy 123.318441 -36.994658)
			(xy 123.392295 -37.06868) (xy 123.46042 -37.148006) (xy 123.522436 -37.232195) (xy 123.577996 -37.320777)
			(xy 123.626791 -37.413258) (xy 123.668549 -37.509123) (xy 123.703037 -37.607836) (xy 123.730062 -37.708848)
			(xy 123.749475 -37.811594) (xy 123.761166 -37.915503) (xy 123.76507 -38.019995) (xy 123.764517 -38.03481)
			(xy 165.292523 -38.03481) (xy 165.292523 -37.864454) (xy 165.300508 -37.694286) (xy 165.31646 -37.524679)
			(xy 165.340345 -37.356007) (xy 165.372109 -37.188639) (xy 165.411684 -37.022944) (xy 165.458981 -36.859286)
			(xy 165.513898 -36.698025) (xy 165.576313 -36.539515) (xy 165.646089 -36.384105) (xy 165.723072 -36.232137)
			(xy 165.807094 -36.083943) (xy 165.89797 -35.939851) (xy 165.9955 -35.800177) (xy 166.09947 -35.665228)
			(xy 166.209651 -35.5353) (xy 166.3258 -35.41068) (xy 166.447664 -35.291641) (xy 166.574972 -35.178445)
			(xy 166.707447 -35.07134) (xy 166.844797 -34.970563) (xy 166.986719 -34.876334) (xy 167.132901 -34.788861)
			(xy 167.283024 -34.708336) (xy 167.436755 -34.634936) (xy 167.593758 -34.568822) (xy 167.753688 -34.51014)
			(xy 167.916192 -34.459019) (xy 168.080913 -34.415571) (xy 168.247491 -34.379892) (xy 168.415557 -34.35206)
			(xy 168.584743 -34.332136) (xy 168.754677 -34.320164) (xy 168.924986 -34.316171) (xy 169.095295 -34.320164)
			(xy 169.265229 -34.332136) (xy 169.434415 -34.35206) (xy 169.602481 -34.379892) (xy 169.769059 -34.415571)
			(xy 169.93378 -34.459019) (xy 170.096284 -34.51014) (xy 170.256214 -34.568822) (xy 170.413217 -34.634936)
			(xy 170.566948 -34.708336) (xy 170.717071 -34.788861) (xy 170.863253 -34.876334) (xy 171.005175 -34.970563)
			(xy 171.142525 -35.07134) (xy 171.275 -35.178445) (xy 171.402308 -35.291641) (xy 171.523084 -35.409617)
			(xy 179.589712 -35.409617) (xy 179.593616 -35.305116) (xy 179.60531 -35.201197) (xy 179.624729 -35.098442)
			(xy 179.651763 -34.997422) (xy 179.686262 -34.898703) (xy 179.728034 -34.802833) (xy 179.776846 -34.71035)
			(xy 179.832424 -34.621768) (xy 179.89446 -34.537581) (xy 179.962607 -34.458261) (xy 180.036485 -34.384248)
			(xy 180.115681 -34.315956) (xy 180.199754 -34.253767) (xy 180.243734 -34.225484) (xy 180.25491 -34.218372)
			(xy 180.267356 -34.19602) (xy 180.267356 -34.083244) (xy 180.25491 -34.060892) (xy 180.243734 -34.05378)
			(xy 180.199782 -34.025453) (xy 180.115707 -33.963265) (xy 180.03651 -33.894975) (xy 179.96263 -33.820964)
			(xy 179.894482 -33.741645) (xy 179.832444 -33.65746) (xy 179.776863 -33.56888) (xy 179.728049 -33.476397)
			(xy 179.686275 -33.380529) (xy 179.651773 -33.28181) (xy 179.624736 -33.180792) (xy 179.605315 -33.078036)
			(xy 179.593619 -32.974118) (xy 179.589712 -32.869617) (xy 179.593616 -32.765116) (xy 179.60531 -32.661197)
			(xy 179.624729 -32.558442) (xy 179.651763 -32.457422) (xy 179.686262 -32.358703) (xy 179.728034 -32.262833)
			(xy 179.776846 -32.17035) (xy 179.832424 -32.081768) (xy 179.89446 -31.997581) (xy 179.962607 -31.918261)
			(xy 180.036485 -31.844248) (xy 180.115681 -31.775956) (xy 180.199754 -31.713767) (xy 180.243734 -31.685484)
			(xy 180.25491 -31.678372) (xy 180.267356 -31.65602) (xy 180.267356 -31.543244) (xy 180.25491 -31.520892)
			(xy 180.243734 -31.51378) (xy 180.198088 -31.484366) (xy 180.110965 -31.419535) (xy 180.029129 -31.348147)
			(xy 179.953072 -31.27063) (xy 179.883253 -31.187451) (xy 179.82009 -31.099111) (xy 179.763965 -31.006141)
			(xy 179.715214 -30.9091) (xy 179.674132 -30.808573) (xy 179.640965 -30.705163) (xy 179.615913 -30.599495)
			(xy 179.599126 -30.492202) (xy 179.590707 -30.383931) (xy 179.590192 -30.329632) (xy 179.590669 -30.277276)
			(xy 179.598492 -30.172858) (xy 179.614099 -30.069316) (xy 179.6374 -29.967231) (xy 179.668266 -29.867172)
			(xy 179.706525 -29.7697) (xy 179.751961 -29.675361) (xy 179.804321 -29.584681) (xy 179.863313 -29.498168)
			(xy 179.928605 -29.416307) (xy 179.999834 -29.339554) (xy 180.076599 -29.26834) (xy 180.158473 -29.203062)
			(xy 180.244996 -29.144086) (xy 180.335685 -29.091742) (xy 180.430033 -29.046323) (xy 180.527512 -29.008082)
			(xy 180.627576 -28.977234) (xy 180.729666 -28.953951) (xy 180.83321 -28.938364) (xy 180.93763 -28.930559)
			(xy 180.989986 -28.930092) (xy 181.04428 -28.93057) (xy 181.152542 -28.938984) (xy 181.259826 -28.955761)
			(xy 181.365488 -28.980801) (xy 181.468891 -29.013953) (xy 181.569415 -29.055018) (xy 181.666455 -29.10375)
			(xy 181.759426 -29.159854) (xy 181.847771 -29.222994) (xy 181.930957 -29.29279) (xy 182.008485 -29.368822)
			(xy 182.079887 -29.450632) (xy 182.144736 -29.53773) (xy 182.174134 -29.58338) (xy 182.181246 -29.594556)
			(xy 182.203598 -29.607002) (xy 182.316374 -29.607002) (xy 182.338726 -29.594556) (xy 182.345838 -29.58338)
			(xy 182.375221 -29.537722) (xy 182.440077 -29.450633) (xy 182.511486 -29.36883) (xy 182.589018 -29.292806)
			(xy 182.672208 -29.223017) (xy 182.760554 -29.159884) (xy 182.853527 -29.103785) (xy 182.950566 -29.055059)
			(xy 183.051089 -29.013997) (xy 183.154491 -28.980848) (xy 183.260151 -28.955809) (xy 183.367433 -28.939033)
			(xy 183.475693 -28.930618) (xy 183.529986 -28.930092) (xy 183.582338 -28.930608) (xy 183.686749 -28.938431)
			(xy 183.790283 -28.954033) (xy 183.892362 -28.977328) (xy 183.992415 -29.008186) (xy 184.089883 -29.046433)
			(xy 184.18422 -29.091856) (xy 184.2749 -29.144202) (xy 184.361415 -29.203176) (xy 184.443281 -29.268451)
			(xy 184.520041 -29.33966) (xy 184.591265 -29.416405) (xy 184.656556 -29.498258) (xy 184.715548 -29.584761)
			(xy 184.767912 -29.67543) (xy 184.813354 -29.769758) (xy 184.851621 -29.867218) (xy 184.882499 -29.967265)
			(xy 184.905814 -30.06934) (xy 184.921437 -30.172871) (xy 184.929281 -30.27728) (xy 184.92978 -30.329632)
			(xy 184.929276 -30.383932) (xy 184.920857 -30.492205) (xy 184.904071 -30.599499) (xy 184.87902 -30.70517)
			(xy 184.845853 -30.808581) (xy 184.804772 -30.909111) (xy 184.756023 -31.006154) (xy 184.699899 -31.099127)
			(xy 184.636737 -31.18747) (xy 184.566919 -31.270653) (xy 184.490864 -31.348173) (xy 184.409029 -31.419566)
			(xy 184.321907 -31.484402) (xy 184.276238 -31.51378) (xy 184.265062 -31.520892) (xy 184.252616 -31.543244)
			(xy 184.252616 -31.65602) (xy 184.265062 -31.678372) (xy 184.276238 -31.685484) (xy 184.320247 -31.713723)
			(xy 184.404319 -31.775918) (xy 184.483515 -31.844214) (xy 184.557391 -31.918231) (xy 184.625537 -31.997556)
			(xy 184.687572 -32.081746) (xy 184.74315 -32.170331) (xy 184.791961 -32.262818) (xy 184.833732 -32.35869)
			(xy 184.868231 -32.457412) (xy 184.895265 -32.558434) (xy 184.914682 -32.661192) (xy 184.926376 -32.765113)
			(xy 184.930281 -32.869617) (xy 184.926374 -32.974121) (xy 184.914677 -33.078041) (xy 184.895257 -33.180799)
			(xy 184.868221 -33.28182) (xy 184.83372 -33.380542) (xy 184.791946 -33.476413) (xy 184.743133 -33.568899)
			(xy 184.687553 -33.657483) (xy 184.625516 -33.741671) (xy 184.557368 -33.820994) (xy 184.48349 -33.895009)
			(xy 184.404293 -33.963304) (xy 184.320219 -34.025496) (xy 184.276238 -34.05378) (xy 184.265062 -34.060892)
			(xy 184.252616 -34.083244) (xy 184.252616 -34.19602) (xy 184.265062 -34.218372) (xy 184.276238 -34.225484)
			(xy 184.320247 -34.253723) (xy 184.404319 -34.315918) (xy 184.483515 -34.384214) (xy 184.557391 -34.458231)
			(xy 184.625537 -34.537556) (xy 184.687572 -34.621746) (xy 184.74315 -34.710331) (xy 184.791961 -34.802818)
			(xy 184.833732 -34.89869) (xy 184.868231 -34.997412) (xy 184.895265 -35.098434) (xy 184.914682 -35.201192)
			(xy 184.926376 -35.305113) (xy 184.930281 -35.409617) (xy 188.479712 -35.409617) (xy 188.483616 -35.305116)
			(xy 188.49531 -35.201197) (xy 188.514729 -35.098442) (xy 188.541763 -34.997422) (xy 188.576262 -34.898703)
			(xy 188.618034 -34.802833) (xy 188.666846 -34.71035) (xy 188.722424 -34.621768) (xy 188.78446 -34.537581)
			(xy 188.852607 -34.458261) (xy 188.926485 -34.384248) (xy 189.005681 -34.315956) (xy 189.089754 -34.253767)
			(xy 189.133734 -34.225484) (xy 189.14491 -34.218372) (xy 189.157356 -34.19602) (xy 189.157356 -34.083244)
			(xy 189.14491 -34.060892) (xy 189.133734 -34.05378) (xy 189.089782 -34.025453) (xy 189.005707 -33.963265)
			(xy 188.92651 -33.894975) (xy 188.85263 -33.820964) (xy 188.784482 -33.741645) (xy 188.722444 -33.65746)
			(xy 188.666863 -33.56888) (xy 188.618049 -33.476397) (xy 188.576275 -33.380529) (xy 188.541773 -33.28181)
			(xy 188.514736 -33.180792) (xy 188.495315 -33.078036) (xy 188.483619 -32.974118) (xy 188.479712 -32.869617)
			(xy 188.483616 -32.765116) (xy 188.49531 -32.661197) (xy 188.514729 -32.558442) (xy 188.541763 -32.457422)
			(xy 188.576262 -32.358703) (xy 188.618034 -32.262833) (xy 188.666846 -32.17035) (xy 188.722424 -32.081768)
			(xy 188.78446 -31.997581) (xy 188.852607 -31.918261) (xy 188.926485 -31.844248) (xy 189.005681 -31.775956)
			(xy 189.089754 -31.713767) (xy 189.133734 -31.685484) (xy 189.14491 -31.678372) (xy 189.157356 -31.65602)
			(xy 189.157356 -31.543244) (xy 189.14491 -31.520892) (xy 189.133734 -31.51378) (xy 189.088088 -31.484366)
			(xy 189.000965 -31.419535) (xy 188.919129 -31.348147) (xy 188.843072 -31.27063) (xy 188.773253 -31.187451)
			(xy 188.71009 -31.099111) (xy 188.653965 -31.006141) (xy 188.605214 -30.9091) (xy 188.564132 -30.808573)
			(xy 188.530965 -30.705163) (xy 188.505913 -30.599495) (xy 188.489126 -30.492202) (xy 188.480707 -30.383931)
			(xy 188.480192 -30.329632) (xy 188.480669 -30.277276) (xy 188.488492 -30.172858) (xy 188.504099 -30.069316)
			(xy 188.5274 -29.967231) (xy 188.558266 -29.867172) (xy 188.596525 -29.7697) (xy 188.641961 -29.675361)
			(xy 188.694321 -29.584681) (xy 188.753313 -29.498168) (xy 188.818605 -29.416307) (xy 188.889834 -29.339554)
			(xy 188.966599 -29.26834) (xy 189.048473 -29.203062) (xy 189.134996 -29.144086) (xy 189.225685 -29.091742)
			(xy 189.320033 -29.046323) (xy 189.417512 -29.008082) (xy 189.517576 -28.977234) (xy 189.619666 -28.953951)
			(xy 189.72321 -28.938364) (xy 189.82763 -28.930559) (xy 189.879986 -28.930092) (xy 189.93428 -28.93057)
			(xy 190.042542 -28.938984) (xy 190.149826 -28.955761) (xy 190.255488 -28.980801) (xy 190.358891 -29.013953)
			(xy 190.459415 -29.055018) (xy 190.556455 -29.10375) (xy 190.649426 -29.159854) (xy 190.737771 -29.222994)
			(xy 190.820957 -29.29279) (xy 190.898485 -29.368822) (xy 190.969887 -29.450632) (xy 191.034736 -29.53773)
			(xy 191.064134 -29.58338) (xy 191.071246 -29.594556) (xy 191.093598 -29.607002) (xy 191.206374 -29.607002)
			(xy 191.228726 -29.594556) (xy 191.235838 -29.58338) (xy 191.265221 -29.537722) (xy 191.330077 -29.450633)
			(xy 191.401486 -29.36883) (xy 191.479018 -29.292806) (xy 191.562208 -29.223017) (xy 191.650554 -29.159884)
			(xy 191.743527 -29.103785) (xy 191.840566 -29.055059) (xy 191.941089 -29.013997) (xy 192.044491 -28.980848)
			(xy 192.150151 -28.955809) (xy 192.257433 -28.939033) (xy 192.365693 -28.930618) (xy 192.419986 -28.930092)
			(xy 192.472338 -28.930608) (xy 192.576749 -28.938431) (xy 192.680283 -28.954033) (xy 192.782362 -28.977328)
			(xy 192.882415 -29.008186) (xy 192.979883 -29.046433) (xy 193.07422 -29.091856) (xy 193.1649 -29.144202)
			(xy 193.251415 -29.203176) (xy 193.333281 -29.268451) (xy 193.410041 -29.33966) (xy 193.481265 -29.416405)
			(xy 193.546556 -29.498258) (xy 193.605548 -29.584761) (xy 193.657912 -29.67543) (xy 193.703354 -29.769758)
			(xy 193.741621 -29.867218) (xy 193.772499 -29.967265) (xy 193.795814 -30.06934) (xy 193.811437 -30.172871)
			(xy 193.819281 -30.27728) (xy 193.81978 -30.329632) (xy 193.819276 -30.383932) (xy 193.810857 -30.492205)
			(xy 193.794071 -30.599499) (xy 193.76902 -30.70517) (xy 193.735853 -30.808581) (xy 193.694772 -30.909111)
			(xy 193.646023 -31.006154) (xy 193.589899 -31.099127) (xy 193.526737 -31.18747) (xy 193.456919 -31.270653)
			(xy 193.380864 -31.348173) (xy 193.299029 -31.419566) (xy 193.211907 -31.484402) (xy 193.166238 -31.51378)
			(xy 193.155062 -31.520892) (xy 193.142616 -31.543244) (xy 193.142616 -31.65602) (xy 193.155062 -31.678372)
			(xy 193.166238 -31.685484) (xy 193.210247 -31.713723) (xy 193.294319 -31.775918) (xy 193.373515 -31.844214)
			(xy 193.447391 -31.918231) (xy 193.515537 -31.997556) (xy 193.577572 -32.081746) (xy 193.63315 -32.170331)
			(xy 193.681961 -32.262818) (xy 193.723732 -32.35869) (xy 193.758231 -32.457412) (xy 193.785265 -32.558434)
			(xy 193.804682 -32.661192) (xy 193.816376 -32.765113) (xy 193.820281 -32.869617) (xy 193.816374 -32.974121)
			(xy 193.804677 -33.078041) (xy 193.785257 -33.180799) (xy 193.758221 -33.28182) (xy 193.72372 -33.380542)
			(xy 193.681946 -33.476413) (xy 193.633133 -33.568899) (xy 193.577553 -33.657483) (xy 193.515516 -33.741671)
			(xy 193.447368 -33.820994) (xy 193.37349 -33.895009) (xy 193.294293 -33.963304) (xy 193.210219 -34.025496)
			(xy 193.166238 -34.05378) (xy 193.155062 -34.060892) (xy 193.142616 -34.083244) (xy 193.142616 -34.19602)
			(xy 193.155062 -34.218372) (xy 193.166238 -34.225484) (xy 193.210247 -34.253723) (xy 193.294319 -34.315918)
			(xy 193.373515 -34.384214) (xy 193.447391 -34.458231) (xy 193.515537 -34.537556) (xy 193.577572 -34.621746)
			(xy 193.63315 -34.710331) (xy 193.681961 -34.802818) (xy 193.723732 -34.89869) (xy 193.758231 -34.997412)
			(xy 193.785265 -35.098434) (xy 193.804682 -35.201192) (xy 193.816376 -35.305113) (xy 193.820281 -35.409617)
			(xy 197.369712 -35.409617) (xy 197.373616 -35.305116) (xy 197.38531 -35.201197) (xy 197.404729 -35.098442)
			(xy 197.431763 -34.997422) (xy 197.466262 -34.898703) (xy 197.508034 -34.802833) (xy 197.556846 -34.71035)
			(xy 197.612424 -34.621768) (xy 197.67446 -34.537581) (xy 197.742607 -34.458261) (xy 197.816485 -34.384248)
			(xy 197.895681 -34.315956) (xy 197.979754 -34.253767) (xy 198.023734 -34.225484) (xy 198.03491 -34.218372)
			(xy 198.047356 -34.19602) (xy 198.047356 -34.083244) (xy 198.03491 -34.060892) (xy 198.023734 -34.05378)
			(xy 197.979782 -34.025453) (xy 197.895707 -33.963265) (xy 197.81651 -33.894975) (xy 197.74263 -33.820964)
			(xy 197.674482 -33.741645) (xy 197.612444 -33.65746) (xy 197.556863 -33.56888) (xy 197.508049 -33.476397)
			(xy 197.466275 -33.380529) (xy 197.431773 -33.28181) (xy 197.404736 -33.180792) (xy 197.385315 -33.078036)
			(xy 197.373619 -32.974118) (xy 197.369712 -32.869617) (xy 197.373616 -32.765116) (xy 197.38531 -32.661197)
			(xy 197.404729 -32.558442) (xy 197.431763 -32.457422) (xy 197.466262 -32.358703) (xy 197.508034 -32.262833)
			(xy 197.556846 -32.17035) (xy 197.612424 -32.081768) (xy 197.67446 -31.997581) (xy 197.742607 -31.918261)
			(xy 197.816485 -31.844248) (xy 197.895681 -31.775956) (xy 197.979754 -31.713767) (xy 198.023734 -31.685484)
			(xy 198.03491 -31.678372) (xy 198.047356 -31.65602) (xy 198.047356 -31.543244) (xy 198.03491 -31.520892)
			(xy 198.023734 -31.51378) (xy 197.978088 -31.484366) (xy 197.890965 -31.419535) (xy 197.809129 -31.348147)
			(xy 197.733072 -31.27063) (xy 197.663253 -31.187451) (xy 197.60009 -31.099111) (xy 197.543965 -31.006141)
			(xy 197.495214 -30.9091) (xy 197.454132 -30.808573) (xy 197.420965 -30.705163) (xy 197.395913 -30.599495)
			(xy 197.379126 -30.492202) (xy 197.370707 -30.383931) (xy 197.370192 -30.329632) (xy 197.370669 -30.277276)
			(xy 197.378492 -30.172858) (xy 197.394099 -30.069316) (xy 197.4174 -29.967231) (xy 197.448266 -29.867172)
			(xy 197.486525 -29.7697) (xy 197.531961 -29.675361) (xy 197.584321 -29.584681) (xy 197.643313 -29.498168)
			(xy 197.708605 -29.416307) (xy 197.779834 -29.339554) (xy 197.856599 -29.26834) (xy 197.938473 -29.203062)
			(xy 198.024996 -29.144086) (xy 198.115685 -29.091742) (xy 198.210033 -29.046323) (xy 198.307512 -29.008082)
			(xy 198.407576 -28.977234) (xy 198.509666 -28.953951) (xy 198.61321 -28.938364) (xy 198.71763 -28.930559)
			(xy 198.769986 -28.930092) (xy 198.82428 -28.93057) (xy 198.932542 -28.938984) (xy 199.039826 -28.955761)
			(xy 199.145488 -28.980801) (xy 199.248891 -29.013953) (xy 199.349415 -29.055018) (xy 199.446455 -29.10375)
			(xy 199.539426 -29.159854) (xy 199.627771 -29.222994) (xy 199.710957 -29.29279) (xy 199.788485 -29.368822)
			(xy 199.859887 -29.450632) (xy 199.924736 -29.53773) (xy 199.954134 -29.58338) (xy 199.961246 -29.594556)
			(xy 199.983598 -29.607002) (xy 200.096374 -29.607002) (xy 200.118726 -29.594556) (xy 200.125838 -29.58338)
			(xy 200.155221 -29.537722) (xy 200.220077 -29.450633) (xy 200.291486 -29.36883) (xy 200.369018 -29.292806)
			(xy 200.452208 -29.223017) (xy 200.540554 -29.159884) (xy 200.633527 -29.103785) (xy 200.730566 -29.055059)
			(xy 200.831089 -29.013997) (xy 200.934491 -28.980848) (xy 201.040151 -28.955809) (xy 201.147433 -28.939033)
			(xy 201.255693 -28.930618) (xy 201.309986 -28.930092) (xy 201.362338 -28.930608) (xy 201.466749 -28.938431)
			(xy 201.570283 -28.954033) (xy 201.672362 -28.977328) (xy 201.772415 -29.008186) (xy 201.869883 -29.046433)
			(xy 201.96422 -29.091856) (xy 202.0549 -29.144202) (xy 202.141415 -29.203176) (xy 202.223281 -29.268451)
			(xy 202.300041 -29.33966) (xy 202.371265 -29.416405) (xy 202.436556 -29.498258) (xy 202.495548 -29.584761)
			(xy 202.547912 -29.67543) (xy 202.593354 -29.769758) (xy 202.631621 -29.867218) (xy 202.662499 -29.967265)
			(xy 202.685814 -30.06934) (xy 202.701437 -30.172871) (xy 202.709281 -30.27728) (xy 202.70978 -30.329632)
			(xy 202.709276 -30.383932) (xy 202.700857 -30.492205) (xy 202.684071 -30.599499) (xy 202.663256 -30.6873)
			(xy 284.351952 -30.6873) (xy 284.355982 -30.602696) (xy 284.368036 -30.518857) (xy 284.388005 -30.436544)
			(xy 284.415708 -30.356502) (xy 284.450893 -30.279456) (xy 284.493244 -30.206103) (xy 284.542375 -30.137109)
			(xy 284.597842 -30.073096) (xy 284.659142 -30.014646) (xy 284.725721 -29.962288) (xy 284.796976 -29.916495)
			(xy 284.87226 -29.877683) (xy 284.950894 -29.846203) (xy 285.032163 -29.822341) (xy 285.115333 -29.806311)
			(xy 285.19965 -29.79826) (xy 285.242 -29.797756) (xy 285.288396 -29.798333) (xy 285.380684 -29.807979)
			(xy 285.471468 -29.827177) (xy 285.559762 -29.855717) (xy 285.602426 -29.873956) (xy 285.612368 -29.877762)
			(xy 285.633632 -29.877762) (xy 285.643574 -29.873956) (xy 285.686235 -29.855709) (xy 285.774528 -29.827166)
			(xy 285.865313 -29.807974) (xy 285.957604 -29.798341) (xy 286.004 -29.797756) (xy 286.047483 -29.798269)
			(xy 286.134036 -29.806754) (xy 286.219347 -29.823643) (xy 286.302603 -29.848776) (xy 286.38301 -29.881911)
			(xy 286.459801 -29.922733) (xy 286.532242 -29.970853) (xy 286.599643 -30.025811) (xy 286.630872 -30.056074)
			(xy 286.638238 -30.063186) (xy 286.656526 -30.070806) (xy 286.748474 -30.070806) (xy 286.766762 -30.063186)
			(xy 286.774128 -30.056074) (xy 286.805348 -30.025802) (xy 286.872752 -29.970849) (xy 286.945196 -29.922734)
			(xy 287.021989 -29.881915) (xy 287.102397 -29.848783) (xy 287.185654 -29.823654) (xy 287.270965 -29.806766)
			(xy 287.357517 -29.798282) (xy 287.401 -29.797756) (xy 287.447396 -29.798333) (xy 287.539684 -29.807979)
			(xy 287.630468 -29.827177) (xy 287.718762 -29.855717) (xy 287.761426 -29.873956) (xy 287.771368 -29.877762)
			(xy 287.792632 -29.877762) (xy 287.802574 -29.873956) (xy 287.845235 -29.855709) (xy 287.933528 -29.827166)
			(xy 288.024313 -29.807974) (xy 288.116604 -29.798341) (xy 288.163 -29.797756) (xy 288.205347 -29.798332)
			(xy 288.289657 -29.806382) (xy 288.37282 -29.822411) (xy 288.454083 -29.846271) (xy 288.53271 -29.877749)
			(xy 288.607988 -29.916558) (xy 288.679237 -29.962347) (xy 288.745811 -30.014701) (xy 288.807106 -30.073146)
			(xy 288.862569 -30.137153) (xy 288.911696 -30.206142) (xy 288.954043 -30.279489) (xy 288.989226 -30.356529)
			(xy 289.016926 -30.436565) (xy 289.036893 -30.518871) (xy 289.048947 -30.602702) (xy 289.052977 -30.6873)
			(xy 289.048947 -30.771898) (xy 289.036893 -30.855729) (xy 289.016926 -30.938035) (xy 288.989226 -31.018071)
			(xy 288.954043 -31.095111) (xy 288.911696 -31.168458) (xy 288.862569 -31.237447) (xy 288.807106 -31.301454)
			(xy 288.745811 -31.359899) (xy 288.679237 -31.412253) (xy 288.607988 -31.458042) (xy 288.53271 -31.496851)
			(xy 288.454083 -31.528329) (xy 288.37282 -31.552189) (xy 288.289657 -31.568218) (xy 288.205347 -31.576268)
			(xy 288.163 -31.576772) (xy 288.116604 -31.576192) (xy 288.024316 -31.566547) (xy 287.933532 -31.54735)
			(xy 287.845239 -31.518811) (xy 287.802574 -31.500572) (xy 287.792632 -31.496766) (xy 287.771368 -31.496766)
			(xy 287.761426 -31.500572) (xy 287.718763 -31.518815) (xy 287.630471 -31.54736) (xy 287.539686 -31.566553)
			(xy 287.447396 -31.576187) (xy 287.401 -31.576772) (xy 287.357516 -31.57628) (xy 287.270963 -31.567794)
			(xy 287.18565 -31.550903) (xy 287.102393 -31.525769) (xy 287.021986 -31.492631) (xy 286.945195 -31.451805)
			(xy 286.872755 -31.403681) (xy 286.805356 -31.348719) (xy 286.774128 -31.318454) (xy 286.766762 -31.311342)
			(xy 286.748474 -31.303722) (xy 286.656526 -31.303722) (xy 286.638238 -31.311342) (xy 286.630872 -31.318454)
			(xy 286.599639 -31.348712) (xy 286.532238 -31.403668) (xy 286.459797 -31.451787) (xy 286.383007 -31.492607)
			(xy 286.3026 -31.525741) (xy 286.219344 -31.550873) (xy 286.134034 -31.567761) (xy 286.047483 -31.576246)
			(xy 286.004 -31.576772) (xy 285.957604 -31.576192) (xy 285.865316 -31.566547) (xy 285.774532 -31.54735)
			(xy 285.686239 -31.518811) (xy 285.643574 -31.500572) (xy 285.633632 -31.496766) (xy 285.612368 -31.496766)
			(xy 285.602426 -31.500572) (xy 285.559763 -31.518815) (xy 285.471471 -31.54736) (xy 285.380686 -31.566553)
			(xy 285.288396 -31.576187) (xy 285.242 -31.576772) (xy 285.19965 -31.57634) (xy 285.115333 -31.568289)
			(xy 285.032163 -31.552259) (xy 284.950894 -31.528397) (xy 284.87226 -31.496917) (xy 284.796976 -31.458105)
			(xy 284.725721 -31.412312) (xy 284.659142 -31.359954) (xy 284.597842 -31.301504) (xy 284.542375 -31.237491)
			(xy 284.493244 -31.168497) (xy 284.450893 -31.095144) (xy 284.415708 -31.018098) (xy 284.388005 -30.938056)
			(xy 284.368036 -30.855743) (xy 284.355982 -30.771904) (xy 284.351952 -30.6873) (xy 202.663256 -30.6873)
			(xy 202.65902 -30.70517) (xy 202.625853 -30.808581) (xy 202.584772 -30.909111) (xy 202.536023 -31.006154)
			(xy 202.479899 -31.099127) (xy 202.416737 -31.18747) (xy 202.346919 -31.270653) (xy 202.270864 -31.348173)
			(xy 202.189029 -31.419566) (xy 202.101907 -31.484402) (xy 202.056238 -31.51378) (xy 202.045062 -31.520892)
			(xy 202.032616 -31.543244) (xy 202.032616 -31.65602) (xy 202.045062 -31.678372) (xy 202.056238 -31.685484)
			(xy 202.100247 -31.713723) (xy 202.184319 -31.775918) (xy 202.263515 -31.844214) (xy 202.337391 -31.918231)
			(xy 202.405537 -31.997556) (xy 202.467572 -32.081746) (xy 202.52315 -32.170331) (xy 202.571961 -32.262818)
			(xy 202.613732 -32.35869) (xy 202.648231 -32.457412) (xy 202.675265 -32.558434) (xy 202.694682 -32.661192)
			(xy 202.706376 -32.765113) (xy 202.710281 -32.869617) (xy 202.706374 -32.974121) (xy 202.694677 -33.078041)
			(xy 202.688184 -33.112399) (xy 274.529292 -33.112399) (xy 274.529292 -33.027677) (xy 274.537345 -32.94334)
			(xy 274.553379 -32.86015) (xy 274.577247 -32.77886) (xy 274.608735 -32.700208) (xy 274.647557 -32.624905)
			(xy 274.69336 -32.553633) (xy 274.745731 -32.487037) (xy 274.804196 -32.425722) (xy 274.868224 -32.370241)
			(xy 274.937236 -32.321098) (xy 275.010606 -32.278738) (xy 275.087671 -32.243543) (xy 275.167733 -32.215834)
			(xy 275.250066 -32.19586) (xy 275.333925 -32.183803) (xy 275.41855 -32.179772) (xy 275.503175 -32.183803)
			(xy 275.587034 -32.19586) (xy 275.598955 -32.198752) (xy 282.524141 -32.198752) (xy 282.524141 -32.114048)
			(xy 282.532193 -32.029727) (xy 282.548223 -31.946554) (xy 282.572088 -31.865281) (xy 282.60357 -31.786644)
			(xy 282.642385 -31.711356) (xy 282.68818 -31.640099) (xy 282.740542 -31.573518) (xy 282.798996 -31.512216)
			(xy 282.863012 -31.456748) (xy 282.932012 -31.407616) (xy 282.968446 -31.386018) (xy 283.002302 -31.366983)
			(xy 283.072707 -31.334173) (xy 283.145705 -31.307624) (xy 283.220737 -31.287536) (xy 283.297235 -31.274064)
			(xy 283.374616 -31.267309) (xy 283.413454 -31.266892) (xy 283.455805 -31.267378) (xy 283.540123 -31.275425)
			(xy 283.623294 -31.291451) (xy 283.704565 -31.315311) (xy 283.783201 -31.346788) (xy 283.858487 -31.385598)
			(xy 283.929744 -31.431388) (xy 283.996325 -31.483745) (xy 284.057628 -31.542194) (xy 284.113097 -31.606206)
			(xy 284.16223 -31.6752) (xy 284.204582 -31.748553) (xy 284.239769 -31.8256) (xy 284.267473 -31.905642)
			(xy 284.287443 -31.987956) (xy 284.299498 -32.071795) (xy 284.303528 -32.1564) (xy 284.299498 -32.241005)
			(xy 284.287443 -32.324844) (xy 284.267473 -32.407158) (xy 284.239769 -32.4872) (xy 284.204582 -32.564247)
			(xy 284.16223 -32.6376) (xy 284.113097 -32.706594) (xy 284.057628 -32.770606) (xy 283.996325 -32.829055)
			(xy 283.929744 -32.881412) (xy 283.858487 -32.927202) (xy 283.783201 -32.966012) (xy 283.704565 -32.997489)
			(xy 283.623294 -33.021349) (xy 283.540123 -33.037375) (xy 283.455805 -33.045422) (xy 283.413454 -33.045908)
			(xy 283.374614 -33.045521) (xy 283.297228 -33.038783) (xy 283.220725 -33.025319) (xy 283.145688 -33.005231)
			(xy 283.07269 -32.978672) (xy 283.002287 -32.945846) (xy 282.968446 -32.926782) (xy 282.932012 -32.905184)
			(xy 282.863012 -32.856052) (xy 282.798996 -32.800584) (xy 282.740542 -32.739282) (xy 282.68818 -32.672701)
			(xy 282.642385 -32.601444) (xy 282.60357 -32.526156) (xy 282.572088 -32.447519) (xy 282.548223 -32.366246)
			(xy 282.532193 -32.283073) (xy 282.524141 -32.198752) (xy 275.598955 -32.198752) (xy 275.669367 -32.215834)
			(xy 275.749429 -32.243543) (xy 275.826494 -32.278738) (xy 275.899864 -32.321098) (xy 275.968876 -32.370241)
			(xy 276.032904 -32.425722) (xy 276.091369 -32.487037) (xy 276.14374 -32.553633) (xy 276.189543 -32.624905)
			(xy 276.228365 -32.700208) (xy 276.259853 -32.77886) (xy 276.283721 -32.86015) (xy 276.299755 -32.94334)
			(xy 276.307808 -33.027677) (xy 276.308312 -33.070038) (xy 276.307808 -33.112399) (xy 276.299755 -33.196736)
			(xy 276.283721 -33.279926) (xy 276.259853 -33.361216) (xy 276.228365 -33.439868) (xy 276.189543 -33.515171)
			(xy 276.14374 -33.586443) (xy 276.091369 -33.653039) (xy 276.032904 -33.714354) (xy 275.968876 -33.769835)
			(xy 275.899864 -33.818978) (xy 275.826494 -33.861338) (xy 275.749429 -33.896533) (xy 275.669367 -33.924242)
			(xy 275.587034 -33.944216) (xy 275.503175 -33.956273) (xy 275.41855 -33.960305) (xy 275.333925 -33.956273)
			(xy 275.250066 -33.944216) (xy 275.167733 -33.924242) (xy 275.087671 -33.896533) (xy 275.010606 -33.861338)
			(xy 274.937236 -33.818978) (xy 274.868224 -33.769835) (xy 274.804196 -33.714354) (xy 274.745731 -33.653039)
			(xy 274.69336 -33.586443) (xy 274.647557 -33.515171) (xy 274.608735 -33.439868) (xy 274.577247 -33.361216)
			(xy 274.553379 -33.279926) (xy 274.537345 -33.196736) (xy 274.529292 -33.112399) (xy 202.688184 -33.112399)
			(xy 202.675257 -33.180799) (xy 202.648221 -33.28182) (xy 202.61372 -33.380542) (xy 202.571946 -33.476413)
			(xy 202.523133 -33.568899) (xy 202.467553 -33.657483) (xy 202.405516 -33.741671) (xy 202.337368 -33.820994)
			(xy 202.26349 -33.895009) (xy 202.184293 -33.963304) (xy 202.100219 -34.025496) (xy 202.056238 -34.05378)
			(xy 202.045062 -34.060892) (xy 202.032616 -34.083244) (xy 202.032616 -34.19602) (xy 202.045062 -34.218372)
			(xy 202.056238 -34.225484) (xy 202.100247 -34.253723) (xy 202.184319 -34.315918) (xy 202.263515 -34.384214)
			(xy 202.337391 -34.458231) (xy 202.405537 -34.537556) (xy 202.467572 -34.621746) (xy 202.52315 -34.710331)
			(xy 202.571961 -34.802818) (xy 202.613732 -34.89869) (xy 202.648231 -34.997412) (xy 202.675265 -35.098434)
			(xy 202.694682 -35.201192) (xy 202.706376 -35.305113) (xy 202.710281 -35.409617) (xy 202.706374 -35.514121)
			(xy 202.694677 -35.618041) (xy 202.675257 -35.720799) (xy 202.648221 -35.82182) (xy 202.61372 -35.920542)
			(xy 202.571946 -36.016413) (xy 202.523133 -36.108899) (xy 202.467553 -36.197483) (xy 202.405516 -36.281671)
			(xy 202.337368 -36.360994) (xy 202.26349 -36.435009) (xy 202.184293 -36.503304) (xy 202.100219 -36.565496)
			(xy 202.056238 -36.59378) (xy 202.045062 -36.600892) (xy 202.032616 -36.623244) (xy 202.032616 -36.73602)
			(xy 202.045062 -36.758372) (xy 202.056238 -36.765484) (xy 202.10193 -36.794827) (xy 202.189051 -36.859666)
			(xy 202.270885 -36.931062) (xy 202.346939 -37.008586) (xy 202.416756 -37.091772) (xy 202.479915 -37.180118)
			(xy 202.536037 -37.273094) (xy 202.584783 -37.37014) (xy 202.625861 -37.470673) (xy 202.659024 -37.574087)
			(xy 202.684071 -37.67976) (xy 202.700853 -37.787057) (xy 202.709268 -37.895331) (xy 202.70978 -37.949632)
			(xy 202.709293 -38.001987) (xy 202.706832 -38.03481) (xy 245.302523 -38.03481) (xy 245.302523 -37.864454)
			(xy 245.310508 -37.694286) (xy 245.32646 -37.524679) (xy 245.350345 -37.356007) (xy 245.382109 -37.188639)
			(xy 245.421684 -37.022944) (xy 245.468981 -36.859286) (xy 245.523898 -36.698025) (xy 245.586313 -36.539515)
			(xy 245.656089 -36.384105) (xy 245.733072 -36.232137) (xy 245.817094 -36.083943) (xy 245.90797 -35.939851)
			(xy 246.0055 -35.800177) (xy 246.10947 -35.665228) (xy 246.219651 -35.5353) (xy 246.3358 -35.41068)
			(xy 246.457664 -35.291641) (xy 246.584972 -35.178445) (xy 246.717447 -35.07134) (xy 246.854797 -34.970563)
			(xy 246.996719 -34.876334) (xy 247.142901 -34.788861) (xy 247.293024 -34.708336) (xy 247.446755 -34.634936)
			(xy 247.603758 -34.568822) (xy 247.763688 -34.51014) (xy 247.926192 -34.459019) (xy 248.090913 -34.415571)
			(xy 248.257491 -34.379892) (xy 248.425557 -34.35206) (xy 248.594743 -34.332136) (xy 248.764677 -34.320164)
			(xy 248.934986 -34.316171) (xy 249.105295 -34.320164) (xy 249.275229 -34.332136) (xy 249.444415 -34.35206)
			(xy 249.612481 -34.379892) (xy 249.779059 -34.415571) (xy 249.94378 -34.459019) (xy 250.106284 -34.51014)
			(xy 250.266214 -34.568822) (xy 250.423217 -34.634936) (xy 250.576948 -34.708336) (xy 250.727071 -34.788861)
			(xy 250.873253 -34.876334) (xy 251.015175 -34.970563) (xy 251.080047 -35.018161) (xy 293.293542 -35.018161)
			(xy 293.293542 -34.933439) (xy 293.301595 -34.849102) (xy 293.317629 -34.765912) (xy 293.341497 -34.684622)
			(xy 293.372985 -34.60597) (xy 293.411807 -34.530667) (xy 293.45761 -34.459395) (xy 293.509981 -34.392799)
			(xy 293.568446 -34.331484) (xy 293.632474 -34.276003) (xy 293.701486 -34.22686) (xy 293.774856 -34.1845)
			(xy 293.851921 -34.149305) (xy 293.931983 -34.121596) (xy 294.014316 -34.101622) (xy 294.098175 -34.089565)
			(xy 294.1828 -34.085534) (xy 294.267425 -34.089565) (xy 294.351284 -34.101622) (xy 294.433617 -34.121596)
			(xy 294.513679 -34.149305) (xy 294.590744 -34.1845) (xy 294.664114 -34.22686) (xy 294.733126 -34.276003)
			(xy 294.797154 -34.331484) (xy 294.855619 -34.392799) (xy 294.90799 -34.459395) (xy 294.953793 -34.530667)
			(xy 294.992615 -34.60597) (xy 295.024103 -34.684622) (xy 295.047971 -34.765912) (xy 295.064005 -34.849102)
			(xy 295.072058 -34.933439) (xy 295.072562 -34.9758) (xy 295.072058 -35.018161) (xy 295.064005 -35.102498)
			(xy 295.047971 -35.185688) (xy 295.024103 -35.266978) (xy 294.992615 -35.34563) (xy 294.953793 -35.420933)
			(xy 294.90799 -35.492205) (xy 294.855619 -35.558801) (xy 294.797154 -35.620116) (xy 294.733126 -35.675597)
			(xy 294.664114 -35.72474) (xy 294.590744 -35.7671) (xy 294.513679 -35.802295) (xy 294.433617 -35.830004)
			(xy 294.351284 -35.849978) (xy 294.267425 -35.862035) (xy 294.1828 -35.866067) (xy 294.098175 -35.862035)
			(xy 294.014316 -35.849978) (xy 293.931983 -35.830004) (xy 293.851921 -35.802295) (xy 293.774856 -35.7671)
			(xy 293.701486 -35.72474) (xy 293.632474 -35.675597) (xy 293.568446 -35.620116) (xy 293.509981 -35.558801)
			(xy 293.45761 -35.492205) (xy 293.411807 -35.420933) (xy 293.372985 -35.34563) (xy 293.341497 -35.266978)
			(xy 293.317629 -35.185688) (xy 293.301595 -35.102498) (xy 293.293542 -35.018161) (xy 251.080047 -35.018161)
			(xy 251.152525 -35.07134) (xy 251.285 -35.178445) (xy 251.412308 -35.291641) (xy 251.534172 -35.41068)
			(xy 251.650321 -35.5353) (xy 251.760502 -35.665228) (xy 251.864472 -35.800177) (xy 251.962002 -35.939851)
			(xy 252.052878 -36.083943) (xy 252.1369 -36.232137) (xy 252.213883 -36.384105) (xy 252.283659 -36.539515)
			(xy 252.346074 -36.698025) (xy 252.400991 -36.859286) (xy 252.448288 -37.022944) (xy 252.487863 -37.188639)
			(xy 252.504967 -37.278761) (xy 259.293102 -37.278761) (xy 259.293102 -37.194039) (xy 259.301155 -37.109702)
			(xy 259.317189 -37.026512) (xy 259.341057 -36.945222) (xy 259.372545 -36.86657) (xy 259.411367 -36.791267)
			(xy 259.45717 -36.719995) (xy 259.509541 -36.653399) (xy 259.568006 -36.592084) (xy 259.632034 -36.536603)
			(xy 259.701046 -36.48746) (xy 259.774416 -36.4451) (xy 259.851481 -36.409905) (xy 259.931543 -36.382196)
			(xy 260.013876 -36.362222) (xy 260.097735 -36.350165) (xy 260.18236 -36.346134) (xy 260.266985 -36.350165)
			(xy 260.350844 -36.362222) (xy 260.433177 -36.382196) (xy 260.513239 -36.409905) (xy 260.590304 -36.4451)
			(xy 260.663674 -36.48746) (xy 260.732686 -36.536603) (xy 260.796714 -36.592084) (xy 260.855179 -36.653399)
			(xy 260.90755 -36.719995) (xy 260.953353 -36.791267) (xy 260.992175 -36.86657) (xy 261.023663 -36.945222)
			(xy 261.047531 -37.026512) (xy 261.063565 -37.109702) (xy 261.071618 -37.194039) (xy 261.072122 -37.2364)
			(xy 261.071618 -37.278761) (xy 261.063565 -37.363098) (xy 261.047531 -37.446288) (xy 261.023663 -37.527578)
			(xy 260.992175 -37.60623) (xy 260.953353 -37.681533) (xy 260.90755 -37.752805) (xy 260.855179 -37.819401)
			(xy 260.796714 -37.880716) (xy 260.732686 -37.936197) (xy 260.663674 -37.98534) (xy 260.590304 -38.0277)
			(xy 260.513239 -38.062895) (xy 260.433177 -38.090604) (xy 260.350844 -38.110578) (xy 260.266985 -38.122635)
			(xy 260.18236 -38.126667) (xy 260.097735 -38.122635) (xy 260.013876 -38.110578) (xy 259.931543 -38.090604)
			(xy 259.851481 -38.062895) (xy 259.774416 -38.0277) (xy 259.701046 -37.98534) (xy 259.632034 -37.936197)
			(xy 259.568006 -37.880716) (xy 259.509541 -37.819401) (xy 259.45717 -37.752805) (xy 259.411367 -37.681533)
			(xy 259.372545 -37.60623) (xy 259.341057 -37.527578) (xy 259.317189 -37.446288) (xy 259.301155 -37.363098)
			(xy 259.293102 -37.278761) (xy 252.504967 -37.278761) (xy 252.519627 -37.356007) (xy 252.543512 -37.524679)
			(xy 252.559464 -37.694286) (xy 252.567449 -37.864454) (xy 252.567948 -37.949632) (xy 252.567449 -38.03481)
			(xy 252.559464 -38.204978) (xy 252.543512 -38.374585) (xy 252.519627 -38.543257) (xy 252.487863 -38.710625)
			(xy 252.448288 -38.87632) (xy 252.400991 -39.039978) (xy 252.350882 -39.18712) (xy 257.640836 -39.18712)
			(xy 257.641465 -39.140264) (xy 257.651373 -39.047077) (xy 257.671018 -38.955447) (xy 257.700183 -38.866389)
			(xy 257.718814 -38.823392) (xy 257.722591 -38.813952) (xy 257.723116 -38.793644) (xy 257.71983 -38.784022)
			(xy 257.705286 -38.745426) (xy 257.682591 -38.666124) (xy 257.667328 -38.585063) (xy 257.659626 -38.502938)
			(xy 257.659124 -38.461696) (xy 257.659628 -38.419335) (xy 257.667681 -38.334998) (xy 257.683715 -38.251808)
			(xy 257.707583 -38.170518) (xy 257.739071 -38.091866) (xy 257.777893 -38.016563) (xy 257.823696 -37.945291)
			(xy 257.876067 -37.878695) (xy 257.934532 -37.81738) (xy 257.99856 -37.761899) (xy 258.067572 -37.712756)
			(xy 258.140942 -37.670396) (xy 258.218007 -37.635201) (xy 258.298069 -37.607492) (xy 258.380402 -37.587518)
			(xy 258.464261 -37.575461) (xy 258.548886 -37.57143) (xy 258.633511 -37.575461) (xy 258.71737 -37.587518)
			(xy 258.799703 -37.607492) (xy 258.879765 -37.635201) (xy 258.95683 -37.670396) (xy 259.0302 -37.712756)
			(xy 259.099212 -37.761899) (xy 259.16324 -37.81738) (xy 259.221705 -37.878695) (xy 259.274076 -37.945291)
			(xy 259.319879 -38.016563) (xy 259.358701 -38.091866) (xy 259.390189 -38.170518) (xy 259.414057 -38.251808)
			(xy 259.430091 -38.334998) (xy 259.438144 -38.419335) (xy 259.438648 -38.461696) (xy 259.438331 -38.49433)
			(xy 259.433502 -38.559421) (xy 259.428996 -38.591744) (xy 259.427218 -38.603682) (xy 259.43433 -38.62578)
			(xy 259.506212 -38.700964) (xy 259.528056 -38.709092) (xy 259.53974 -38.707822) (xy 259.562407 -38.705593)
			(xy 259.607896 -38.703178) (xy 259.630672 -38.702996) (xy 259.671782 -38.703479) (xy 259.753652 -38.711065)
			(xy 259.834473 -38.726173) (xy 259.913554 -38.748676) (xy 259.990221 -38.778381) (xy 260.06382 -38.815034)
			(xy 260.133721 -38.858323) (xy 260.19933 -38.907879) (xy 260.260085 -38.963278) (xy 260.315468 -39.024047)
			(xy 260.365007 -39.089669) (xy 260.408278 -39.159581) (xy 260.444912 -39.233189) (xy 260.474597 -39.309864)
			(xy 260.49708 -39.388951) (xy 260.512167 -39.469776) (xy 260.519731 -39.551648) (xy 260.52018 -39.592758)
			(xy 260.519659 -39.635175) (xy 260.511589 -39.719623) (xy 260.495517 -39.80292) (xy 260.47159 -39.884309)
			(xy 260.440025 -39.963051) (xy 260.401108 -40.038431) (xy 260.355193 -40.109764) (xy 260.302698 -40.176404)
			(xy 260.244097 -40.237744) (xy 260.212332 -40.265858) (xy 260.203696 -40.273224) (xy 260.194806 -40.293036)
			(xy 260.194806 -40.392604) (xy 260.203696 -40.412416) (xy 260.212332 -40.419782) (xy 260.24409 -40.447905)
			(xy 260.302694 -40.509243) (xy 260.355193 -40.575881) (xy 260.401112 -40.647213) (xy 260.440033 -40.722591)
			(xy 260.471603 -40.801332) (xy 260.495535 -40.88272) (xy 260.502615 -40.9194) (xy 287.730188 -40.9194)
			(xy 287.734218 -40.834799) (xy 287.746271 -40.750964) (xy 287.766239 -40.668655) (xy 287.793941 -40.588616)
			(xy 287.829125 -40.511573) (xy 287.871474 -40.438223) (xy 287.920603 -40.369231) (xy 287.976068 -40.305221)
			(xy 288.037366 -40.246773) (xy 288.103942 -40.194417) (xy 288.175194 -40.148627) (xy 288.250475 -40.109816)
			(xy 288.329105 -40.078337) (xy 288.410372 -40.054476) (xy 288.493538 -40.038447) (xy 288.577852 -40.030396)
			(xy 288.6202 -40.029892) (xy 288.658991 -40.030305) (xy 288.736279 -40.037037) (xy 288.812687 -40.050475)
			(xy 288.887634 -40.070517) (xy 288.960551 -40.097012) (xy 289.030883 -40.129757) (xy 289.0647 -40.148764)
			(xy 289.072574 -40.152923) (xy 289.0901 -40.156017) (xy 289.107626 -40.152923) (xy 289.1155 -40.148764)
			(xy 289.149326 -40.129773) (xy 289.219657 -40.097028) (xy 289.292572 -40.070532) (xy 289.367517 -40.050487)
			(xy 289.443923 -40.037043) (xy 289.52121 -40.030305) (xy 289.56 -40.029892) (xy 289.602348 -40.030396)
			(xy 289.686662 -40.038447) (xy 289.769828 -40.054476) (xy 289.851095 -40.078337) (xy 289.929725 -40.109816)
			(xy 290.005006 -40.148627) (xy 290.076258 -40.194417) (xy 290.142834 -40.246773) (xy 290.204132 -40.305221)
			(xy 290.259597 -40.369231) (xy 290.308726 -40.438223) (xy 290.351075 -40.511573) (xy 290.386259 -40.588616)
			(xy 290.413961 -40.668655) (xy 290.433929 -40.750964) (xy 290.445982 -40.834799) (xy 290.450013 -40.9194)
			(xy 290.445982 -41.004001) (xy 290.433929 -41.087836) (xy 290.413961 -41.170145) (xy 290.386259 -41.250184)
			(xy 290.351075 -41.327227) (xy 290.308726 -41.400577) (xy 290.259597 -41.469569) (xy 290.204132 -41.533579)
			(xy 290.142834 -41.592027) (xy 290.076258 -41.644383) (xy 290.005006 -41.690173) (xy 289.929725 -41.728984)
			(xy 289.851095 -41.760463) (xy 289.769828 -41.784324) (xy 289.686662 -41.800353) (xy 289.602348 -41.808404)
			(xy 289.56 -41.808908) (xy 289.521209 -41.808495) (xy 289.443921 -41.801763) (xy 289.367513 -41.788325)
			(xy 289.292566 -41.768283) (xy 289.219649 -41.741788) (xy 289.149317 -41.709043) (xy 289.1155 -41.690036)
			(xy 289.107626 -41.685877) (xy 289.0901 -41.682783) (xy 289.072574 -41.685877) (xy 289.0647 -41.690036)
			(xy 289.030874 -41.709027) (xy 288.960543 -41.741772) (xy 288.887628 -41.768268) (xy 288.812683 -41.788313)
			(xy 288.736277 -41.801757) (xy 288.65899 -41.808495) (xy 288.6202 -41.808908) (xy 288.577852 -41.808404)
			(xy 288.493538 -41.800353) (xy 288.410372 -41.784324) (xy 288.329105 -41.760463) (xy 288.250475 -41.728984)
			(xy 288.175194 -41.690173) (xy 288.103942 -41.644383) (xy 288.037366 -41.592027) (xy 287.976068 -41.533579)
			(xy 287.920603 -41.469569) (xy 287.871474 -41.400577) (xy 287.829125 -41.327227) (xy 287.793941 -41.250184)
			(xy 287.766239 -41.170145) (xy 287.746271 -41.087836) (xy 287.734218 -41.004001) (xy 287.730188 -40.9194)
			(xy 260.502615 -40.9194) (xy 260.511612 -40.966017) (xy 260.519688 -41.050465) (xy 260.52018 -41.092882)
			(xy 260.519705 -41.135309) (xy 260.511626 -41.219777) (xy 260.49554 -41.303091) (xy 260.471593 -41.384495)
			(xy 260.440002 -41.463249) (xy 260.401055 -41.538636) (xy 260.355107 -41.609972) (xy 260.302573 -41.676608)
			(xy 260.243933 -41.737938) (xy 260.179718 -41.793405) (xy 260.110513 -41.842505) (xy 260.036947 -41.884791)
			(xy 259.959689 -41.919879) (xy 259.919724 -41.93413) (xy 259.910326 -41.937432) (xy 259.895594 -41.950132)
			(xy 259.854446 -42.03065) (xy 259.852668 -42.049954) (xy 259.855462 -42.059606) (xy 259.867486 -42.101336)
			(xy 259.874135 -42.134987) (xy 291.917116 -42.134987) (xy 291.917116 -42.050265) (xy 291.925169 -41.965928)
			(xy 291.941203 -41.882738) (xy 291.965071 -41.801448) (xy 291.996559 -41.722796) (xy 292.035381 -41.647493)
			(xy 292.081184 -41.576221) (xy 292.133555 -41.509625) (xy 292.19202 -41.44831) (xy 292.256048 -41.392829)
			(xy 292.32506 -41.343686) (xy 292.39843 -41.301326) (xy 292.475495 -41.266131) (xy 292.555557 -41.238422)
			(xy 292.63789 -41.218448) (xy 292.721749 -41.206391) (xy 292.806374 -41.20236) (xy 292.890999 -41.206391)
			(xy 292.974858 -41.218448) (xy 293.057191 -41.238422) (xy 293.137253 -41.266131) (xy 293.214318 -41.301326)
			(xy 293.287688 -41.343686) (xy 293.3567 -41.392829) (xy 293.420728 -41.44831) (xy 293.479193 -41.509625)
			(xy 293.531564 -41.576221) (xy 293.577367 -41.647493) (xy 293.616189 -41.722796) (xy 293.647677 -41.801448)
			(xy 293.671545 -41.882738) (xy 293.687579 -41.965928) (xy 293.695632 -42.050265) (xy 293.696136 -42.092626)
			(xy 293.695632 -42.134987) (xy 293.687579 -42.219324) (xy 293.671545 -42.302514) (xy 293.647677 -42.383804)
			(xy 293.616189 -42.462456) (xy 293.577367 -42.537759) (xy 293.531564 -42.609031) (xy 293.479193 -42.675627)
			(xy 293.420728 -42.736942) (xy 293.3567 -42.792423) (xy 293.287688 -42.841566) (xy 293.214318 -42.883926)
			(xy 293.137253 -42.919121) (xy 293.057191 -42.94683) (xy 292.974858 -42.966804) (xy 292.890999 -42.978861)
			(xy 292.806374 -42.982893) (xy 292.721749 -42.978861) (xy 292.63789 -42.966804) (xy 292.555557 -42.94683)
			(xy 292.475495 -42.919121) (xy 292.39843 -42.883926) (xy 292.32506 -42.841566) (xy 292.256048 -42.792423)
			(xy 292.19202 -42.736942) (xy 292.133555 -42.675627) (xy 292.081184 -42.609031) (xy 292.035381 -42.537759)
			(xy 291.996559 -42.462456) (xy 291.965071 -42.383804) (xy 291.941203 -42.302514) (xy 291.925169 -42.219324)
			(xy 291.917116 -42.134987) (xy 259.874135 -42.134987) (xy 259.88432 -42.186539) (xy 259.892782 -42.272975)
			(xy 259.893308 -42.3164) (xy 259.892842 -42.358233) (xy 259.885017 -42.441532) (xy 259.869417 -42.523731)
			(xy 259.858256 -42.56405) (xy 259.85597 -42.573278) (xy 259.857676 -42.592201) (xy 259.861558 -42.60088)
			(xy 259.87502 -42.627804) (xy 259.879656 -42.63618) (xy 259.893889 -42.648965) (xy 259.902706 -42.652696)
			(xy 259.941221 -42.667831) (xy 260.015569 -42.704177) (xy 260.086221 -42.747271) (xy 260.152565 -42.79674)
			(xy 260.214028 -42.852157) (xy 260.270078 -42.913043) (xy 260.320231 -42.978871) (xy 260.364054 -43.049073)
			(xy 260.401167 -43.123041) (xy 260.431251 -43.200137) (xy 260.454044 -43.279693) (xy 260.469349 -43.361022)
			(xy 260.477035 -43.443421) (xy 260.477508 -43.4848) (xy 260.477004 -43.527148) (xy 260.468953 -43.611462)
			(xy 260.452924 -43.694628) (xy 260.432497 -43.7642) (xy 287.730188 -43.7642) (xy 287.734218 -43.679599)
			(xy 287.746271 -43.595764) (xy 287.766239 -43.513455) (xy 287.793941 -43.433416) (xy 287.829125 -43.356373)
			(xy 287.871474 -43.283023) (xy 287.920603 -43.214031) (xy 287.976068 -43.150021) (xy 288.037366 -43.091573)
			(xy 288.103942 -43.039217) (xy 288.175194 -42.993427) (xy 288.250475 -42.954616) (xy 288.329105 -42.923137)
			(xy 288.410372 -42.899276) (xy 288.493538 -42.883247) (xy 288.577852 -42.875196) (xy 288.6202 -42.874692)
			(xy 288.658991 -42.875105) (xy 288.736279 -42.881837) (xy 288.812687 -42.895275) (xy 288.887634 -42.915317)
			(xy 288.960551 -42.941812) (xy 289.030883 -42.974557) (xy 289.0647 -42.993564) (xy 289.072574 -42.997723)
			(xy 289.0901 -43.000817) (xy 289.107626 -42.997723) (xy 289.1155 -42.993564) (xy 289.149326 -42.974573)
			(xy 289.219657 -42.941828) (xy 289.292572 -42.915332) (xy 289.367517 -42.895287) (xy 289.443923 -42.881843)
			(xy 289.52121 -42.875105) (xy 289.56 -42.874692) (xy 289.602348 -42.875196) (xy 289.686662 -42.883247)
			(xy 289.769828 -42.899276) (xy 289.851095 -42.923137) (xy 289.929725 -42.954616) (xy 290.005006 -42.993427)
			(xy 290.076258 -43.039217) (xy 290.142834 -43.091573) (xy 290.204132 -43.150021) (xy 290.259597 -43.214031)
			(xy 290.308726 -43.283023) (xy 290.351075 -43.356373) (xy 290.386259 -43.433416) (xy 290.413961 -43.513455)
			(xy 290.433929 -43.595764) (xy 290.445982 -43.679599) (xy 290.450013 -43.7642) (xy 290.445982 -43.848801)
			(xy 290.433929 -43.932636) (xy 290.413961 -44.014945) (xy 290.386259 -44.094984) (xy 290.351075 -44.172027)
			(xy 290.308726 -44.245377) (xy 290.259597 -44.314369) (xy 290.204132 -44.378379) (xy 290.142834 -44.436827)
			(xy 290.076258 -44.489183) (xy 290.005006 -44.534973) (xy 289.929725 -44.573784) (xy 289.851095 -44.605263)
			(xy 289.769828 -44.629124) (xy 289.686662 -44.645153) (xy 289.602348 -44.653204) (xy 289.56 -44.653708)
			(xy 289.521209 -44.653295) (xy 289.443921 -44.646563) (xy 289.367513 -44.633125) (xy 289.292566 -44.613083)
			(xy 289.219649 -44.586588) (xy 289.149317 -44.553843) (xy 289.1155 -44.534836) (xy 289.107626 -44.530677)
			(xy 289.0901 -44.527583) (xy 289.072574 -44.530677) (xy 289.0647 -44.534836) (xy 289.030874 -44.553827)
			(xy 288.960543 -44.586572) (xy 288.887628 -44.613068) (xy 288.812683 -44.633113) (xy 288.736277 -44.646557)
			(xy 288.65899 -44.653295) (xy 288.6202 -44.653708) (xy 288.577852 -44.653204) (xy 288.493538 -44.645153)
			(xy 288.410372 -44.629124) (xy 288.329105 -44.605263) (xy 288.250475 -44.573784) (xy 288.175194 -44.534973)
			(xy 288.103942 -44.489183) (xy 288.037366 -44.436827) (xy 287.976068 -44.378379) (xy 287.920603 -44.314369)
			(xy 287.871474 -44.245377) (xy 287.829125 -44.172027) (xy 287.793941 -44.094984) (xy 287.766239 -44.014945)
			(xy 287.746271 -43.932636) (xy 287.734218 -43.848801) (xy 287.730188 -43.7642) (xy 260.432497 -43.7642)
			(xy 260.429063 -43.775895) (xy 260.397584 -43.854525) (xy 260.358773 -43.929806) (xy 260.312983 -44.001058)
			(xy 260.260627 -44.067634) (xy 260.202179 -44.128932) (xy 260.138169 -44.184397) (xy 260.069177 -44.233526)
			(xy 259.995827 -44.275875) (xy 259.918784 -44.311059) (xy 259.838745 -44.338761) (xy 259.756436 -44.358729)
			(xy 259.672601 -44.370782) (xy 259.588 -44.374813) (xy 259.503399 -44.370782) (xy 259.419564 -44.358729)
			(xy 259.337255 -44.338761) (xy 259.257216 -44.311059) (xy 259.180173 -44.275875) (xy 259.106823 -44.233526)
			(xy 259.037831 -44.184397) (xy 258.973821 -44.128932) (xy 258.915373 -44.067634) (xy 258.863017 -44.001058)
			(xy 258.817227 -43.929806) (xy 258.778416 -43.854525) (xy 258.746937 -43.775895) (xy 258.723076 -43.694628)
			(xy 258.707047 -43.611462) (xy 258.698996 -43.527148) (xy 258.698492 -43.4848) (xy 258.698958 -43.442967)
			(xy 258.706783 -43.359668) (xy 258.722383 -43.277469) (xy 258.733544 -43.23715) (xy 258.73583 -43.227922)
			(xy 258.734124 -43.208999) (xy 258.730242 -43.20032) (xy 258.71678 -43.173396) (xy 258.712144 -43.16502)
			(xy 258.697911 -43.152235) (xy 258.689094 -43.148504) (xy 258.650579 -43.133369) (xy 258.576231 -43.097023)
			(xy 258.505579 -43.053929) (xy 258.439235 -43.00446) (xy 258.377772 -42.949043) (xy 258.321722 -42.888157)
			(xy 258.271569 -42.822329) (xy 258.227746 -42.752127) (xy 258.190633 -42.678159) (xy 258.160549 -42.601063)
			(xy 258.137756 -42.521507) (xy 258.122451 -42.440178) (xy 258.114765 -42.357779) (xy 258.114292 -42.3164)
			(xy 258.114767 -42.275174) (xy 258.122403 -42.193078) (xy 258.1376 -42.112039) (xy 258.160229 -42.032754)
			(xy 258.190094 -41.955902) (xy 258.226941 -41.882142) (xy 258.270452 -41.812106) (xy 258.320255 -41.746396)
			(xy 258.375923 -41.685574) (xy 258.406138 -41.657524) (xy 258.415282 -41.649142) (xy 258.423918 -41.62679)
			(xy 258.412488 -41.520618) (xy 258.39928 -41.500298) (xy 258.388612 -41.494202) (xy 258.352203 -41.47258)
			(xy 258.283247 -41.423422) (xy 258.219273 -41.367935) (xy 258.16086 -41.306622) (xy 258.108535 -41.240036)
			(xy 258.062773 -41.168781) (xy 258.023988 -41.093501) (xy 257.992529 -41.014876) (xy 257.968682 -40.933619)
			(xy 257.952663 -40.850463) (xy 257.944616 -40.766162) (xy 257.944112 -40.72382) (xy 257.944722 -40.676728)
			(xy 257.954664 -40.583071) (xy 257.974438 -40.490987) (xy 258.003824 -40.401506) (xy 258.022598 -40.358314)
			(xy 258.02655 -40.348334) (xy 258.026555 -40.32689) (xy 258.022598 -40.316912) (xy 258.004411 -40.274268)
			(xy 257.97595 -40.186031) (xy 257.956819 -40.095313) (xy 257.947225 -40.003097) (xy 257.946652 -39.95674)
			(xy 257.946693 -39.939388) (xy 257.947962 -39.904707) (xy 257.949192 -39.887398) (xy 257.949484 -39.87578)
			(xy 257.9409 -39.854212) (xy 257.932682 -39.845996) (xy 257.902445 -39.817967) (xy 257.846768 -39.757149)
			(xy 257.796958 -39.69144) (xy 257.753442 -39.621403) (xy 257.716595 -39.54764) (xy 257.686732 -39.470783)
			(xy 257.664109 -39.391493) (xy 257.648921 -39.310449) (xy 257.641298 -39.228347) (xy 257.640836 -39.18712)
			(xy 252.350882 -39.18712) (xy 252.346074 -39.201239) (xy 252.283659 -39.359749) (xy 252.213883 -39.515159)
			(xy 252.1369 -39.667127) (xy 252.052878 -39.815321) (xy 251.962002 -39.959413) (xy 251.864472 -40.099087)
			(xy 251.760502 -40.234036) (xy 251.650321 -40.363964) (xy 251.534172 -40.488584) (xy 251.412308 -40.607623)
			(xy 251.285 -40.720819) (xy 251.152525 -40.827924) (xy 251.015175 -40.928701) (xy 250.873253 -41.02293)
			(xy 250.727071 -41.110403) (xy 250.576948 -41.190928) (xy 250.423217 -41.264328) (xy 250.266214 -41.330442)
			(xy 250.106284 -41.389124) (xy 249.94378 -41.440245) (xy 249.779059 -41.483693) (xy 249.612481 -41.519372)
			(xy 249.444415 -41.547204) (xy 249.275229 -41.567128) (xy 249.105295 -41.5791) (xy 248.934986 -41.583094)
			(xy 248.764677 -41.5791) (xy 248.594743 -41.567128) (xy 248.425557 -41.547204) (xy 248.257491 -41.519372)
			(xy 248.090913 -41.483693) (xy 247.926192 -41.440245) (xy 247.763688 -41.389124) (xy 247.603758 -41.330442)
			(xy 247.446755 -41.264328) (xy 247.293024 -41.190928) (xy 247.142901 -41.110403) (xy 246.996719 -41.02293)
			(xy 246.854797 -40.928701) (xy 246.717447 -40.827924) (xy 246.584972 -40.720819) (xy 246.457664 -40.607623)
			(xy 246.3358 -40.488584) (xy 246.219651 -40.363964) (xy 246.10947 -40.234036) (xy 246.0055 -40.099087)
			(xy 245.90797 -39.959413) (xy 245.817094 -39.815321) (xy 245.733072 -39.667127) (xy 245.656089 -39.515159)
			(xy 245.586313 -39.359749) (xy 245.523898 -39.201239) (xy 245.468981 -39.039978) (xy 245.421684 -38.87632)
			(xy 245.382109 -38.710625) (xy 245.350345 -38.543257) (xy 245.32646 -38.374585) (xy 245.310508 -38.204978)
			(xy 245.302523 -38.03481) (xy 202.706832 -38.03481) (xy 202.701465 -38.106403) (xy 202.685855 -38.209943)
			(xy 202.662551 -38.312026) (xy 202.631683 -38.412082) (xy 202.593423 -38.509551) (xy 202.547985 -38.603889)
			(xy 202.495624 -38.694566) (xy 202.436633 -38.781077) (xy 202.371342 -38.862937) (xy 202.300114 -38.939688)
			(xy 202.22335 -39.010902) (xy 202.141479 -39.076179) (xy 202.054958 -39.135155) (xy 201.964271 -39.1875)
			(xy 201.869926 -39.232921) (xy 201.77245 -39.271164) (xy 201.672388 -39.302015) (xy 201.570301 -39.325301)
			(xy 201.466759 -39.340893) (xy 201.362341 -39.348702) (xy 201.309986 -39.349172) (xy 201.255694 -39.348606)
			(xy 201.147435 -39.340199) (xy 201.040154 -39.323428) (xy 200.934494 -39.298394) (xy 200.831092 -39.265249)
			(xy 200.730569 -39.224191) (xy 200.63353 -39.175467) (xy 200.540559 -39.11937) (xy 200.452213 -39.056237)
			(xy 200.369026 -38.986449) (xy 200.291496 -38.910425) (xy 200.22009 -38.828621) (xy 200.155238 -38.74153)
			(xy 200.125838 -38.695884) (xy 200.118726 -38.684708) (xy 200.096374 -38.672262) (xy 199.983598 -38.672262)
			(xy 199.961246 -38.684708) (xy 199.954134 -38.695884) (xy 199.924757 -38.741546) (xy 199.859901 -38.828636)
			(xy 199.788493 -38.91044) (xy 199.71096 -38.986465) (xy 199.62777 -39.056254) (xy 199.539423 -39.119388)
			(xy 199.44645 -39.175486) (xy 199.34941 -39.224212) (xy 199.248886 -39.265273) (xy 199.145483 -39.298422)
			(xy 199.039822 -39.323459) (xy 198.93254 -39.340234) (xy 198.824279 -39.348647) (xy 198.769986 -39.349172)
			(xy 198.717633 -39.348718) (xy 198.61322 -39.340894) (xy 198.509683 -39.325289) (xy 198.407602 -39.301991)
			(xy 198.307547 -39.271131) (xy 198.210078 -39.23288) (xy 198.11574 -39.187454) (xy 198.025059 -39.135106)
			(xy 197.938544 -39.076128) (xy 197.856677 -39.01085) (xy 197.779917 -38.939637) (xy 197.708692 -38.862888)
			(xy 197.643402 -38.781032) (xy 197.584411 -38.694526) (xy 197.532048 -38.603853) (xy 197.486607 -38.509522)
			(xy 197.448341 -38.412058) (xy 197.417465 -38.312008) (xy 197.394152 -38.209931) (xy 197.378531 -38.106397)
			(xy 197.37069 -38.001985) (xy 197.370192 -37.949632) (xy 197.370714 -37.895332) (xy 197.379129 -37.787059)
			(xy 197.395911 -37.679764) (xy 197.420959 -37.574093) (xy 197.454122 -37.470681) (xy 197.495202 -37.370151)
			(xy 197.543949 -37.273107) (xy 197.600072 -37.180134) (xy 197.663233 -37.09179) (xy 197.733051 -37.008608)
			(xy 197.809106 -36.931087) (xy 197.890942 -36.859696) (xy 197.978065 -36.794861) (xy 198.023734 -36.765484)
			(xy 198.03491 -36.758372) (xy 198.047356 -36.73602) (xy 198.047356 -36.623244) (xy 198.03491 -36.600892)
			(xy 198.023734 -36.59378) (xy 197.979782 -36.565453) (xy 197.895707 -36.503265) (xy 197.81651 -36.434975)
			(xy 197.74263 -36.360964) (xy 197.674482 -36.281645) (xy 197.612444 -36.19746) (xy 197.556863 -36.10888)
			(xy 197.508049 -36.016397) (xy 197.466275 -35.920529) (xy 197.431773 -35.82181) (xy 197.404736 -35.720792)
			(xy 197.385315 -35.618036) (xy 197.373619 -35.514118) (xy 197.369712 -35.409617) (xy 193.820281 -35.409617)
			(xy 193.816374 -35.514121) (xy 193.804677 -35.618041) (xy 193.785257 -35.720799) (xy 193.758221 -35.82182)
			(xy 193.72372 -35.920542) (xy 193.681946 -36.016413) (xy 193.633133 -36.108899) (xy 193.577553 -36.197483)
			(xy 193.515516 -36.281671) (xy 193.447368 -36.360994) (xy 193.37349 -36.435009) (xy 193.294293 -36.503304)
			(xy 193.210219 -36.565496) (xy 193.166238 -36.59378) (xy 193.155062 -36.600892) (xy 193.142616 -36.623244)
			(xy 193.142616 -36.73602) (xy 193.155062 -36.758372) (xy 193.166238 -36.765484) (xy 193.21193 -36.794827)
			(xy 193.299051 -36.859666) (xy 193.380885 -36.931062) (xy 193.456939 -37.008586) (xy 193.526756 -37.091772)
			(xy 193.589915 -37.180118) (xy 193.646037 -37.273094) (xy 193.694783 -37.37014) (xy 193.735861 -37.470673)
			(xy 193.769024 -37.574087) (xy 193.794071 -37.67976) (xy 193.810853 -37.787057) (xy 193.819268 -37.895331)
			(xy 193.81978 -37.949632) (xy 193.819293 -38.001987) (xy 193.811465 -38.106403) (xy 193.795855 -38.209943)
			(xy 193.772551 -38.312026) (xy 193.741683 -38.412082) (xy 193.703423 -38.509551) (xy 193.657985 -38.603889)
			(xy 193.605624 -38.694566) (xy 193.546633 -38.781077) (xy 193.481342 -38.862937) (xy 193.410114 -38.939688)
			(xy 193.33335 -39.010902) (xy 193.251479 -39.076179) (xy 193.164958 -39.135155) (xy 193.074271 -39.1875)
			(xy 192.979926 -39.232921) (xy 192.88245 -39.271164) (xy 192.782388 -39.302015) (xy 192.680301 -39.325301)
			(xy 192.576759 -39.340893) (xy 192.472341 -39.348702) (xy 192.419986 -39.349172) (xy 192.365694 -39.348606)
			(xy 192.257435 -39.340199) (xy 192.150154 -39.323428) (xy 192.044494 -39.298394) (xy 191.941092 -39.265249)
			(xy 191.840569 -39.224191) (xy 191.74353 -39.175467) (xy 191.650559 -39.11937) (xy 191.562213 -39.056237)
			(xy 191.479026 -38.986449) (xy 191.401496 -38.910425) (xy 191.33009 -38.828621) (xy 191.265238 -38.74153)
			(xy 191.235838 -38.695884) (xy 191.228726 -38.684708) (xy 191.206374 -38.672262) (xy 191.093598 -38.672262)
			(xy 191.071246 -38.684708) (xy 191.064134 -38.695884) (xy 191.034757 -38.741546) (xy 190.969901 -38.828636)
			(xy 190.898493 -38.91044) (xy 190.82096 -38.986465) (xy 190.73777 -39.056254) (xy 190.649423 -39.119388)
			(xy 190.55645 -39.175486) (xy 190.45941 -39.224212) (xy 190.358886 -39.265273) (xy 190.255483 -39.298422)
			(xy 190.149822 -39.323459) (xy 190.04254 -39.340234) (xy 189.934279 -39.348647) (xy 189.879986 -39.349172)
			(xy 189.827633 -39.348718) (xy 189.72322 -39.340894) (xy 189.619683 -39.325289) (xy 189.517602 -39.301991)
			(xy 189.417547 -39.271131) (xy 189.320078 -39.23288) (xy 189.22574 -39.187454) (xy 189.135059 -39.135106)
			(xy 189.048544 -39.076128) (xy 188.966677 -39.01085) (xy 188.889917 -38.939637) (xy 188.818692 -38.862888)
			(xy 188.753402 -38.781032) (xy 188.694411 -38.694526) (xy 188.642048 -38.603853) (xy 188.596607 -38.509522)
			(xy 188.558341 -38.412058) (xy 188.527465 -38.312008) (xy 188.504152 -38.209931) (xy 188.488531 -38.106397)
			(xy 188.48069 -38.001985) (xy 188.480192 -37.949632) (xy 188.480714 -37.895332) (xy 188.489129 -37.787059)
			(xy 188.505911 -37.679764) (xy 188.530959 -37.574093) (xy 188.564122 -37.470681) (xy 188.605202 -37.370151)
			(xy 188.653949 -37.273107) (xy 188.710072 -37.180134) (xy 188.773233 -37.09179) (xy 188.843051 -37.008608)
			(xy 188.919106 -36.931087) (xy 189.000942 -36.859696) (xy 189.088065 -36.794861) (xy 189.133734 -36.765484)
			(xy 189.14491 -36.758372) (xy 189.157356 -36.73602) (xy 189.157356 -36.623244) (xy 189.14491 -36.600892)
			(xy 189.133734 -36.59378) (xy 189.089782 -36.565453) (xy 189.005707 -36.503265) (xy 188.92651 -36.434975)
			(xy 188.85263 -36.360964) (xy 188.784482 -36.281645) (xy 188.722444 -36.19746) (xy 188.666863 -36.10888)
			(xy 188.618049 -36.016397) (xy 188.576275 -35.920529) (xy 188.541773 -35.82181) (xy 188.514736 -35.720792)
			(xy 188.495315 -35.618036) (xy 188.483619 -35.514118) (xy 188.479712 -35.409617) (xy 184.930281 -35.409617)
			(xy 184.926374 -35.514121) (xy 184.914677 -35.618041) (xy 184.895257 -35.720799) (xy 184.868221 -35.82182)
			(xy 184.83372 -35.920542) (xy 184.791946 -36.016413) (xy 184.743133 -36.108899) (xy 184.687553 -36.197483)
			(xy 184.625516 -36.281671) (xy 184.557368 -36.360994) (xy 184.48349 -36.435009) (xy 184.404293 -36.503304)
			(xy 184.320219 -36.565496) (xy 184.276238 -36.59378) (xy 184.265062 -36.600892) (xy 184.252616 -36.623244)
			(xy 184.252616 -36.73602) (xy 184.265062 -36.758372) (xy 184.276238 -36.765484) (xy 184.32193 -36.794827)
			(xy 184.409051 -36.859666) (xy 184.490885 -36.931062) (xy 184.566939 -37.008586) (xy 184.636756 -37.091772)
			(xy 184.699915 -37.180118) (xy 184.756037 -37.273094) (xy 184.804783 -37.37014) (xy 184.845861 -37.470673)
			(xy 184.879024 -37.574087) (xy 184.904071 -37.67976) (xy 184.920853 -37.787057) (xy 184.929268 -37.895331)
			(xy 184.92978 -37.949632) (xy 184.929293 -38.001987) (xy 184.921465 -38.106403) (xy 184.905855 -38.209943)
			(xy 184.882551 -38.312026) (xy 184.851683 -38.412082) (xy 184.813423 -38.509551) (xy 184.767985 -38.603889)
			(xy 184.715624 -38.694566) (xy 184.656633 -38.781077) (xy 184.591342 -38.862937) (xy 184.520114 -38.939688)
			(xy 184.44335 -39.010902) (xy 184.361479 -39.076179) (xy 184.274958 -39.135155) (xy 184.184271 -39.1875)
			(xy 184.089926 -39.232921) (xy 183.99245 -39.271164) (xy 183.892388 -39.302015) (xy 183.790301 -39.325301)
			(xy 183.686759 -39.340893) (xy 183.582341 -39.348702) (xy 183.529986 -39.349172) (xy 183.475694 -39.348606)
			(xy 183.367435 -39.340199) (xy 183.260154 -39.323428) (xy 183.154494 -39.298394) (xy 183.051092 -39.265249)
			(xy 182.950569 -39.224191) (xy 182.85353 -39.175467) (xy 182.760559 -39.11937) (xy 182.672213 -39.056237)
			(xy 182.589026 -38.986449) (xy 182.511496 -38.910425) (xy 182.44009 -38.828621) (xy 182.375238 -38.74153)
			(xy 182.345838 -38.695884) (xy 182.338726 -38.684708) (xy 182.316374 -38.672262) (xy 182.203598 -38.672262)
			(xy 182.181246 -38.684708) (xy 182.174134 -38.695884) (xy 182.144757 -38.741546) (xy 182.079901 -38.828636)
			(xy 182.008493 -38.91044) (xy 181.93096 -38.986465) (xy 181.84777 -39.056254) (xy 181.759423 -39.119388)
			(xy 181.66645 -39.175486) (xy 181.56941 -39.224212) (xy 181.468886 -39.265273) (xy 181.365483 -39.298422)
			(xy 181.259822 -39.323459) (xy 181.15254 -39.340234) (xy 181.044279 -39.348647) (xy 180.989986 -39.349172)
			(xy 180.937633 -39.348718) (xy 180.83322 -39.340894) (xy 180.729683 -39.325289) (xy 180.627602 -39.301991)
			(xy 180.527547 -39.271131) (xy 180.430078 -39.23288) (xy 180.33574 -39.187454) (xy 180.245059 -39.135106)
			(xy 180.158544 -39.076128) (xy 180.076677 -39.01085) (xy 179.999917 -38.939637) (xy 179.928692 -38.862888)
			(xy 179.863402 -38.781032) (xy 179.804411 -38.694526) (xy 179.752048 -38.603853) (xy 179.706607 -38.509522)
			(xy 179.668341 -38.412058) (xy 179.637465 -38.312008) (xy 179.614152 -38.209931) (xy 179.598531 -38.106397)
			(xy 179.59069 -38.001985) (xy 179.590192 -37.949632) (xy 179.590714 -37.895332) (xy 179.599129 -37.787059)
			(xy 179.615911 -37.679764) (xy 179.640959 -37.574093) (xy 179.674122 -37.470681) (xy 179.715202 -37.370151)
			(xy 179.763949 -37.273107) (xy 179.820072 -37.180134) (xy 179.883233 -37.09179) (xy 179.953051 -37.008608)
			(xy 180.029106 -36.931087) (xy 180.110942 -36.859696) (xy 180.198065 -36.794861) (xy 180.243734 -36.765484)
			(xy 180.25491 -36.758372) (xy 180.267356 -36.73602) (xy 180.267356 -36.623244) (xy 180.25491 -36.600892)
			(xy 180.243734 -36.59378) (xy 180.199782 -36.565453) (xy 180.115707 -36.503265) (xy 180.03651 -36.434975)
			(xy 179.96263 -36.360964) (xy 179.894482 -36.281645) (xy 179.832444 -36.19746) (xy 179.776863 -36.10888)
			(xy 179.728049 -36.016397) (xy 179.686275 -35.920529) (xy 179.651773 -35.82181) (xy 179.624736 -35.720792)
			(xy 179.605315 -35.618036) (xy 179.593619 -35.514118) (xy 179.589712 -35.409617) (xy 171.523084 -35.409617)
			(xy 171.524172 -35.41068) (xy 171.640321 -35.5353) (xy 171.750502 -35.665228) (xy 171.854472 -35.800177)
			(xy 171.952002 -35.939851) (xy 172.042878 -36.083943) (xy 172.1269 -36.232137) (xy 172.203883 -36.384105)
			(xy 172.273659 -36.539515) (xy 172.336074 -36.698025) (xy 172.390991 -36.859286) (xy 172.438288 -37.022944)
			(xy 172.477863 -37.188639) (xy 172.509627 -37.356007) (xy 172.533512 -37.524679) (xy 172.549464 -37.694286)
			(xy 172.557449 -37.864454) (xy 172.557948 -37.949632) (xy 172.557449 -38.03481) (xy 172.549464 -38.204978)
			(xy 172.533512 -38.374585) (xy 172.509627 -38.543257) (xy 172.477863 -38.710625) (xy 172.438288 -38.87632)
			(xy 172.390991 -39.039978) (xy 172.336074 -39.201239) (xy 172.273659 -39.359749) (xy 172.203883 -39.515159)
			(xy 172.1269 -39.667127) (xy 172.042878 -39.815321) (xy 171.952002 -39.959413) (xy 171.854472 -40.099087)
			(xy 171.750502 -40.234036) (xy 171.640321 -40.363964) (xy 171.524172 -40.488584) (xy 171.402308 -40.607623)
			(xy 171.275 -40.720819) (xy 171.142525 -40.827924) (xy 171.005175 -40.928701) (xy 170.863253 -41.02293)
			(xy 170.717071 -41.110403) (xy 170.566948 -41.190928) (xy 170.413217 -41.264328) (xy 170.256214 -41.330442)
			(xy 170.096284 -41.389124) (xy 169.93378 -41.440245) (xy 169.769059 -41.483693) (xy 169.602481 -41.519372)
			(xy 169.434415 -41.547204) (xy 169.265229 -41.567128) (xy 169.095295 -41.5791) (xy 168.924986 -41.583094)
			(xy 168.754677 -41.5791) (xy 168.584743 -41.567128) (xy 168.415557 -41.547204) (xy 168.247491 -41.519372)
			(xy 168.080913 -41.483693) (xy 167.916192 -41.440245) (xy 167.753688 -41.389124) (xy 167.593758 -41.330442)
			(xy 167.436755 -41.264328) (xy 167.283024 -41.190928) (xy 167.132901 -41.110403) (xy 166.986719 -41.02293)
			(xy 166.844797 -40.928701) (xy 166.707447 -40.827924) (xy 166.574972 -40.720819) (xy 166.447664 -40.607623)
			(xy 166.3258 -40.488584) (xy 166.209651 -40.363964) (xy 166.09947 -40.234036) (xy 165.9955 -40.099087)
			(xy 165.89797 -39.959413) (xy 165.807094 -39.815321) (xy 165.723072 -39.667127) (xy 165.646089 -39.515159)
			(xy 165.576313 -39.359749) (xy 165.513898 -39.201239) (xy 165.458981 -39.039978) (xy 165.411684 -38.87632)
			(xy 165.372109 -38.710625) (xy 165.340345 -38.543257) (xy 165.31646 -38.374585) (xy 165.300508 -38.204978)
			(xy 165.292523 -38.03481) (xy 123.764517 -38.03481) (xy 123.761167 -38.124486) (xy 123.749476 -38.228395)
			(xy 123.730065 -38.331142) (xy 123.70304 -38.432154) (xy 123.668553 -38.530867) (xy 123.626796 -38.626732)
			(xy 123.578001 -38.719214) (xy 123.522442 -38.807796) (xy 123.460427 -38.891986) (xy 123.392303 -38.971313)
			(xy 123.318449 -39.045335) (xy 123.239277 -39.11364) (xy 123.155229 -39.175846) (xy 123.11126 -39.204138)
			(xy 123.100084 -39.21125) (xy 123.087638 -39.233602) (xy 123.087638 -39.346378) (xy 123.100084 -39.36873)
			(xy 123.11126 -39.375842) (xy 123.156905 -39.405244) (xy 123.243996 -39.470097) (xy 123.325801 -39.541503)
			(xy 123.401827 -39.619033) (xy 123.471617 -39.702221) (xy 123.534751 -39.790565) (xy 123.590851 -39.883536)
			(xy 123.639579 -39.980574) (xy 123.680641 -40.081096) (xy 123.713792 -40.184498) (xy 123.738831 -40.290157)
			(xy 123.755608 -40.397438) (xy 123.764022 -40.505697) (xy 123.764548 -40.55999) (xy 123.764095 -40.612343)
			(xy 123.756272 -40.716757) (xy 123.740669 -40.820294) (xy 123.717372 -40.922376) (xy 123.686513 -41.022432)
			(xy 123.648263 -41.119902) (xy 123.602837 -41.214241) (xy 123.550489 -41.304922) (xy 123.491511 -41.391438)
			(xy 123.426233 -41.473306) (xy 123.35502 -41.550066) (xy 123.278271 -41.621291) (xy 123.196414 -41.686581)
			(xy 123.109907 -41.745573) (xy 123.019234 -41.797935) (xy 122.924902 -41.843376) (xy 122.827438 -41.881641)
			(xy 122.727387 -41.912516) (xy 122.625308 -41.935828) (xy 122.521774 -41.951448) (xy 122.417361 -41.959287)
			(xy 122.365008 -41.959784) (xy 122.310709 -41.959246) (xy 122.202437 -41.95083) (xy 122.095143 -41.934047)
			(xy 121.989473 -41.908999) (xy 121.886062 -41.875835) (xy 121.785533 -41.834757) (xy 121.68849 -41.786011)
			(xy 121.595516 -41.729889) (xy 121.507173 -41.666731) (xy 121.42399 -41.596915) (xy 121.346469 -41.520862)
			(xy 121.275075 -41.43903) (xy 121.210239 -41.35191) (xy 121.18086 -41.306242) (xy 121.173748 -41.295066)
			(xy 121.151396 -41.28262) (xy 121.03862 -41.28262) (xy 121.016268 -41.295066) (xy 121.009156 -41.306242)
			(xy 120.979787 -41.351917) (xy 120.91495 -41.439038) (xy 120.843556 -41.520872) (xy 120.766034 -41.596926)
			(xy 120.682851 -41.666744) (xy 120.594507 -41.729904) (xy 120.501533 -41.786026) (xy 120.404489 -41.834774)
			(xy 120.303959 -41.875854) (xy 120.200547 -41.909019) (xy 120.094876 -41.934068) (xy 119.987581 -41.950853)
			(xy 119.879308 -41.95927) (xy 119.825008 -41.959784) (xy 119.772654 -41.959255) (xy 119.668238 -41.95143)
			(xy 119.5647 -41.935823) (xy 119.462617 -41.912521) (xy 119.362562 -41.881656) (xy 119.265093 -41.843398)
			(xy 119.170756 -41.797963) (xy 119.080078 -41.745605) (xy 118.993567 -41.686616) (xy 118.911707 -41.621327)
			(xy 118.834955 -41.550102) (xy 118.763742 -41.47334) (xy 118.698464 -41.39147) (xy 118.639487 -41.304951)
			(xy 118.587142 -41.214266) (xy 118.541721 -41.119922) (xy 118.503478 -41.022448) (xy 118.472627 -40.922388)
			(xy 118.44934 -40.820302) (xy 118.433748 -40.716761) (xy 118.425938 -40.612344) (xy 118.425468 -40.55999)
			(xy 118.426019 -40.505697) (xy 118.434426 -40.397438) (xy 118.451197 -40.290155) (xy 118.476231 -40.184495)
			(xy 118.509377 -40.081093) (xy 118.550436 -39.980569) (xy 118.599162 -39.88353) (xy 118.65526 -39.790558)
			(xy 118.718394 -39.702213) (xy 118.788184 -39.619026) (xy 118.864211 -39.541497) (xy 118.946016 -39.470092)
			(xy 119.033109 -39.405241) (xy 119.078756 -39.375842) (xy 119.089932 -39.36873) (xy 119.102378 -39.346378)
			(xy 119.102378 -39.233602) (xy 119.089932 -39.21125) (xy 119.078756 -39.204138) (xy 119.03478 -39.175858)
			(xy 118.950735 -39.113648) (xy 118.871567 -39.045341) (xy 118.797716 -38.971316) (xy 118.729595 -38.891987)
			(xy 118.667583 -38.807796) (xy 118.612027 -38.719212) (xy 118.563235 -38.62673) (xy 118.52148 -38.530865)
			(xy 118.486995 -38.432152) (xy 118.459971 -38.33114) (xy 118.440561 -38.228394) (xy 118.428871 -38.124486)
			(xy 118.424968 -38.019995) (xy 114.87507 -38.019995) (xy 114.871167 -38.124486) (xy 114.859476 -38.228395)
			(xy 114.840065 -38.331142) (xy 114.81304 -38.432154) (xy 114.778553 -38.530867) (xy 114.736796 -38.626732)
			(xy 114.688001 -38.719214) (xy 114.632442 -38.807796) (xy 114.570427 -38.891986) (xy 114.502303 -38.971313)
			(xy 114.428449 -39.045335) (xy 114.349277 -39.11364) (xy 114.265229 -39.175846) (xy 114.22126 -39.204138)
			(xy 114.210084 -39.21125) (xy 114.197638 -39.233602) (xy 114.197638 -39.346378) (xy 114.210084 -39.36873)
			(xy 114.22126 -39.375842) (xy 114.266905 -39.405244) (xy 114.353996 -39.470097) (xy 114.435801 -39.541503)
			(xy 114.511827 -39.619033) (xy 114.581617 -39.702221) (xy 114.644751 -39.790565) (xy 114.700851 -39.883536)
			(xy 114.749579 -39.980574) (xy 114.790641 -40.081096) (xy 114.823792 -40.184498) (xy 114.848831 -40.290157)
			(xy 114.865608 -40.397438) (xy 114.874022 -40.505697) (xy 114.874548 -40.55999) (xy 114.874095 -40.612343)
			(xy 114.866272 -40.716757) (xy 114.850669 -40.820294) (xy 114.827372 -40.922376) (xy 114.796513 -41.022432)
			(xy 114.758263 -41.119902) (xy 114.712837 -41.214241) (xy 114.660489 -41.304922) (xy 114.601511 -41.391438)
			(xy 114.536233 -41.473306) (xy 114.46502 -41.550066) (xy 114.388271 -41.621291) (xy 114.306414 -41.686581)
			(xy 114.219907 -41.745573) (xy 114.129234 -41.797935) (xy 114.034902 -41.843376) (xy 113.937438 -41.881641)
			(xy 113.837387 -41.912516) (xy 113.735308 -41.935828) (xy 113.631774 -41.951448) (xy 113.527361 -41.959287)
			(xy 113.475008 -41.959784) (xy 113.420709 -41.959246) (xy 113.312437 -41.95083) (xy 113.205143 -41.934047)
			(xy 113.099473 -41.908999) (xy 112.996062 -41.875835) (xy 112.895533 -41.834757) (xy 112.79849 -41.786011)
			(xy 112.705516 -41.729889) (xy 112.617173 -41.666731) (xy 112.53399 -41.596915) (xy 112.456469 -41.520862)
			(xy 112.385075 -41.43903) (xy 112.320239 -41.35191) (xy 112.29086 -41.306242) (xy 112.283748 -41.295066)
			(xy 112.261396 -41.28262) (xy 112.14862 -41.28262) (xy 112.126268 -41.295066) (xy 112.119156 -41.306242)
			(xy 112.089787 -41.351917) (xy 112.02495 -41.439038) (xy 111.953556 -41.520872) (xy 111.876034 -41.596926)
			(xy 111.792851 -41.666744) (xy 111.704507 -41.729904) (xy 111.611533 -41.786026) (xy 111.514489 -41.834774)
			(xy 111.413959 -41.875854) (xy 111.310547 -41.909019) (xy 111.204876 -41.934068) (xy 111.097581 -41.950853)
			(xy 110.989308 -41.95927) (xy 110.935008 -41.959784) (xy 110.882654 -41.959255) (xy 110.778238 -41.95143)
			(xy 110.6747 -41.935823) (xy 110.572617 -41.912521) (xy 110.472562 -41.881656) (xy 110.375093 -41.843398)
			(xy 110.280756 -41.797963) (xy 110.190078 -41.745605) (xy 110.103567 -41.686616) (xy 110.021707 -41.621327)
			(xy 109.944955 -41.550102) (xy 109.873742 -41.47334) (xy 109.808464 -41.39147) (xy 109.749487 -41.304951)
			(xy 109.697142 -41.214266) (xy 109.651721 -41.119922) (xy 109.613478 -41.022448) (xy 109.582627 -40.922388)
			(xy 109.55934 -40.820302) (xy 109.543748 -40.716761) (xy 109.535938 -40.612344) (xy 109.535468 -40.55999)
			(xy 109.536019 -40.505697) (xy 109.544426 -40.397438) (xy 109.561197 -40.290155) (xy 109.586231 -40.184495)
			(xy 109.619377 -40.081093) (xy 109.660436 -39.980569) (xy 109.709162 -39.88353) (xy 109.76526 -39.790558)
			(xy 109.828394 -39.702213) (xy 109.898184 -39.619026) (xy 109.974211 -39.541497) (xy 110.056016 -39.470092)
			(xy 110.143109 -39.405241) (xy 110.188756 -39.375842) (xy 110.199932 -39.36873) (xy 110.212378 -39.346378)
			(xy 110.212378 -39.233602) (xy 110.199932 -39.21125) (xy 110.188756 -39.204138) (xy 110.14478 -39.175858)
			(xy 110.060735 -39.113648) (xy 109.981567 -39.045341) (xy 109.907716 -38.971316) (xy 109.839595 -38.891987)
			(xy 109.777583 -38.807796) (xy 109.722027 -38.719212) (xy 109.673235 -38.62673) (xy 109.63148 -38.530865)
			(xy 109.596995 -38.432152) (xy 109.569971 -38.33114) (xy 109.550561 -38.228394) (xy 109.538871 -38.124486)
			(xy 109.534968 -38.019995) (xy 105.98507 -38.019995) (xy 105.981167 -38.124486) (xy 105.969476 -38.228395)
			(xy 105.950065 -38.331142) (xy 105.92304 -38.432154) (xy 105.888553 -38.530867) (xy 105.846796 -38.626732)
			(xy 105.798001 -38.719214) (xy 105.742442 -38.807796) (xy 105.680427 -38.891986) (xy 105.612303 -38.971313)
			(xy 105.538449 -39.045335) (xy 105.459277 -39.11364) (xy 105.375229 -39.175846) (xy 105.33126 -39.204138)
			(xy 105.320084 -39.21125) (xy 105.307638 -39.233602) (xy 105.307638 -39.346378) (xy 105.320084 -39.36873)
			(xy 105.33126 -39.375842) (xy 105.376905 -39.405244) (xy 105.463996 -39.470097) (xy 105.545801 -39.541503)
			(xy 105.621827 -39.619033) (xy 105.691617 -39.702221) (xy 105.754751 -39.790565) (xy 105.810851 -39.883536)
			(xy 105.859579 -39.980574) (xy 105.900641 -40.081096) (xy 105.933792 -40.184498) (xy 105.958831 -40.290157)
			(xy 105.975608 -40.397438) (xy 105.984022 -40.505697) (xy 105.984548 -40.55999) (xy 105.984095 -40.612343)
			(xy 105.976272 -40.716757) (xy 105.960669 -40.820294) (xy 105.937372 -40.922376) (xy 105.906513 -41.022432)
			(xy 105.868263 -41.119902) (xy 105.822837 -41.214241) (xy 105.770489 -41.304922) (xy 105.711511 -41.391438)
			(xy 105.646233 -41.473306) (xy 105.57502 -41.550066) (xy 105.498271 -41.621291) (xy 105.416414 -41.686581)
			(xy 105.329907 -41.745573) (xy 105.239234 -41.797935) (xy 105.144902 -41.843376) (xy 105.047438 -41.881641)
			(xy 104.947387 -41.912516) (xy 104.845308 -41.935828) (xy 104.741774 -41.951448) (xy 104.637361 -41.959287)
			(xy 104.585008 -41.959784) (xy 104.530709 -41.959246) (xy 104.422437 -41.95083) (xy 104.315143 -41.934047)
			(xy 104.209473 -41.908999) (xy 104.106062 -41.875835) (xy 104.005533 -41.834757) (xy 103.90849 -41.786011)
			(xy 103.815516 -41.729889) (xy 103.727173 -41.666731) (xy 103.64399 -41.596915) (xy 103.566469 -41.520862)
			(xy 103.495075 -41.43903) (xy 103.430239 -41.35191) (xy 103.40086 -41.306242) (xy 103.393748 -41.295066)
			(xy 103.371396 -41.28262) (xy 103.25862 -41.28262) (xy 103.236268 -41.295066) (xy 103.229156 -41.306242)
			(xy 103.199787 -41.351917) (xy 103.13495 -41.439038) (xy 103.063556 -41.520872) (xy 102.986034 -41.596926)
			(xy 102.902851 -41.666744) (xy 102.814507 -41.729904) (xy 102.721533 -41.786026) (xy 102.624489 -41.834774)
			(xy 102.523959 -41.875854) (xy 102.420547 -41.909019) (xy 102.314876 -41.934068) (xy 102.207581 -41.950853)
			(xy 102.099308 -41.95927) (xy 102.045008 -41.959784) (xy 101.992654 -41.959255) (xy 101.888238 -41.95143)
			(xy 101.7847 -41.935823) (xy 101.682617 -41.912521) (xy 101.582562 -41.881656) (xy 101.485093 -41.843398)
			(xy 101.390756 -41.797963) (xy 101.300078 -41.745605) (xy 101.213567 -41.686616) (xy 101.131707 -41.621327)
			(xy 101.054955 -41.550102) (xy 100.983742 -41.47334) (xy 100.918464 -41.39147) (xy 100.859487 -41.304951)
			(xy 100.807142 -41.214266) (xy 100.761721 -41.119922) (xy 100.723478 -41.022448) (xy 100.692627 -40.922388)
			(xy 100.66934 -40.820302) (xy 100.653748 -40.716761) (xy 100.645938 -40.612344) (xy 100.645468 -40.55999)
			(xy 100.646019 -40.505697) (xy 100.654426 -40.397438) (xy 100.671197 -40.290155) (xy 100.696231 -40.184495)
			(xy 100.729377 -40.081093) (xy 100.770436 -39.980569) (xy 100.819162 -39.88353) (xy 100.87526 -39.790558)
			(xy 100.938394 -39.702213) (xy 101.008184 -39.619026) (xy 101.084211 -39.541497) (xy 101.166016 -39.470092)
			(xy 101.253109 -39.405241) (xy 101.298756 -39.375842) (xy 101.309932 -39.36873) (xy 101.322378 -39.346378)
			(xy 101.322378 -39.233602) (xy 101.309932 -39.21125) (xy 101.298756 -39.204138) (xy 101.25478 -39.175858)
			(xy 101.170735 -39.113648) (xy 101.091567 -39.045341) (xy 101.017716 -38.971316) (xy 100.949595 -38.891987)
			(xy 100.887583 -38.807796) (xy 100.832027 -38.719212) (xy 100.783235 -38.62673) (xy 100.74148 -38.530865)
			(xy 100.706995 -38.432152) (xy 100.679971 -38.33114) (xy 100.660561 -38.228394) (xy 100.648871 -38.124486)
			(xy 100.644968 -38.019995) (xy 0.509016 -38.019995) (xy 0.509016 -46.6242) (xy 288.755312 -46.6242)
			(xy 288.759342 -46.539599) (xy 288.771396 -46.455763) (xy 288.791365 -46.373454) (xy 288.819068 -46.293415)
			(xy 288.854253 -46.216372) (xy 288.896603 -46.143023) (xy 288.945734 -46.074031) (xy 289.0012 -46.010023)
			(xy 289.0625 -45.951576) (xy 289.129078 -45.899222) (xy 289.200331 -45.853433) (xy 289.275615 -45.814625)
			(xy 289.354246 -45.783149) (xy 289.435514 -45.759291) (xy 289.518681 -45.743265) (xy 289.602995 -45.735218)
			(xy 289.645344 -45.734732) (xy 289.684496 -45.735134) (xy 289.7625 -45.741969) (xy 289.8396 -45.755642)
			(xy 289.915198 -45.776048) (xy 289.988706 -45.803028) (xy 290.024312 -45.819314) (xy 290.034699 -45.823549)
			(xy 290.057105 -45.823549) (xy 290.067492 -45.819314) (xy 290.103097 -45.80303) (xy 290.176614 -45.77608)
			(xy 290.252213 -45.755686) (xy 290.32931 -45.742008) (xy 290.407309 -45.735149) (xy 290.44646 -45.734732)
			(xy 290.488812 -45.735138) (xy 290.573134 -45.743186) (xy 290.656308 -45.759214) (xy 290.737583 -45.783075)
			(xy 290.816221 -45.814554) (xy 290.891511 -45.853365) (xy 290.96277 -45.899158) (xy 291.029354 -45.951517)
			(xy 291.090659 -46.009969) (xy 291.14613 -46.073983) (xy 291.195265 -46.142981) (xy 291.237618 -46.216336)
			(xy 291.272807 -46.293386) (xy 291.300512 -46.373432) (xy 291.320482 -46.455749) (xy 291.332537 -46.539591)
			(xy 291.336568 -46.6242) (xy 291.332537 -46.708809) (xy 291.320482 -46.792651) (xy 291.300512 -46.874968)
			(xy 291.272807 -46.955014) (xy 291.237618 -47.032064) (xy 291.195265 -47.105419) (xy 291.14613 -47.174417)
			(xy 291.090659 -47.238431) (xy 291.029354 -47.296883) (xy 290.96277 -47.349242) (xy 290.891511 -47.395035)
			(xy 290.85596 -47.413361) (xy 291.845742 -47.413361) (xy 291.845742 -47.328639) (xy 291.853795 -47.244302)
			(xy 291.869829 -47.161112) (xy 291.893697 -47.079822) (xy 291.925185 -47.00117) (xy 291.964007 -46.925867)
			(xy 292.00981 -46.854595) (xy 292.062181 -46.787999) (xy 292.120646 -46.726684) (xy 292.184674 -46.671203)
			(xy 292.253686 -46.62206) (xy 292.327056 -46.5797) (xy 292.404121 -46.544505) (xy 292.484183 -46.516796)
			(xy 292.566516 -46.496822) (xy 292.650375 -46.484765) (xy 292.735 -46.480734) (xy 292.819625 -46.484765)
			(xy 292.903484 -46.496822) (xy 292.985817 -46.516796) (xy 293.065879 -46.544505) (xy 293.142944 -46.5797)
			(xy 293.216314 -46.62206) (xy 293.285326 -46.671203) (xy 293.349354 -46.726684) (xy 293.407819 -46.787999)
			(xy 293.46019 -46.854595) (xy 293.505993 -46.925867) (xy 293.544815 -47.00117) (xy 293.576303 -47.079822)
			(xy 293.600171 -47.161112) (xy 293.616205 -47.244302) (xy 293.624258 -47.328639) (xy 293.624762 -47.371)
			(xy 293.624258 -47.413361) (xy 293.616205 -47.497698) (xy 293.600171 -47.580888) (xy 293.576303 -47.662178)
			(xy 293.544815 -47.74083) (xy 293.505993 -47.816133) (xy 293.46019 -47.887405) (xy 293.407819 -47.954001)
			(xy 293.349354 -48.015316) (xy 293.285326 -48.070797) (xy 293.216314 -48.11994) (xy 293.142944 -48.1623)
			(xy 293.065879 -48.197495) (xy 292.985817 -48.225204) (xy 292.903484 -48.245178) (xy 292.819625 -48.257235)
			(xy 292.735 -48.261267) (xy 292.650375 -48.257235) (xy 292.566516 -48.245178) (xy 292.484183 -48.225204)
			(xy 292.404121 -48.197495) (xy 292.327056 -48.1623) (xy 292.253686 -48.11994) (xy 292.184674 -48.070797)
			(xy 292.120646 -48.015316) (xy 292.062181 -47.954001) (xy 292.00981 -47.887405) (xy 291.964007 -47.816133)
			(xy 291.925185 -47.74083) (xy 291.893697 -47.662178) (xy 291.869829 -47.580888) (xy 291.853795 -47.497698)
			(xy 291.845742 -47.413361) (xy 290.85596 -47.413361) (xy 290.816221 -47.433846) (xy 290.737583 -47.465325)
			(xy 290.656308 -47.489186) (xy 290.573134 -47.505214) (xy 290.488812 -47.513262) (xy 290.44646 -47.513748)
			(xy 290.407308 -47.513346) (xy 290.329304 -47.506512) (xy 290.252204 -47.492839) (xy 290.176606 -47.472433)
			(xy 290.103098 -47.445452) (xy 290.067492 -47.429166) (xy 290.057105 -47.424931) (xy 290.034699 -47.424931)
			(xy 290.024312 -47.429166) (xy 289.988705 -47.445448) (xy 289.915189 -47.472398) (xy 289.839591 -47.492792)
			(xy 289.762494 -47.506472) (xy 289.684494 -47.513331) (xy 289.645344 -47.513748) (xy 289.602995 -47.513182)
			(xy 289.518681 -47.505135) (xy 289.435514 -47.489109) (xy 289.354246 -47.465251) (xy 289.275615 -47.433775)
			(xy 289.200331 -47.394967) (xy 289.129078 -47.349178) (xy 289.0625 -47.296824) (xy 289.0012 -47.238377)
			(xy 288.945734 -47.174369) (xy 288.896603 -47.105377) (xy 288.854253 -47.032028) (xy 288.819068 -46.954985)
			(xy 288.791365 -46.874946) (xy 288.771396 -46.792637) (xy 288.759342 -46.708801) (xy 288.755312 -46.6242)
			(xy 0.509016 -46.6242) (xy 0.509016 -48.327818) (xy 257.330448 -48.327818) (xy 257.331032 -48.281422)
			(xy 257.340676 -48.189134) (xy 257.359872 -48.09835) (xy 257.38841 -48.010057) (xy 257.406648 -47.967392)
			(xy 257.410445 -47.957447) (xy 257.410452 -47.936186) (xy 257.406648 -47.926244) (xy 257.388413 -47.883578)
			(xy 257.359865 -47.795287) (xy 257.340669 -47.704503) (xy 257.331034 -47.612214) (xy 257.330448 -47.565818)
			(xy 257.330952 -47.52347) (xy 257.339003 -47.439156) (xy 257.355032 -47.35599) (xy 257.378893 -47.274723)
			(xy 257.410372 -47.196093) (xy 257.449183 -47.120812) (xy 257.494973 -47.04956) (xy 257.547329 -46.982984)
			(xy 257.605777 -46.921686) (xy 257.669787 -46.866221) (xy 257.738779 -46.817092) (xy 257.812129 -46.774743)
			(xy 257.889172 -46.739559) (xy 257.969211 -46.711857) (xy 258.05152 -46.691889) (xy 258.135355 -46.679836)
			(xy 258.219956 -46.675806) (xy 258.304557 -46.679836) (xy 258.388392 -46.691889) (xy 258.470701 -46.711857)
			(xy 258.55074 -46.739559) (xy 258.627783 -46.774743) (xy 258.701133 -46.817092) (xy 258.770125 -46.866221)
			(xy 258.834135 -46.921686) (xy 258.892583 -46.982984) (xy 258.944939 -47.04956) (xy 258.990729 -47.120812)
			(xy 259.02954 -47.196093) (xy 259.061019 -47.274723) (xy 259.08488 -47.35599) (xy 259.100909 -47.439156)
			(xy 259.10896 -47.52347) (xy 259.109464 -47.565818) (xy 259.108891 -47.612214) (xy 259.099244 -47.704503)
			(xy 259.080045 -47.795286) (xy 259.051504 -47.88358) (xy 259.033264 -47.926244) (xy 259.029445 -47.936182)
			(xy 259.029452 -47.95745) (xy 259.033264 -47.967392) (xy 259.051512 -48.010053) (xy 259.080056 -48.098346)
			(xy 259.099248 -48.189131) (xy 259.10888 -48.281422) (xy 259.109464 -48.327818) (xy 259.10896 -48.370166)
			(xy 259.100909 -48.45448) (xy 259.08488 -48.537646) (xy 259.061019 -48.618913) (xy 259.02954 -48.697543)
			(xy 258.990729 -48.772824) (xy 258.944939 -48.844076) (xy 258.892583 -48.910652) (xy 258.834135 -48.97195)
			(xy 258.770125 -49.027415) (xy 258.701133 -49.076544) (xy 258.627783 -49.118893) (xy 258.55074 -49.154077)
			(xy 258.470701 -49.181779) (xy 258.388392 -49.201747) (xy 258.304557 -49.2138) (xy 258.219956 -49.217831)
			(xy 258.135355 -49.2138) (xy 258.05152 -49.201747) (xy 257.969211 -49.181779) (xy 257.889172 -49.154077)
			(xy 257.812129 -49.118893) (xy 257.738779 -49.076544) (xy 257.669787 -49.027415) (xy 257.605777 -48.97195)
			(xy 257.547329 -48.910652) (xy 257.494973 -48.844076) (xy 257.449183 -48.772824) (xy 257.410372 -48.697543)
			(xy 257.378893 -48.618913) (xy 257.355032 -48.537646) (xy 257.339003 -48.45448) (xy 257.330952 -48.370166)
			(xy 257.330448 -48.327818) (xy 0.509016 -48.327818) (xy 0.509016 -52.2859) (xy 43.474132 -52.2859)
			(xy 43.47455 -52.246133) (xy 43.48159 -52.166911) (xy 43.495677 -52.088634) (xy 43.516699 -52.011928)
			(xy 43.544486 -51.937406) (xy 43.561254 -51.901344) (xy 43.565585 -51.890843) (xy 43.565585 -51.868157)
			(xy 43.561254 -51.857656) (xy 43.544513 -51.821583) (xy 43.516732 -51.74706) (xy 43.495709 -51.670357)
			(xy 43.481612 -51.592084) (xy 43.474554 -51.512866) (xy 43.474132 -51.4731) (xy 43.474546 -51.432489)
			(xy 43.481951 -51.351605) (xy 43.496699 -51.271733) (xy 43.518668 -51.193537) (xy 43.547674 -51.117671)
			(xy 43.583475 -51.044765) (xy 43.625775 -50.975426) (xy 43.674219 -50.910233) (xy 43.728406 -50.849727)
			(xy 43.787882 -50.794414) (xy 43.852155 -50.744753) (xy 43.920686 -50.701159) (xy 43.992907 -50.663994)
			(xy 44.030392 -50.648362) (xy 44.040552 -50.644044) (xy 44.055792 -50.628042) (xy 44.087796 -50.534062)
			(xy 44.08551 -50.511964) (xy 44.079922 -50.502566) (xy 44.060228 -50.46832) (xy 44.026305 -50.396969)
			(xy 43.998845 -50.322889) (xy 43.978066 -50.246665) (xy 43.96413 -50.168899) (xy 43.957148 -50.090203)
			(xy 43.956732 -50.0507) (xy 43.957152 -50.009596) (xy 43.964738 -49.927738) (xy 43.979844 -49.846929)
			(xy 44.002342 -49.767859) (xy 44.03204 -49.691202) (xy 44.068685 -49.617612) (xy 44.111963 -49.547717)
			(xy 44.161506 -49.482114) (xy 44.216891 -49.421363) (xy 44.277645 -49.36598) (xy 44.34325 -49.31644)
			(xy 44.413147 -49.273165) (xy 44.486738 -49.236524) (xy 44.563397 -49.206829) (xy 44.642468 -49.184335)
			(xy 44.723277 -49.169232) (xy 44.805136 -49.16165) (xy 44.84624 -49.161192) (xy 44.891005 -49.161711)
			(xy 44.980087 -49.170644) (xy 45.06782 -49.188486) (xy 45.153315 -49.215055) (xy 45.194728 -49.232058)
			(xy 45.204319 -49.235623) (xy 45.224761 -49.235623) (xy 45.234352 -49.232058) (xy 45.275769 -49.215065)
			(xy 45.361266 -49.188508) (xy 45.448997 -49.170667) (xy 45.538076 -49.161723) (xy 45.58284 -49.161192)
			(xy 45.625958 -49.161716) (xy 45.71179 -49.170059) (xy 45.796411 -49.186672) (xy 45.879027 -49.211399)
			(xy 45.919136 -49.227232) (xy 45.928507 -49.230558) (xy 45.948373 -49.230558) (xy 45.957744 -49.227232)
			(xy 45.997848 -49.211383) (xy 46.080465 -49.186656) (xy 46.165087 -49.170043) (xy 46.250921 -49.161699)
			(xy 46.29404 -49.161192) (xy 46.336388 -49.161696) (xy 46.420702 -49.169747) (xy 46.503868 -49.185776)
			(xy 46.585135 -49.209637) (xy 46.663765 -49.241116) (xy 46.739046 -49.279927) (xy 46.810298 -49.325717)
			(xy 46.876874 -49.378073) (xy 46.938172 -49.436521) (xy 46.993637 -49.500531) (xy 47.042766 -49.569523)
			(xy 47.085115 -49.642873) (xy 47.120299 -49.719916) (xy 47.148001 -49.799955) (xy 47.167969 -49.882264)
			(xy 47.180022 -49.966099) (xy 47.184053 -50.0507) (xy 47.180022 -50.135301) (xy 47.167969 -50.219136)
			(xy 47.148001 -50.301445) (xy 47.120299 -50.381484) (xy 47.085115 -50.458527) (xy 47.042766 -50.531877)
			(xy 46.993637 -50.600869) (xy 46.938172 -50.664879) (xy 46.876874 -50.723327) (xy 46.810298 -50.775683)
			(xy 46.739046 -50.821473) (xy 46.663765 -50.860284) (xy 46.585135 -50.891763) (xy 46.503868 -50.915624)
			(xy 46.420702 -50.931653) (xy 46.336388 -50.939704) (xy 46.29404 -50.940208) (xy 46.250922 -50.939691)
			(xy 46.165089 -50.931346) (xy 46.080468 -50.914731) (xy 45.997853 -50.890002) (xy 45.957744 -50.874168)
			(xy 45.948373 -50.870842) (xy 45.928507 -50.870842) (xy 45.919136 -50.874168) (xy 45.879023 -50.889992)
			(xy 45.796409 -50.914725) (xy 45.71179 -50.931346) (xy 45.625958 -50.939697) (xy 45.58284 -50.940208)
			(xy 45.538075 -50.939695) (xy 45.448993 -50.930761) (xy 45.36126 -50.912917) (xy 45.275765 -50.886346)
			(xy 45.234352 -50.869342) (xy 45.224761 -50.865777) (xy 45.204319 -50.865777) (xy 45.194728 -50.869342)
			(xy 45.179488 -50.875438) (xy 45.169328 -50.879756) (xy 45.154088 -50.895758) (xy 45.122084 -50.989738)
			(xy 45.12437 -51.011836) (xy 45.129958 -51.021234) (xy 45.14965 -51.055481) (xy 45.183574 -51.126832)
			(xy 45.211034 -51.200912) (xy 45.231814 -51.277135) (xy 45.24575 -51.354901) (xy 45.252732 -51.433597)
			(xy 45.253148 -51.4731) (xy 45.252732 -51.512867) (xy 45.245691 -51.59209) (xy 45.231604 -51.670366)
			(xy 45.210582 -51.747072) (xy 45.182794 -51.821594) (xy 45.166026 -51.857656) (xy 45.161691 -51.868157)
			(xy 45.161691 -51.890843) (xy 45.166026 -51.901344) (xy 45.182773 -51.937415) (xy 45.210551 -52.011938)
			(xy 45.231572 -52.088642) (xy 45.245668 -52.166915) (xy 45.252726 -52.246134) (xy 45.253148 -52.2859)
			(xy 45.252644 -52.328248) (xy 45.244593 -52.412562) (xy 45.228564 -52.495728) (xy 45.204703 -52.576995)
			(xy 45.173224 -52.655625) (xy 45.134413 -52.730906) (xy 45.088623 -52.802158) (xy 45.036267 -52.868734)
			(xy 44.986526 -52.9209) (xy 46.166532 -52.9209) (xy 46.167111 -52.874504) (xy 46.176757 -52.782216)
			(xy 46.195954 -52.691432) (xy 46.224493 -52.603139) (xy 46.242732 -52.560474) (xy 46.246541 -52.550532)
			(xy 46.246541 -52.529268) (xy 46.242732 -52.519326) (xy 46.22449 -52.476663) (xy 46.195944 -52.388371)
			(xy 46.176751 -52.297586) (xy 46.167117 -52.205296) (xy 46.166532 -52.1589) (xy 46.167036 -52.116552)
			(xy 46.175087 -52.032238) (xy 46.191116 -51.949072) (xy 46.214977 -51.867805) (xy 46.246456 -51.789175)
			(xy 46.285267 -51.713894) (xy 46.331057 -51.642642) (xy 46.383413 -51.576066) (xy 46.441861 -51.514768)
			(xy 46.505871 -51.459303) (xy 46.574863 -51.410174) (xy 46.648213 -51.367825) (xy 46.725256 -51.332641)
			(xy 46.805295 -51.304939) (xy 46.887604 -51.284971) (xy 46.971439 -51.272918) (xy 47.05604 -51.268888)
			(xy 47.140641 -51.272918) (xy 47.224476 -51.284971) (xy 47.306785 -51.304939) (xy 47.386824 -51.332641)
			(xy 47.463867 -51.367825) (xy 47.537217 -51.410174) (xy 47.606209 -51.459303) (xy 47.670219 -51.514768)
			(xy 47.728667 -51.576066) (xy 47.781023 -51.642642) (xy 47.826813 -51.713894) (xy 47.865624 -51.789175)
			(xy 47.897103 -51.867805) (xy 47.920964 -51.949072) (xy 47.936993 -52.032238) (xy 47.945044 -52.116552)
			(xy 47.945548 -52.1589) (xy 47.94497 -52.205296) (xy 47.935324 -52.297584) (xy 47.916127 -52.388368)
			(xy 47.887587 -52.476662) (xy 47.869348 -52.519326) (xy 47.86554 -52.529268) (xy 47.86554 -52.550532)
			(xy 47.869348 -52.560474) (xy 47.887595 -52.603135) (xy 47.916138 -52.691428) (xy 47.93533 -52.782213)
			(xy 47.944963 -52.874504) (xy 47.945068 -52.8828) (xy 48.427132 -52.8828) (xy 48.427711 -52.836404)
			(xy 48.437357 -52.744116) (xy 48.456554 -52.653332) (xy 48.485093 -52.565039) (xy 48.503332 -52.522374)
			(xy 48.507141 -52.512432) (xy 48.507141 -52.491168) (xy 48.503332 -52.481226) (xy 48.48509 -52.438563)
			(xy 48.456544 -52.350271) (xy 48.437351 -52.259486) (xy 48.427717 -52.167196) (xy 48.427132 -52.1208)
			(xy 48.427552 -52.079696) (xy 48.435138 -51.997838) (xy 48.450244 -51.917029) (xy 48.472742 -51.837959)
			(xy 48.50244 -51.761302) (xy 48.539085 -51.687712) (xy 48.582363 -51.617817) (xy 48.631906 -51.552214)
			(xy 48.687291 -51.491463) (xy 48.748045 -51.43608) (xy 48.81365 -51.38654) (xy 48.883547 -51.343265)
			(xy 48.957138 -51.306624) (xy 49.033797 -51.276929) (xy 49.112868 -51.254435) (xy 49.193677 -51.239332)
			(xy 49.275536 -51.23175) (xy 49.31664 -51.231292) (xy 49.363035 -51.231896) (xy 49.455323 -51.241535)
			(xy 49.546107 -51.260725) (xy 49.634401 -51.289257) (xy 49.677066 -51.307492) (xy 49.687008 -51.311298)
			(xy 49.708272 -51.311298) (xy 49.718214 -51.307492) (xy 49.760871 -51.289234) (xy 49.849165 -51.260693)
			(xy 49.939952 -51.241504) (xy 50.032243 -51.231875) (xy 50.07864 -51.231292) (xy 50.125035 -51.231896)
			(xy 50.217323 -51.241535) (xy 50.308107 -51.260725) (xy 50.396401 -51.289257) (xy 50.439066 -51.307492)
			(xy 50.449008 -51.311298) (xy 50.470272 -51.311298) (xy 50.480214 -51.307492) (xy 50.522871 -51.289234)
			(xy 50.611165 -51.260693) (xy 50.701952 -51.241504) (xy 50.794243 -51.231875) (xy 50.84064 -51.231292)
			(xy 50.881743 -51.231728) (xy 50.963598 -51.239317) (xy 51.044404 -51.254426) (xy 51.123472 -51.276925)
			(xy 51.200126 -51.306624) (xy 51.273713 -51.343269) (xy 51.343605 -51.386547) (xy 51.409206 -51.436089)
			(xy 51.469955 -51.491473) (xy 51.525336 -51.552225) (xy 51.574875 -51.617828) (xy 51.61815 -51.687722)
			(xy 51.654792 -51.761311) (xy 51.684487 -51.837966) (xy 51.706984 -51.917034) (xy 51.722089 -51.997841)
			(xy 51.729673 -52.079697) (xy 51.730148 -52.1208) (xy 51.72957 -52.167196) (xy 51.719924 -52.259484)
			(xy 51.706282 -52.324) (xy 70.992492 -52.324) (xy 70.99288 -52.285716) (xy 70.999419 -52.209427)
			(xy 71.0125 -52.133985) (xy 71.032027 -52.059948) (xy 71.044562 -52.023772) (xy 71.047213 -52.015335)
			(xy 71.047213 -51.997665) (xy 71.044562 -51.989228) (xy 71.032037 -51.95305) (xy 71.012529 -51.87901)
			(xy 70.999449 -51.803569) (xy 70.992894 -51.727283) (xy 70.992492 -51.689) (xy 70.992943 -51.648953)
			(xy 71.000117 -51.569181) (xy 71.014434 -51.490378) (xy 71.035778 -51.413181) (xy 71.063976 -51.338215)
			(xy 71.0988 -51.266088) (xy 71.139968 -51.197385) (xy 71.187146 -51.13266) (xy 71.213218 -51.10226)
			(xy 71.218983 -51.095171) (xy 71.225495 -51.078114) (xy 71.225918 -51.068986) (xy 71.225918 -51.039014)
			(xy 71.225484 -51.029891) (xy 71.218964 -51.012841) (xy 71.213218 -51.00574) (xy 71.187158 -50.975329)
			(xy 71.139979 -50.910606) (xy 71.098809 -50.841904) (xy 71.063981 -50.769779) (xy 71.035779 -50.694815)
			(xy 71.014429 -50.61762) (xy 71.000105 -50.538818) (xy 70.992923 -50.459047) (xy 70.992492 -50.419)
			(xy 70.99288 -50.380716) (xy 70.999419 -50.304427) (xy 71.0125 -50.228985) (xy 71.032027 -50.154948)
			(xy 71.044562 -50.118772) (xy 71.047213 -50.110335) (xy 71.047213 -50.092665) (xy 71.044562 -50.084228)
			(xy 71.032037 -50.04805) (xy 71.012529 -49.97401) (xy 70.999449 -49.898569) (xy 70.992894 -49.822283)
			(xy 70.992492 -49.784) (xy 70.992996 -49.741652) (xy 71.001047 -49.657338) (xy 71.017076 -49.574172)
			(xy 71.040937 -49.492905) (xy 71.072416 -49.414275) (xy 71.111227 -49.338994) (xy 71.157017 -49.267742)
			(xy 71.209373 -49.201166) (xy 71.267821 -49.139868) (xy 71.331831 -49.084403) (xy 71.400823 -49.035274)
			(xy 71.474173 -48.992925) (xy 71.551216 -48.957741) (xy 71.631255 -48.930039) (xy 71.713564 -48.910071)
			(xy 71.797399 -48.898018) (xy 71.882 -48.893988) (xy 71.966601 -48.898018) (xy 72.050436 -48.910071)
			(xy 72.132745 -48.930039) (xy 72.212784 -48.957741) (xy 72.289827 -48.992925) (xy 72.363177 -49.035274)
			(xy 72.432169 -49.084403) (xy 72.496179 -49.139868) (xy 72.554627 -49.201166) (xy 72.606983 -49.267742)
			(xy 72.652773 -49.338994) (xy 72.691584 -49.414275) (xy 72.723063 -49.492905) (xy 72.746924 -49.574172)
			(xy 72.762953 -49.657338) (xy 72.771004 -49.741652) (xy 72.771508 -49.784) (xy 72.77112 -49.822284)
			(xy 72.764581 -49.898573) (xy 72.7515 -49.974015) (xy 72.731973 -50.048052) (xy 72.719438 -50.084228)
			(xy 72.716787 -50.092665) (xy 72.716787 -50.110335) (xy 72.719438 -50.118772) (xy 72.731963 -50.15495)
			(xy 72.751471 -50.22899) (xy 72.764551 -50.304431) (xy 72.771106 -50.380717) (xy 72.771508 -50.419)
			(xy 72.771057 -50.459047) (xy 72.763883 -50.538819) (xy 72.749566 -50.617622) (xy 72.728222 -50.694819)
			(xy 72.700024 -50.769785) (xy 72.6652 -50.841912) (xy 72.624032 -50.910615) (xy 72.576854 -50.97534)
			(xy 72.550782 -51.00574) (xy 72.545017 -51.012829) (xy 72.538505 -51.029886) (xy 72.538082 -51.039014)
			(xy 72.538082 -51.068986) (xy 72.538516 -51.078109) (xy 72.545036 -51.095159) (xy 72.550782 -51.10226)
			(xy 72.576842 -51.132671) (xy 72.624021 -51.197394) (xy 72.665191 -51.266096) (xy 72.700019 -51.338221)
			(xy 72.728221 -51.413185) (xy 72.749571 -51.49038) (xy 72.763895 -51.569182) (xy 72.771077 -51.648953)
			(xy 72.771508 -51.689) (xy 72.77112 -51.727284) (xy 72.764581 -51.803573) (xy 72.7515 -51.879015)
			(xy 72.731973 -51.953052) (xy 72.719438 -51.989228) (xy 72.716787 -51.997665) (xy 72.716787 -52.015335)
			(xy 72.719438 -52.023772) (xy 72.731963 -52.05995) (xy 72.751471 -52.13399) (xy 72.764551 -52.209431)
			(xy 72.771106 -52.285717) (xy 72.771508 -52.324) (xy 76.453492 -52.324) (xy 76.45388 -52.285716)
			(xy 76.460419 -52.209427) (xy 76.4735 -52.133985) (xy 76.493027 -52.059948) (xy 76.505562 -52.023772)
			(xy 76.508213 -52.015335) (xy 76.508213 -51.997665) (xy 76.505562 -51.989228) (xy 76.493037 -51.95305)
			(xy 76.473529 -51.87901) (xy 76.460449 -51.803569) (xy 76.453894 -51.727283) (xy 76.453492 -51.689)
			(xy 76.453943 -51.648953) (xy 76.461117 -51.569181) (xy 76.475434 -51.490378) (xy 76.496778 -51.413181)
			(xy 76.524976 -51.338215) (xy 76.5598 -51.266088) (xy 76.600968 -51.197385) (xy 76.648146 -51.13266)
			(xy 76.674218 -51.10226) (xy 76.679983 -51.095171) (xy 76.686495 -51.078114) (xy 76.686918 -51.068986)
			(xy 76.686918 -51.039014) (xy 76.686484 -51.029891) (xy 76.679964 -51.012841) (xy 76.674218 -51.00574)
			(xy 76.648158 -50.975329) (xy 76.600979 -50.910606) (xy 76.559809 -50.841904) (xy 76.524981 -50.769779)
			(xy 76.496779 -50.694815) (xy 76.475429 -50.61762) (xy 76.461105 -50.538818) (xy 76.453923 -50.459047)
			(xy 76.453492 -50.419) (xy 76.45388 -50.380716) (xy 76.460419 -50.304427) (xy 76.4735 -50.228985)
			(xy 76.493027 -50.154948) (xy 76.505562 -50.118772) (xy 76.508213 -50.110335) (xy 76.508213 -50.092665)
			(xy 76.505562 -50.084228) (xy 76.493037 -50.04805) (xy 76.473529 -49.97401) (xy 76.460449 -49.898569)
			(xy 76.453894 -49.822283) (xy 76.453492 -49.784) (xy 76.453996 -49.741652) (xy 76.462047 -49.657338)
			(xy 76.478076 -49.574172) (xy 76.501937 -49.492905) (xy 76.533416 -49.414275) (xy 76.572227 -49.338994)
			(xy 76.618017 -49.267742) (xy 76.670373 -49.201166) (xy 76.728821 -49.139868) (xy 76.792831 -49.084403)
			(xy 76.861823 -49.035274) (xy 76.935173 -48.992925) (xy 77.012216 -48.957741) (xy 77.092255 -48.930039)
			(xy 77.174564 -48.910071) (xy 77.258399 -48.898018) (xy 77.343 -48.893988) (xy 77.427601 -48.898018)
			(xy 77.511436 -48.910071) (xy 77.593745 -48.930039) (xy 77.673784 -48.957741) (xy 77.750827 -48.992925)
			(xy 77.824177 -49.035274) (xy 77.893169 -49.084403) (xy 77.957179 -49.139868) (xy 78.015627 -49.201166)
			(xy 78.067983 -49.267742) (xy 78.113773 -49.338994) (xy 78.152584 -49.414275) (xy 78.184063 -49.492905)
			(xy 78.207924 -49.574172) (xy 78.223953 -49.657338) (xy 78.232004 -49.741652) (xy 78.232508 -49.784)
			(xy 78.23212 -49.822284) (xy 78.225581 -49.898573) (xy 78.2125 -49.974015) (xy 78.192973 -50.048052)
			(xy 78.180438 -50.084228) (xy 78.177787 -50.092665) (xy 78.177787 -50.110335) (xy 78.180438 -50.118772)
			(xy 78.192963 -50.15495) (xy 78.212471 -50.22899) (xy 78.225551 -50.304431) (xy 78.232106 -50.380717)
			(xy 78.232508 -50.419) (xy 78.232057 -50.459047) (xy 78.224883 -50.538819) (xy 78.210566 -50.617622)
			(xy 78.189222 -50.694819) (xy 78.161024 -50.769785) (xy 78.1262 -50.841912) (xy 78.085032 -50.910615)
			(xy 78.037854 -50.97534) (xy 78.011782 -51.00574) (xy 78.006017 -51.012829) (xy 77.999505 -51.029886)
			(xy 77.999082 -51.039014) (xy 77.999082 -51.068986) (xy 77.999516 -51.078109) (xy 78.006036 -51.095159)
			(xy 78.011782 -51.10226) (xy 78.037842 -51.132671) (xy 78.085021 -51.197394) (xy 78.126191 -51.266096)
			(xy 78.161019 -51.338221) (xy 78.189221 -51.413185) (xy 78.210571 -51.49038) (xy 78.224895 -51.569182)
			(xy 78.232077 -51.648953) (xy 78.232508 -51.689) (xy 78.23212 -51.727284) (xy 78.225581 -51.803573)
			(xy 78.2125 -51.879015) (xy 78.192973 -51.953052) (xy 78.180438 -51.989228) (xy 78.177787 -51.997665)
			(xy 78.177787 -52.015335) (xy 78.180438 -52.023772) (xy 78.192963 -52.05995) (xy 78.212471 -52.13399)
			(xy 78.225551 -52.209431) (xy 78.232106 -52.285717) (xy 78.232508 -52.324) (xy 81.914492 -52.324)
			(xy 81.91488 -52.285716) (xy 81.921419 -52.209427) (xy 81.9345 -52.133985) (xy 81.954027 -52.059948)
			(xy 81.966562 -52.023772) (xy 81.969213 -52.015335) (xy 81.969213 -51.997665) (xy 81.966562 -51.989228)
			(xy 81.954037 -51.95305) (xy 81.934529 -51.87901) (xy 81.921449 -51.803569) (xy 81.914894 -51.727283)
			(xy 81.914492 -51.689) (xy 81.914943 -51.648953) (xy 81.922117 -51.569181) (xy 81.936434 -51.490378)
			(xy 81.957778 -51.413181) (xy 81.985976 -51.338215) (xy 82.0208 -51.266088) (xy 82.061968 -51.197385)
			(xy 82.109146 -51.13266) (xy 82.135218 -51.10226) (xy 82.140983 -51.095171) (xy 82.147495 -51.078114)
			(xy 82.147918 -51.068986) (xy 82.147918 -51.039014) (xy 82.147484 -51.029891) (xy 82.140964 -51.012841)
			(xy 82.135218 -51.00574) (xy 82.109158 -50.975329) (xy 82.061979 -50.910606) (xy 82.020809 -50.841904)
			(xy 81.985981 -50.769779) (xy 81.957779 -50.694815) (xy 81.936429 -50.61762) (xy 81.922105 -50.538818)
			(xy 81.914923 -50.459047) (xy 81.914492 -50.419) (xy 81.91488 -50.380716) (xy 81.921419 -50.304427)
			(xy 81.9345 -50.228985) (xy 81.954027 -50.154948) (xy 81.966562 -50.118772) (xy 81.969213 -50.110335)
			(xy 81.969213 -50.092665) (xy 81.966562 -50.084228) (xy 81.954037 -50.04805) (xy 81.934529 -49.97401)
			(xy 81.921449 -49.898569) (xy 81.914894 -49.822283) (xy 81.914492 -49.784) (xy 81.914996 -49.741652)
			(xy 81.923047 -49.657338) (xy 81.939076 -49.574172) (xy 81.962937 -49.492905) (xy 81.994416 -49.414275)
			(xy 82.033227 -49.338994) (xy 82.079017 -49.267742) (xy 82.131373 -49.201166) (xy 82.189821 -49.139868)
			(xy 82.253831 -49.084403) (xy 82.322823 -49.035274) (xy 82.396173 -48.992925) (xy 82.473216 -48.957741)
			(xy 82.553255 -48.930039) (xy 82.635564 -48.910071) (xy 82.719399 -48.898018) (xy 82.804 -48.893988)
			(xy 82.888601 -48.898018) (xy 82.972436 -48.910071) (xy 83.054745 -48.930039) (xy 83.134784 -48.957741)
			(xy 83.211827 -48.992925) (xy 83.285177 -49.035274) (xy 83.354169 -49.084403) (xy 83.418179 -49.139868)
			(xy 83.476627 -49.201166) (xy 83.528983 -49.267742) (xy 83.574773 -49.338994) (xy 83.613584 -49.414275)
			(xy 83.645063 -49.492905) (xy 83.668924 -49.574172) (xy 83.684953 -49.657338) (xy 83.693004 -49.741652)
			(xy 83.693508 -49.784) (xy 83.69312 -49.822284) (xy 83.686581 -49.898573) (xy 83.6735 -49.974015)
			(xy 83.653973 -50.048052) (xy 83.641438 -50.084228) (xy 83.638787 -50.092665) (xy 83.638787 -50.110335)
			(xy 83.641438 -50.118772) (xy 83.653963 -50.15495) (xy 83.673471 -50.22899) (xy 83.686551 -50.304431)
			(xy 83.693106 -50.380717) (xy 83.693508 -50.419) (xy 83.693057 -50.459047) (xy 83.685883 -50.538819)
			(xy 83.671566 -50.617622) (xy 83.650222 -50.694819) (xy 83.622024 -50.769785) (xy 83.5872 -50.841912)
			(xy 83.546032 -50.910615) (xy 83.498854 -50.97534) (xy 83.472782 -51.00574) (xy 83.467017 -51.012829)
			(xy 83.460505 -51.029886) (xy 83.460082 -51.039014) (xy 83.460082 -51.068986) (xy 83.460516 -51.078109)
			(xy 83.467036 -51.095159) (xy 83.472782 -51.10226) (xy 83.498842 -51.132671) (xy 83.546021 -51.197394)
			(xy 83.587191 -51.266096) (xy 83.622019 -51.338221) (xy 83.650221 -51.413185) (xy 83.671571 -51.49038)
			(xy 83.685895 -51.569182) (xy 83.693077 -51.648953) (xy 83.693508 -51.689) (xy 83.69312 -51.727284)
			(xy 83.686581 -51.803573) (xy 83.6735 -51.879015) (xy 83.653973 -51.953052) (xy 83.641438 -51.989228)
			(xy 83.638787 -51.997665) (xy 83.638787 -52.015335) (xy 83.641438 -52.023772) (xy 83.653963 -52.05995)
			(xy 83.673471 -52.13399) (xy 83.686551 -52.209431) (xy 83.693106 -52.285717) (xy 83.693508 -52.324)
			(xy 87.375492 -52.324) (xy 87.37588 -52.285716) (xy 87.382419 -52.209427) (xy 87.3955 -52.133985)
			(xy 87.415027 -52.059948) (xy 87.427562 -52.023772) (xy 87.430213 -52.015335) (xy 87.430213 -51.997665)
			(xy 87.427562 -51.989228) (xy 87.415037 -51.95305) (xy 87.395529 -51.87901) (xy 87.382449 -51.803569)
			(xy 87.375894 -51.727283) (xy 87.375492 -51.689) (xy 87.375943 -51.648953) (xy 87.383117 -51.569181)
			(xy 87.397434 -51.490378) (xy 87.418778 -51.413181) (xy 87.446976 -51.338215) (xy 87.4818 -51.266088)
			(xy 87.522968 -51.197385) (xy 87.570146 -51.13266) (xy 87.596218 -51.10226) (xy 87.601983 -51.095171)
			(xy 87.608495 -51.078114) (xy 87.608918 -51.068986) (xy 87.608918 -51.039014) (xy 87.608484 -51.029891)
			(xy 87.601964 -51.012841) (xy 87.596218 -51.00574) (xy 87.570158 -50.975329) (xy 87.522979 -50.910606)
			(xy 87.481809 -50.841904) (xy 87.446981 -50.769779) (xy 87.418779 -50.694815) (xy 87.397429 -50.61762)
			(xy 87.383105 -50.538818) (xy 87.375923 -50.459047) (xy 87.375492 -50.419) (xy 87.37588 -50.380716)
			(xy 87.382419 -50.304427) (xy 87.3955 -50.228985) (xy 87.415027 -50.154948) (xy 87.427562 -50.118772)
			(xy 87.430213 -50.110335) (xy 87.430213 -50.092665) (xy 87.427562 -50.084228) (xy 87.415037 -50.04805)
			(xy 87.395529 -49.97401) (xy 87.382449 -49.898569) (xy 87.375894 -49.822283) (xy 87.375492 -49.784)
			(xy 87.375996 -49.741652) (xy 87.384047 -49.657338) (xy 87.400076 -49.574172) (xy 87.423937 -49.492905)
			(xy 87.455416 -49.414275) (xy 87.494227 -49.338994) (xy 87.540017 -49.267742) (xy 87.592373 -49.201166)
			(xy 87.650821 -49.139868) (xy 87.714831 -49.084403) (xy 87.783823 -49.035274) (xy 87.857173 -48.992925)
			(xy 87.934216 -48.957741) (xy 88.014255 -48.930039) (xy 88.096564 -48.910071) (xy 88.180399 -48.898018)
			(xy 88.265 -48.893988) (xy 88.349601 -48.898018) (xy 88.433436 -48.910071) (xy 88.515745 -48.930039)
			(xy 88.595784 -48.957741) (xy 88.672827 -48.992925) (xy 88.746177 -49.035274) (xy 88.815169 -49.084403)
			(xy 88.879179 -49.139868) (xy 88.937627 -49.201166) (xy 88.989983 -49.267742) (xy 89.035773 -49.338994)
			(xy 89.074584 -49.414275) (xy 89.106063 -49.492905) (xy 89.129924 -49.574172) (xy 89.145953 -49.657338)
			(xy 89.154004 -49.741652) (xy 89.154508 -49.784) (xy 89.15412 -49.822284) (xy 89.147581 -49.898573)
			(xy 89.1345 -49.974015) (xy 89.114973 -50.048052) (xy 89.102438 -50.084228) (xy 89.099787 -50.092665)
			(xy 89.099787 -50.110335) (xy 89.102438 -50.118772) (xy 89.114963 -50.15495) (xy 89.134471 -50.22899)
			(xy 89.147551 -50.304431) (xy 89.154106 -50.380717) (xy 89.154508 -50.419) (xy 89.154057 -50.459047)
			(xy 89.146883 -50.538819) (xy 89.132566 -50.617622) (xy 89.111222 -50.694819) (xy 89.083024 -50.769785)
			(xy 89.0482 -50.841912) (xy 89.007032 -50.910615) (xy 88.959854 -50.97534) (xy 88.933782 -51.00574)
			(xy 88.928017 -51.012829) (xy 88.921505 -51.029886) (xy 88.921082 -51.039014) (xy 88.921082 -51.068986)
			(xy 88.921516 -51.078109) (xy 88.928036 -51.095159) (xy 88.933782 -51.10226) (xy 88.959842 -51.132671)
			(xy 89.007021 -51.197394) (xy 89.048191 -51.266096) (xy 89.083019 -51.338221) (xy 89.111221 -51.413185)
			(xy 89.132571 -51.49038) (xy 89.146895 -51.569182) (xy 89.154077 -51.648953) (xy 89.154508 -51.689)
			(xy 89.15412 -51.727284) (xy 89.147581 -51.803573) (xy 89.1345 -51.879015) (xy 89.114973 -51.953052)
			(xy 89.102438 -51.989228) (xy 89.099787 -51.997665) (xy 89.099787 -52.015335) (xy 89.102438 -52.023772)
			(xy 89.114963 -52.05995) (xy 89.134471 -52.13399) (xy 89.147551 -52.209431) (xy 89.154106 -52.285717)
			(xy 89.154508 -52.324) (xy 92.836492 -52.324) (xy 92.83688 -52.285716) (xy 92.843419 -52.209427)
			(xy 92.8565 -52.133985) (xy 92.876027 -52.059948) (xy 92.888562 -52.023772) (xy 92.891213 -52.015335)
			(xy 92.891213 -51.997665) (xy 92.888562 -51.989228) (xy 92.876037 -51.95305) (xy 92.856529 -51.87901)
			(xy 92.843449 -51.803569) (xy 92.836894 -51.727283) (xy 92.836492 -51.689) (xy 92.836943 -51.648953)
			(xy 92.844117 -51.569181) (xy 92.858434 -51.490378) (xy 92.879778 -51.413181) (xy 92.907976 -51.338215)
			(xy 92.9428 -51.266088) (xy 92.983968 -51.197385) (xy 93.031146 -51.13266) (xy 93.057218 -51.10226)
			(xy 93.062983 -51.095171) (xy 93.069495 -51.078114) (xy 93.069918 -51.068986) (xy 93.069918 -51.039014)
			(xy 93.069484 -51.029891) (xy 93.062964 -51.012841) (xy 93.057218 -51.00574) (xy 93.031158 -50.975329)
			(xy 92.983979 -50.910606) (xy 92.942809 -50.841904) (xy 92.907981 -50.769779) (xy 92.879779 -50.694815)
			(xy 92.858429 -50.61762) (xy 92.844105 -50.538818) (xy 92.836923 -50.459047) (xy 92.836492 -50.419)
			(xy 92.83688 -50.380716) (xy 92.843419 -50.304427) (xy 92.8565 -50.228985) (xy 92.876027 -50.154948)
			(xy 92.888562 -50.118772) (xy 92.891213 -50.110335) (xy 92.891213 -50.092665) (xy 92.888562 -50.084228)
			(xy 92.876037 -50.04805) (xy 92.856529 -49.97401) (xy 92.843449 -49.898569) (xy 92.836894 -49.822283)
			(xy 92.836492 -49.784) (xy 92.836996 -49.741652) (xy 92.845047 -49.657338) (xy 92.861076 -49.574172)
			(xy 92.884937 -49.492905) (xy 92.916416 -49.414275) (xy 92.955227 -49.338994) (xy 93.001017 -49.267742)
			(xy 93.053373 -49.201166) (xy 93.111821 -49.139868) (xy 93.175831 -49.084403) (xy 93.244823 -49.035274)
			(xy 93.318173 -48.992925) (xy 93.395216 -48.957741) (xy 93.475255 -48.930039) (xy 93.557564 -48.910071)
			(xy 93.641399 -48.898018) (xy 93.726 -48.893988) (xy 93.810601 -48.898018) (xy 93.894436 -48.910071)
			(xy 93.976745 -48.930039) (xy 94.056784 -48.957741) (xy 94.133827 -48.992925) (xy 94.207177 -49.035274)
			(xy 94.276169 -49.084403) (xy 94.340179 -49.139868) (xy 94.398627 -49.201166) (xy 94.450983 -49.267742)
			(xy 94.496773 -49.338994) (xy 94.535584 -49.414275) (xy 94.567063 -49.492905) (xy 94.590924 -49.574172)
			(xy 94.606953 -49.657338) (xy 94.615004 -49.741652) (xy 94.615508 -49.784) (xy 94.61512 -49.822284)
			(xy 94.608581 -49.898573) (xy 94.5955 -49.974015) (xy 94.575973 -50.048052) (xy 94.563438 -50.084228)
			(xy 94.560787 -50.092665) (xy 94.560787 -50.110335) (xy 94.563438 -50.118772) (xy 94.575963 -50.15495)
			(xy 94.595471 -50.22899) (xy 94.608551 -50.304431) (xy 94.615106 -50.380717) (xy 94.615508 -50.419)
			(xy 94.615057 -50.459047) (xy 94.607883 -50.538819) (xy 94.593566 -50.617622) (xy 94.572222 -50.694819)
			(xy 94.544024 -50.769785) (xy 94.5092 -50.841912) (xy 94.468032 -50.910615) (xy 94.420854 -50.97534)
			(xy 94.394782 -51.00574) (xy 94.389017 -51.012829) (xy 94.382505 -51.029886) (xy 94.382082 -51.039014)
			(xy 94.382082 -51.068986) (xy 94.382516 -51.078109) (xy 94.389036 -51.095159) (xy 94.394782 -51.10226)
			(xy 94.420842 -51.132671) (xy 94.468021 -51.197394) (xy 94.509191 -51.266096) (xy 94.544019 -51.338221)
			(xy 94.572221 -51.413185) (xy 94.593571 -51.49038) (xy 94.607895 -51.569182) (xy 94.615077 -51.648953)
			(xy 94.615508 -51.689) (xy 94.61512 -51.727284) (xy 94.608581 -51.803573) (xy 94.5955 -51.879015)
			(xy 94.575973 -51.953052) (xy 94.563438 -51.989228) (xy 94.560787 -51.997665) (xy 94.560787 -52.015335)
			(xy 94.563438 -52.023772) (xy 94.575963 -52.05995) (xy 94.595471 -52.13399) (xy 94.608551 -52.209431)
			(xy 94.615106 -52.285717) (xy 94.615508 -52.324) (xy 98.297492 -52.324) (xy 98.29788 -52.285716)
			(xy 98.304419 -52.209427) (xy 98.3175 -52.133985) (xy 98.337027 -52.059948) (xy 98.349562 -52.023772)
			(xy 98.352213 -52.015335) (xy 98.352213 -51.997665) (xy 98.349562 -51.989228) (xy 98.337037 -51.95305)
			(xy 98.317529 -51.87901) (xy 98.304449 -51.803569) (xy 98.297894 -51.727283) (xy 98.297492 -51.689)
			(xy 98.297943 -51.648953) (xy 98.305117 -51.569181) (xy 98.319434 -51.490378) (xy 98.340778 -51.413181)
			(xy 98.368976 -51.338215) (xy 98.4038 -51.266088) (xy 98.444968 -51.197385) (xy 98.492146 -51.13266)
			(xy 98.518218 -51.10226) (xy 98.523983 -51.095171) (xy 98.530495 -51.078114) (xy 98.530918 -51.068986)
			(xy 98.530918 -51.039014) (xy 98.530484 -51.029891) (xy 98.523964 -51.012841) (xy 98.518218 -51.00574)
			(xy 98.492158 -50.975329) (xy 98.444979 -50.910606) (xy 98.403809 -50.841904) (xy 98.368981 -50.769779)
			(xy 98.340779 -50.694815) (xy 98.319429 -50.61762) (xy 98.305105 -50.538818) (xy 98.297923 -50.459047)
			(xy 98.297492 -50.419) (xy 98.29788 -50.380716) (xy 98.304419 -50.304427) (xy 98.3175 -50.228985)
			(xy 98.337027 -50.154948) (xy 98.349562 -50.118772) (xy 98.352213 -50.110335) (xy 98.352213 -50.092665)
			(xy 98.349562 -50.084228) (xy 98.337037 -50.04805) (xy 98.317529 -49.97401) (xy 98.304449 -49.898569)
			(xy 98.297894 -49.822283) (xy 98.297492 -49.784) (xy 98.297996 -49.741652) (xy 98.306047 -49.657338)
			(xy 98.322076 -49.574172) (xy 98.345937 -49.492905) (xy 98.377416 -49.414275) (xy 98.416227 -49.338994)
			(xy 98.462017 -49.267742) (xy 98.514373 -49.201166) (xy 98.572821 -49.139868) (xy 98.636831 -49.084403)
			(xy 98.705823 -49.035274) (xy 98.779173 -48.992925) (xy 98.856216 -48.957741) (xy 98.936255 -48.930039)
			(xy 99.018564 -48.910071) (xy 99.102399 -48.898018) (xy 99.187 -48.893988) (xy 99.271601 -48.898018)
			(xy 99.355436 -48.910071) (xy 99.437745 -48.930039) (xy 99.517784 -48.957741) (xy 99.594827 -48.992925)
			(xy 99.668177 -49.035274) (xy 99.737169 -49.084403) (xy 99.801179 -49.139868) (xy 99.859627 -49.201166)
			(xy 99.911983 -49.267742) (xy 99.957773 -49.338994) (xy 99.996584 -49.414275) (xy 100.028063 -49.492905)
			(xy 100.051924 -49.574172) (xy 100.067953 -49.657338) (xy 100.076004 -49.741652) (xy 100.076508 -49.784)
			(xy 100.07612 -49.822284) (xy 100.069581 -49.898573) (xy 100.0565 -49.974015) (xy 100.036973 -50.048052)
			(xy 100.024438 -50.084228) (xy 100.021787 -50.092665) (xy 100.021787 -50.110335) (xy 100.024438 -50.118772)
			(xy 100.036963 -50.15495) (xy 100.056471 -50.22899) (xy 100.069551 -50.304431) (xy 100.076106 -50.380717)
			(xy 100.076508 -50.419) (xy 100.076057 -50.459047) (xy 100.068883 -50.538819) (xy 100.054566 -50.617622)
			(xy 100.033222 -50.694819) (xy 100.005024 -50.769785) (xy 99.9702 -50.841912) (xy 99.929032 -50.910615)
			(xy 99.881854 -50.97534) (xy 99.855782 -51.00574) (xy 99.850017 -51.012829) (xy 99.843505 -51.029886)
			(xy 99.843082 -51.039014) (xy 99.843082 -51.068986) (xy 99.843516 -51.078109) (xy 99.850036 -51.095159)
			(xy 99.855782 -51.10226) (xy 99.881842 -51.132671) (xy 99.929021 -51.197394) (xy 99.970191 -51.266096)
			(xy 100.005019 -51.338221) (xy 100.033221 -51.413185) (xy 100.054571 -51.49038) (xy 100.068895 -51.569182)
			(xy 100.076077 -51.648953) (xy 100.076508 -51.689) (xy 100.07612 -51.727284) (xy 100.069581 -51.803573)
			(xy 100.0565 -51.879015) (xy 100.036973 -51.953052) (xy 100.024438 -51.989228) (xy 100.021787 -51.997665)
			(xy 100.021787 -52.015335) (xy 100.024438 -52.023772) (xy 100.036963 -52.05995) (xy 100.056471 -52.13399)
			(xy 100.069551 -52.209431) (xy 100.076106 -52.285717) (xy 100.076508 -52.324) (xy 103.758492 -52.324)
			(xy 103.75888 -52.285716) (xy 103.765419 -52.209427) (xy 103.7785 -52.133985) (xy 103.798027 -52.059948)
			(xy 103.810562 -52.023772) (xy 103.813213 -52.015335) (xy 103.813213 -51.997665) (xy 103.810562 -51.989228)
			(xy 103.798037 -51.95305) (xy 103.778529 -51.87901) (xy 103.765449 -51.803569) (xy 103.758894 -51.727283)
			(xy 103.758492 -51.689) (xy 103.758943 -51.648953) (xy 103.766117 -51.569181) (xy 103.780434 -51.490378)
			(xy 103.801778 -51.413181) (xy 103.829976 -51.338215) (xy 103.8648 -51.266088) (xy 103.905968 -51.197385)
			(xy 103.953146 -51.13266) (xy 103.979218 -51.10226) (xy 103.984983 -51.095171) (xy 103.991495 -51.078114)
			(xy 103.991918 -51.068986) (xy 103.991918 -51.039014) (xy 103.991484 -51.029891) (xy 103.984964 -51.012841)
			(xy 103.979218 -51.00574) (xy 103.953158 -50.975329) (xy 103.905979 -50.910606) (xy 103.864809 -50.841904)
			(xy 103.829981 -50.769779) (xy 103.801779 -50.694815) (xy 103.780429 -50.61762) (xy 103.766105 -50.538818)
			(xy 103.758923 -50.459047) (xy 103.758492 -50.419) (xy 103.75888 -50.380716) (xy 103.765419 -50.304427)
			(xy 103.7785 -50.228985) (xy 103.798027 -50.154948) (xy 103.810562 -50.118772) (xy 103.813213 -50.110335)
			(xy 103.813213 -50.092665) (xy 103.810562 -50.084228) (xy 103.798037 -50.04805) (xy 103.778529 -49.97401)
			(xy 103.765449 -49.898569) (xy 103.758894 -49.822283) (xy 103.758492 -49.784) (xy 103.758996 -49.741652)
			(xy 103.767047 -49.657338) (xy 103.783076 -49.574172) (xy 103.806937 -49.492905) (xy 103.838416 -49.414275)
			(xy 103.877227 -49.338994) (xy 103.923017 -49.267742) (xy 103.975373 -49.201166) (xy 104.033821 -49.139868)
			(xy 104.097831 -49.084403) (xy 104.166823 -49.035274) (xy 104.240173 -48.992925) (xy 104.317216 -48.957741)
			(xy 104.397255 -48.930039) (xy 104.479564 -48.910071) (xy 104.563399 -48.898018) (xy 104.648 -48.893988)
			(xy 104.732601 -48.898018) (xy 104.816436 -48.910071) (xy 104.898745 -48.930039) (xy 104.978784 -48.957741)
			(xy 105.055827 -48.992925) (xy 105.129177 -49.035274) (xy 105.198169 -49.084403) (xy 105.262179 -49.139868)
			(xy 105.320627 -49.201166) (xy 105.372983 -49.267742) (xy 105.418773 -49.338994) (xy 105.457584 -49.414275)
			(xy 105.489063 -49.492905) (xy 105.512924 -49.574172) (xy 105.528953 -49.657338) (xy 105.537004 -49.741652)
			(xy 105.537508 -49.784) (xy 105.53712 -49.822284) (xy 105.530581 -49.898573) (xy 105.5175 -49.974015)
			(xy 105.497973 -50.048052) (xy 105.485438 -50.084228) (xy 105.482787 -50.092665) (xy 105.482787 -50.110335)
			(xy 105.485438 -50.118772) (xy 105.497963 -50.15495) (xy 105.517471 -50.22899) (xy 105.530551 -50.304431)
			(xy 105.537106 -50.380717) (xy 105.537508 -50.419) (xy 105.537057 -50.459047) (xy 105.529883 -50.538819)
			(xy 105.515566 -50.617622) (xy 105.494222 -50.694819) (xy 105.466024 -50.769785) (xy 105.4312 -50.841912)
			(xy 105.390032 -50.910615) (xy 105.342854 -50.97534) (xy 105.316782 -51.00574) (xy 105.311017 -51.012829)
			(xy 105.304505 -51.029886) (xy 105.304082 -51.039014) (xy 105.304082 -51.068986) (xy 105.304516 -51.078109)
			(xy 105.311036 -51.095159) (xy 105.316782 -51.10226) (xy 105.342842 -51.132671) (xy 105.390021 -51.197394)
			(xy 105.431191 -51.266096) (xy 105.466019 -51.338221) (xy 105.494221 -51.413185) (xy 105.515571 -51.49038)
			(xy 105.529895 -51.569182) (xy 105.537077 -51.648953) (xy 105.537508 -51.689) (xy 105.53712 -51.727284)
			(xy 105.530581 -51.803573) (xy 105.5175 -51.879015) (xy 105.497973 -51.953052) (xy 105.485438 -51.989228)
			(xy 105.482787 -51.997665) (xy 105.482787 -52.015335) (xy 105.485438 -52.023772) (xy 105.497963 -52.05995)
			(xy 105.517471 -52.13399) (xy 105.528396 -52.197) (xy 149.097492 -52.197) (xy 149.09788 -52.158716)
			(xy 149.104419 -52.082427) (xy 149.1175 -52.006985) (xy 149.137027 -51.932948) (xy 149.149562 -51.896772)
			(xy 149.152213 -51.888335) (xy 149.152213 -51.870665) (xy 149.149562 -51.862228) (xy 149.137037 -51.82605)
			(xy 149.117529 -51.75201) (xy 149.104449 -51.676569) (xy 149.097894 -51.600283) (xy 149.097492 -51.562)
			(xy 149.097943 -51.521953) (xy 149.105117 -51.442181) (xy 149.119434 -51.363378) (xy 149.140778 -51.286181)
			(xy 149.168976 -51.211215) (xy 149.2038 -51.139088) (xy 149.244968 -51.070385) (xy 149.292146 -51.00566)
			(xy 149.318218 -50.97526) (xy 149.323983 -50.968171) (xy 149.330495 -50.951114) (xy 149.330918 -50.941986)
			(xy 149.330918 -50.912014) (xy 149.330484 -50.902891) (xy 149.323964 -50.885841) (xy 149.318218 -50.87874)
			(xy 149.292158 -50.848329) (xy 149.244979 -50.783606) (xy 149.203809 -50.714904) (xy 149.168981 -50.642779)
			(xy 149.140779 -50.567815) (xy 149.119429 -50.49062) (xy 149.105105 -50.411818) (xy 149.097923 -50.332047)
			(xy 149.097492 -50.292) (xy 149.09788 -50.253716) (xy 149.104419 -50.177427) (xy 149.1175 -50.101985)
			(xy 149.137027 -50.027948) (xy 149.149562 -49.991772) (xy 149.152213 -49.983335) (xy 149.152213 -49.965665)
			(xy 149.149562 -49.957228) (xy 149.137037 -49.92105) (xy 149.117529 -49.84701) (xy 149.104449 -49.771569)
			(xy 149.097894 -49.695283) (xy 149.097492 -49.657) (xy 149.097996 -49.614652) (xy 149.106047 -49.530338)
			(xy 149.122076 -49.447172) (xy 149.145937 -49.365905) (xy 149.177416 -49.287275) (xy 149.216227 -49.211994)
			(xy 149.262017 -49.140742) (xy 149.314373 -49.074166) (xy 149.372821 -49.012868) (xy 149.436831 -48.957403)
			(xy 149.505823 -48.908274) (xy 149.579173 -48.865925) (xy 149.656216 -48.830741) (xy 149.736255 -48.803039)
			(xy 149.818564 -48.783071) (xy 149.902399 -48.771018) (xy 149.987 -48.766988) (xy 150.071601 -48.771018)
			(xy 150.155436 -48.783071) (xy 150.237745 -48.803039) (xy 150.317784 -48.830741) (xy 150.394827 -48.865925)
			(xy 150.468177 -48.908274) (xy 150.537169 -48.957403) (xy 150.601179 -49.012868) (xy 150.659627 -49.074166)
			(xy 150.711983 -49.140742) (xy 150.757773 -49.211994) (xy 150.796584 -49.287275) (xy 150.828063 -49.365905)
			(xy 150.851924 -49.447172) (xy 150.867953 -49.530338) (xy 150.876004 -49.614652) (xy 150.876508 -49.657)
			(xy 150.87612 -49.695284) (xy 150.869581 -49.771573) (xy 150.8565 -49.847015) (xy 150.836973 -49.921052)
			(xy 150.824438 -49.957228) (xy 150.821787 -49.965665) (xy 150.821787 -49.983335) (xy 150.824438 -49.991772)
			(xy 150.836963 -50.02795) (xy 150.856471 -50.10199) (xy 150.869551 -50.177431) (xy 150.876106 -50.253717)
			(xy 150.876508 -50.292) (xy 150.876057 -50.332047) (xy 150.868883 -50.411819) (xy 150.854566 -50.490622)
			(xy 150.833222 -50.567819) (xy 150.805024 -50.642785) (xy 150.7702 -50.714912) (xy 150.729032 -50.783615)
			(xy 150.681854 -50.84834) (xy 150.655782 -50.87874) (xy 150.650017 -50.885829) (xy 150.643505 -50.902886)
			(xy 150.643082 -50.912014) (xy 150.643082 -50.941986) (xy 150.643516 -50.951109) (xy 150.650036 -50.968159)
			(xy 150.655782 -50.97526) (xy 150.681842 -51.005671) (xy 150.729021 -51.070394) (xy 150.770191 -51.139096)
			(xy 150.805019 -51.211221) (xy 150.833221 -51.286185) (xy 150.854571 -51.36338) (xy 150.868895 -51.442182)
			(xy 150.876077 -51.521953) (xy 150.876508 -51.562) (xy 150.87612 -51.600284) (xy 150.869581 -51.676573)
			(xy 150.8565 -51.752015) (xy 150.836973 -51.826052) (xy 150.824438 -51.862228) (xy 150.821787 -51.870665)
			(xy 150.821787 -51.888335) (xy 150.824438 -51.896772) (xy 150.836963 -51.93295) (xy 150.856471 -52.00699)
			(xy 150.869551 -52.082431) (xy 150.876106 -52.158717) (xy 150.876508 -52.197) (xy 154.558492 -52.197)
			(xy 154.55888 -52.158716) (xy 154.565419 -52.082427) (xy 154.5785 -52.006985) (xy 154.598027 -51.932948)
			(xy 154.610562 -51.896772) (xy 154.613213 -51.888335) (xy 154.613213 -51.870665) (xy 154.610562 -51.862228)
			(xy 154.598037 -51.82605) (xy 154.578529 -51.75201) (xy 154.565449 -51.676569) (xy 154.558894 -51.600283)
			(xy 154.558492 -51.562) (xy 154.558943 -51.521953) (xy 154.566117 -51.442181) (xy 154.580434 -51.363378)
			(xy 154.601778 -51.286181) (xy 154.629976 -51.211215) (xy 154.6648 -51.139088) (xy 154.705968 -51.070385)
			(xy 154.753146 -51.00566) (xy 154.779218 -50.97526) (xy 154.784983 -50.968171) (xy 154.791495 -50.951114)
			(xy 154.791918 -50.941986) (xy 154.791918 -50.912014) (xy 154.791484 -50.902891) (xy 154.784964 -50.885841)
			(xy 154.779218 -50.87874) (xy 154.753158 -50.848329) (xy 154.705979 -50.783606) (xy 154.664809 -50.714904)
			(xy 154.629981 -50.642779) (xy 154.601779 -50.567815) (xy 154.580429 -50.49062) (xy 154.566105 -50.411818)
			(xy 154.558923 -50.332047) (xy 154.558492 -50.292) (xy 154.55888 -50.253716) (xy 154.565419 -50.177427)
			(xy 154.5785 -50.101985) (xy 154.598027 -50.027948) (xy 154.610562 -49.991772) (xy 154.613213 -49.983335)
			(xy 154.613213 -49.965665) (xy 154.610562 -49.957228) (xy 154.598037 -49.92105) (xy 154.578529 -49.84701)
			(xy 154.565449 -49.771569) (xy 154.558894 -49.695283) (xy 154.558492 -49.657) (xy 154.558996 -49.614652)
			(xy 154.567047 -49.530338) (xy 154.583076 -49.447172) (xy 154.606937 -49.365905) (xy 154.638416 -49.287275)
			(xy 154.677227 -49.211994) (xy 154.723017 -49.140742) (xy 154.775373 -49.074166) (xy 154.833821 -49.012868)
			(xy 154.897831 -48.957403) (xy 154.966823 -48.908274) (xy 155.040173 -48.865925) (xy 155.117216 -48.830741)
			(xy 155.197255 -48.803039) (xy 155.279564 -48.783071) (xy 155.363399 -48.771018) (xy 155.448 -48.766988)
			(xy 155.532601 -48.771018) (xy 155.616436 -48.783071) (xy 155.698745 -48.803039) (xy 155.778784 -48.830741)
			(xy 155.855827 -48.865925) (xy 155.929177 -48.908274) (xy 155.998169 -48.957403) (xy 156.062179 -49.012868)
			(xy 156.120627 -49.074166) (xy 156.172983 -49.140742) (xy 156.218773 -49.211994) (xy 156.257584 -49.287275)
			(xy 156.289063 -49.365905) (xy 156.312924 -49.447172) (xy 156.328953 -49.530338) (xy 156.337004 -49.614652)
			(xy 156.337508 -49.657) (xy 156.33712 -49.695284) (xy 156.330581 -49.771573) (xy 156.3175 -49.847015)
			(xy 156.297973 -49.921052) (xy 156.285438 -49.957228) (xy 156.282787 -49.965665) (xy 156.282787 -49.983335)
			(xy 156.285438 -49.991772) (xy 156.297963 -50.02795) (xy 156.317471 -50.10199) (xy 156.330551 -50.177431)
			(xy 156.337106 -50.253717) (xy 156.337508 -50.292) (xy 156.337057 -50.332047) (xy 156.329883 -50.411819)
			(xy 156.315566 -50.490622) (xy 156.294222 -50.567819) (xy 156.266024 -50.642785) (xy 156.2312 -50.714912)
			(xy 156.190032 -50.783615) (xy 156.142854 -50.84834) (xy 156.116782 -50.87874) (xy 156.111017 -50.885829)
			(xy 156.104505 -50.902886) (xy 156.104082 -50.912014) (xy 156.104082 -50.941986) (xy 156.104516 -50.951109)
			(xy 156.111036 -50.968159) (xy 156.116782 -50.97526) (xy 156.142842 -51.005671) (xy 156.190021 -51.070394)
			(xy 156.231191 -51.139096) (xy 156.266019 -51.211221) (xy 156.294221 -51.286185) (xy 156.315571 -51.36338)
			(xy 156.329895 -51.442182) (xy 156.337077 -51.521953) (xy 156.337508 -51.562) (xy 156.33712 -51.600284)
			(xy 156.330581 -51.676573) (xy 156.3175 -51.752015) (xy 156.297973 -51.826052) (xy 156.285438 -51.862228)
			(xy 156.282787 -51.870665) (xy 156.282787 -51.888335) (xy 156.285438 -51.896772) (xy 156.297963 -51.93295)
			(xy 156.317471 -52.00699) (xy 156.330551 -52.082431) (xy 156.337106 -52.158717) (xy 156.337508 -52.197)
			(xy 160.019492 -52.197) (xy 160.01988 -52.158716) (xy 160.026419 -52.082427) (xy 160.0395 -52.006985)
			(xy 160.059027 -51.932948) (xy 160.071562 -51.896772) (xy 160.074213 -51.888335) (xy 160.074213 -51.870665)
			(xy 160.071562 -51.862228) (xy 160.059037 -51.82605) (xy 160.039529 -51.75201) (xy 160.026449 -51.676569)
			(xy 160.019894 -51.600283) (xy 160.019492 -51.562) (xy 160.019943 -51.521953) (xy 160.027117 -51.442181)
			(xy 160.041434 -51.363378) (xy 160.062778 -51.286181) (xy 160.090976 -51.211215) (xy 160.1258 -51.139088)
			(xy 160.166968 -51.070385) (xy 160.214146 -51.00566) (xy 160.240218 -50.97526) (xy 160.245983 -50.968171)
			(xy 160.252495 -50.951114) (xy 160.252918 -50.941986) (xy 160.252918 -50.912014) (xy 160.252484 -50.902891)
			(xy 160.245964 -50.885841) (xy 160.240218 -50.87874) (xy 160.214158 -50.848329) (xy 160.166979 -50.783606)
			(xy 160.125809 -50.714904) (xy 160.090981 -50.642779) (xy 160.062779 -50.567815) (xy 160.041429 -50.49062)
			(xy 160.027105 -50.411818) (xy 160.019923 -50.332047) (xy 160.019492 -50.292) (xy 160.01988 -50.253716)
			(xy 160.026419 -50.177427) (xy 160.0395 -50.101985) (xy 160.059027 -50.027948) (xy 160.071562 -49.991772)
			(xy 160.074213 -49.983335) (xy 160.074213 -49.965665) (xy 160.071562 -49.957228) (xy 160.059037 -49.92105)
			(xy 160.039529 -49.84701) (xy 160.026449 -49.771569) (xy 160.019894 -49.695283) (xy 160.019492 -49.657)
			(xy 160.019996 -49.614652) (xy 160.028047 -49.530338) (xy 160.044076 -49.447172) (xy 160.067937 -49.365905)
			(xy 160.099416 -49.287275) (xy 160.138227 -49.211994) (xy 160.184017 -49.140742) (xy 160.236373 -49.074166)
			(xy 160.294821 -49.012868) (xy 160.358831 -48.957403) (xy 160.427823 -48.908274) (xy 160.501173 -48.865925)
			(xy 160.578216 -48.830741) (xy 160.658255 -48.803039) (xy 160.740564 -48.783071) (xy 160.824399 -48.771018)
			(xy 160.909 -48.766988) (xy 160.993601 -48.771018) (xy 161.077436 -48.783071) (xy 161.159745 -48.803039)
			(xy 161.239784 -48.830741) (xy 161.316827 -48.865925) (xy 161.390177 -48.908274) (xy 161.459169 -48.957403)
			(xy 161.523179 -49.012868) (xy 161.581627 -49.074166) (xy 161.633983 -49.140742) (xy 161.679773 -49.211994)
			(xy 161.718584 -49.287275) (xy 161.750063 -49.365905) (xy 161.773924 -49.447172) (xy 161.789953 -49.530338)
			(xy 161.798004 -49.614652) (xy 161.798508 -49.657) (xy 161.79812 -49.695284) (xy 161.791581 -49.771573)
			(xy 161.7785 -49.847015) (xy 161.758973 -49.921052) (xy 161.746438 -49.957228) (xy 161.743787 -49.965665)
			(xy 161.743787 -49.983335) (xy 161.746438 -49.991772) (xy 161.758963 -50.02795) (xy 161.778471 -50.10199)
			(xy 161.791551 -50.177431) (xy 161.798106 -50.253717) (xy 161.798508 -50.292) (xy 161.798057 -50.332047)
			(xy 161.790883 -50.411819) (xy 161.776566 -50.490622) (xy 161.755222 -50.567819) (xy 161.727024 -50.642785)
			(xy 161.6922 -50.714912) (xy 161.651032 -50.783615) (xy 161.603854 -50.84834) (xy 161.577782 -50.87874)
			(xy 161.572017 -50.885829) (xy 161.565505 -50.902886) (xy 161.565082 -50.912014) (xy 161.565082 -50.941986)
			(xy 161.565516 -50.951109) (xy 161.572036 -50.968159) (xy 161.577782 -50.97526) (xy 161.603842 -51.005671)
			(xy 161.651021 -51.070394) (xy 161.692191 -51.139096) (xy 161.727019 -51.211221) (xy 161.755221 -51.286185)
			(xy 161.776571 -51.36338) (xy 161.790895 -51.442182) (xy 161.798077 -51.521953) (xy 161.798508 -51.562)
			(xy 161.79812 -51.600284) (xy 161.791581 -51.676573) (xy 161.7785 -51.752015) (xy 161.758973 -51.826052)
			(xy 161.746438 -51.862228) (xy 161.743787 -51.870665) (xy 161.743787 -51.888335) (xy 161.746438 -51.896772)
			(xy 161.758963 -51.93295) (xy 161.778471 -52.00699) (xy 161.791551 -52.082431) (xy 161.798106 -52.158717)
			(xy 161.798508 -52.197) (xy 165.480492 -52.197) (xy 165.48088 -52.158716) (xy 165.487419 -52.082427)
			(xy 165.5005 -52.006985) (xy 165.520027 -51.932948) (xy 165.532562 -51.896772) (xy 165.535213 -51.888335)
			(xy 165.535213 -51.870665) (xy 165.532562 -51.862228) (xy 165.520037 -51.82605) (xy 165.500529 -51.75201)
			(xy 165.487449 -51.676569) (xy 165.480894 -51.600283) (xy 165.480492 -51.562) (xy 165.480943 -51.521953)
			(xy 165.488117 -51.442181) (xy 165.502434 -51.363378) (xy 165.523778 -51.286181) (xy 165.551976 -51.211215)
			(xy 165.5868 -51.139088) (xy 165.627968 -51.070385) (xy 165.675146 -51.00566) (xy 165.701218 -50.97526)
			(xy 165.706983 -50.968171) (xy 165.713495 -50.951114) (xy 165.713918 -50.941986) (xy 165.713918 -50.912014)
			(xy 165.713484 -50.902891) (xy 165.706964 -50.885841) (xy 165.701218 -50.87874) (xy 165.675158 -50.848329)
			(xy 165.627979 -50.783606) (xy 165.586809 -50.714904) (xy 165.551981 -50.642779) (xy 165.523779 -50.567815)
			(xy 165.502429 -50.49062) (xy 165.488105 -50.411818) (xy 165.480923 -50.332047) (xy 165.480492 -50.292)
			(xy 165.48088 -50.253716) (xy 165.487419 -50.177427) (xy 165.5005 -50.101985) (xy 165.520027 -50.027948)
			(xy 165.532562 -49.991772) (xy 165.535213 -49.983335) (xy 165.535213 -49.965665) (xy 165.532562 -49.957228)
			(xy 165.520037 -49.92105) (xy 165.500529 -49.84701) (xy 165.487449 -49.771569) (xy 165.480894 -49.695283)
			(xy 165.480492 -49.657) (xy 165.480996 -49.614652) (xy 165.489047 -49.530338) (xy 165.505076 -49.447172)
			(xy 165.528937 -49.365905) (xy 165.560416 -49.287275) (xy 165.599227 -49.211994) (xy 165.645017 -49.140742)
			(xy 165.697373 -49.074166) (xy 165.755821 -49.012868) (xy 165.819831 -48.957403) (xy 165.888823 -48.908274)
			(xy 165.962173 -48.865925) (xy 166.039216 -48.830741) (xy 166.119255 -48.803039) (xy 166.201564 -48.783071)
			(xy 166.285399 -48.771018) (xy 166.37 -48.766988) (xy 166.454601 -48.771018) (xy 166.538436 -48.783071)
			(xy 166.620745 -48.803039) (xy 166.700784 -48.830741) (xy 166.777827 -48.865925) (xy 166.851177 -48.908274)
			(xy 166.920169 -48.957403) (xy 166.984179 -49.012868) (xy 167.042627 -49.074166) (xy 167.094983 -49.140742)
			(xy 167.140773 -49.211994) (xy 167.179584 -49.287275) (xy 167.211063 -49.365905) (xy 167.234924 -49.447172)
			(xy 167.250953 -49.530338) (xy 167.259004 -49.614652) (xy 167.259508 -49.657) (xy 167.25912 -49.695284)
			(xy 167.252581 -49.771573) (xy 167.2395 -49.847015) (xy 167.219973 -49.921052) (xy 167.207438 -49.957228)
			(xy 167.204787 -49.965665) (xy 167.204787 -49.983335) (xy 167.207438 -49.991772) (xy 167.219963 -50.02795)
			(xy 167.239471 -50.10199) (xy 167.252551 -50.177431) (xy 167.259106 -50.253717) (xy 167.259508 -50.292)
			(xy 167.259057 -50.332047) (xy 167.251883 -50.411819) (xy 167.237566 -50.490622) (xy 167.216222 -50.567819)
			(xy 167.188024 -50.642785) (xy 167.1532 -50.714912) (xy 167.112032 -50.783615) (xy 167.064854 -50.84834)
			(xy 167.038782 -50.87874) (xy 167.033017 -50.885829) (xy 167.026505 -50.902886) (xy 167.026082 -50.912014)
			(xy 167.026082 -50.941986) (xy 167.026516 -50.951109) (xy 167.033036 -50.968159) (xy 167.038782 -50.97526)
			(xy 167.064842 -51.005671) (xy 167.112021 -51.070394) (xy 167.153191 -51.139096) (xy 167.188019 -51.211221)
			(xy 167.216221 -51.286185) (xy 167.237571 -51.36338) (xy 167.251895 -51.442182) (xy 167.259077 -51.521953)
			(xy 167.259508 -51.562) (xy 167.25912 -51.600284) (xy 167.252581 -51.676573) (xy 167.2395 -51.752015)
			(xy 167.219973 -51.826052) (xy 167.207438 -51.862228) (xy 167.204787 -51.870665) (xy 167.204787 -51.888335)
			(xy 167.207438 -51.896772) (xy 167.219963 -51.93295) (xy 167.239471 -52.00699) (xy 167.252551 -52.082431)
			(xy 167.259106 -52.158717) (xy 167.259508 -52.197) (xy 170.941492 -52.197) (xy 170.94188 -52.158716)
			(xy 170.948419 -52.082427) (xy 170.9615 -52.006985) (xy 170.981027 -51.932948) (xy 170.993562 -51.896772)
			(xy 170.996213 -51.888335) (xy 170.996213 -51.870665) (xy 170.993562 -51.862228) (xy 170.981037 -51.82605)
			(xy 170.961529 -51.75201) (xy 170.948449 -51.676569) (xy 170.941894 -51.600283) (xy 170.941492 -51.562)
			(xy 170.941943 -51.521953) (xy 170.949117 -51.442181) (xy 170.963434 -51.363378) (xy 170.984778 -51.286181)
			(xy 171.012976 -51.211215) (xy 171.0478 -51.139088) (xy 171.088968 -51.070385) (xy 171.136146 -51.00566)
			(xy 171.162218 -50.97526) (xy 171.167983 -50.968171) (xy 171.174495 -50.951114) (xy 171.174918 -50.941986)
			(xy 171.174918 -50.912014) (xy 171.174484 -50.902891) (xy 171.167964 -50.885841) (xy 171.162218 -50.87874)
			(xy 171.136158 -50.848329) (xy 171.088979 -50.783606) (xy 171.047809 -50.714904) (xy 171.012981 -50.642779)
			(xy 170.984779 -50.567815) (xy 170.963429 -50.49062) (xy 170.949105 -50.411818) (xy 170.941923 -50.332047)
			(xy 170.941492 -50.292) (xy 170.94188 -50.253716) (xy 170.948419 -50.177427) (xy 170.9615 -50.101985)
			(xy 170.981027 -50.027948) (xy 170.993562 -49.991772) (xy 170.996213 -49.983335) (xy 170.996213 -49.965665)
			(xy 170.993562 -49.957228) (xy 170.981037 -49.92105) (xy 170.961529 -49.84701) (xy 170.948449 -49.771569)
			(xy 170.941894 -49.695283) (xy 170.941492 -49.657) (xy 170.941996 -49.614652) (xy 170.950047 -49.530338)
			(xy 170.966076 -49.447172) (xy 170.989937 -49.365905) (xy 171.021416 -49.287275) (xy 171.060227 -49.211994)
			(xy 171.106017 -49.140742) (xy 171.158373 -49.074166) (xy 171.216821 -49.012868) (xy 171.280831 -48.957403)
			(xy 171.349823 -48.908274) (xy 171.423173 -48.865925) (xy 171.500216 -48.830741) (xy 171.580255 -48.803039)
			(xy 171.662564 -48.783071) (xy 171.746399 -48.771018) (xy 171.831 -48.766988) (xy 171.915601 -48.771018)
			(xy 171.999436 -48.783071) (xy 172.081745 -48.803039) (xy 172.161784 -48.830741) (xy 172.238827 -48.865925)
			(xy 172.312177 -48.908274) (xy 172.381169 -48.957403) (xy 172.445179 -49.012868) (xy 172.503627 -49.074166)
			(xy 172.555983 -49.140742) (xy 172.601773 -49.211994) (xy 172.640584 -49.287275) (xy 172.672063 -49.365905)
			(xy 172.695924 -49.447172) (xy 172.711953 -49.530338) (xy 172.720004 -49.614652) (xy 172.720508 -49.657)
			(xy 172.72012 -49.695284) (xy 172.713581 -49.771573) (xy 172.7005 -49.847015) (xy 172.680973 -49.921052)
			(xy 172.668438 -49.957228) (xy 172.665787 -49.965665) (xy 172.665787 -49.983335) (xy 172.668438 -49.991772)
			(xy 172.680963 -50.02795) (xy 172.700471 -50.10199) (xy 172.713551 -50.177431) (xy 172.720106 -50.253717)
			(xy 172.720508 -50.292) (xy 172.720057 -50.332047) (xy 172.712883 -50.411819) (xy 172.698566 -50.490622)
			(xy 172.677222 -50.567819) (xy 172.649024 -50.642785) (xy 172.6142 -50.714912) (xy 172.573032 -50.783615)
			(xy 172.525854 -50.84834) (xy 172.499782 -50.87874) (xy 172.494017 -50.885829) (xy 172.487505 -50.902886)
			(xy 172.487082 -50.912014) (xy 172.487082 -50.941986) (xy 172.487516 -50.951109) (xy 172.494036 -50.968159)
			(xy 172.499782 -50.97526) (xy 172.525842 -51.005671) (xy 172.573021 -51.070394) (xy 172.614191 -51.139096)
			(xy 172.649019 -51.211221) (xy 172.677221 -51.286185) (xy 172.698571 -51.36338) (xy 172.712895 -51.442182)
			(xy 172.720077 -51.521953) (xy 172.720508 -51.562) (xy 172.72012 -51.600284) (xy 172.713581 -51.676573)
			(xy 172.7005 -51.752015) (xy 172.680973 -51.826052) (xy 172.668438 -51.862228) (xy 172.665787 -51.870665)
			(xy 172.665787 -51.888335) (xy 172.668438 -51.896772) (xy 172.680963 -51.93295) (xy 172.700471 -52.00699)
			(xy 172.713551 -52.082431) (xy 172.720106 -52.158717) (xy 172.720508 -52.197) (xy 176.399952 -52.197)
			(xy 176.400342 -52.158716) (xy 176.406881 -52.082427) (xy 176.419962 -52.006985) (xy 176.439487 -51.932948)
			(xy 176.452022 -51.896772) (xy 176.454674 -51.888335) (xy 176.454674 -51.870665) (xy 176.452022 -51.862228)
			(xy 176.439495 -51.82605) (xy 176.419988 -51.75201) (xy 176.406909 -51.676569) (xy 176.400354 -51.600283)
			(xy 176.399952 -51.562) (xy 176.400388 -51.521953) (xy 176.407563 -51.44218) (xy 176.421881 -51.363376)
			(xy 176.443226 -51.286178) (xy 176.471427 -51.211212) (xy 176.506253 -51.139086) (xy 176.547423 -51.070383)
			(xy 176.594604 -51.00566) (xy 176.620678 -50.97526) (xy 176.626439 -50.968167) (xy 176.632954 -50.951113)
			(xy 176.633378 -50.941986) (xy 176.633378 -50.912014) (xy 176.632931 -50.902892) (xy 176.626419 -50.885843)
			(xy 176.620678 -50.87874) (xy 176.594628 -50.84832) (xy 176.547447 -50.7836) (xy 176.506274 -50.714899)
			(xy 176.471445 -50.642776) (xy 176.443241 -50.567813) (xy 176.42189 -50.490618) (xy 176.407565 -50.411817)
			(xy 176.400383 -50.332047) (xy 176.399952 -50.292) (xy 176.400342 -50.253716) (xy 176.406881 -50.177427)
			(xy 176.419962 -50.101985) (xy 176.439487 -50.027948) (xy 176.452022 -49.991772) (xy 176.454674 -49.983335)
			(xy 176.454674 -49.965665) (xy 176.452022 -49.957228) (xy 176.439495 -49.92105) (xy 176.419988 -49.84701)
			(xy 176.406909 -49.771569) (xy 176.400354 -49.695283) (xy 176.399952 -49.657) (xy 176.400456 -49.614652)
			(xy 176.408507 -49.530338) (xy 176.424536 -49.447172) (xy 176.448397 -49.365905) (xy 176.479876 -49.287275)
			(xy 176.518687 -49.211994) (xy 176.564477 -49.140742) (xy 176.616833 -49.074166) (xy 176.675281 -49.012868)
			(xy 176.739291 -48.957403) (xy 176.808283 -48.908274) (xy 176.881633 -48.865925) (xy 176.958676 -48.830741)
			(xy 177.038715 -48.803039) (xy 177.121024 -48.783071) (xy 177.204859 -48.771018) (xy 177.28946 -48.766988)
			(xy 177.374061 -48.771018) (xy 177.457896 -48.783071) (xy 177.540205 -48.803039) (xy 177.620244 -48.830741)
			(xy 177.697287 -48.865925) (xy 177.770637 -48.908274) (xy 177.839629 -48.957403) (xy 177.903639 -49.012868)
			(xy 177.962087 -49.074166) (xy 178.014443 -49.140742) (xy 178.060233 -49.211994) (xy 178.099044 -49.287275)
			(xy 178.130523 -49.365905) (xy 178.154384 -49.447172) (xy 178.170413 -49.530338) (xy 178.178464 -49.614652)
			(xy 178.178968 -49.657) (xy 178.178577 -49.695284) (xy 178.172038 -49.771573) (xy 178.158958 -49.847015)
			(xy 178.139432 -49.921052) (xy 178.126898 -49.957228) (xy 178.124245 -49.965664) (xy 178.124245 -49.983336)
			(xy 178.126898 -49.991772) (xy 178.139422 -50.027951) (xy 178.15893 -50.10199) (xy 178.172011 -50.177431)
			(xy 178.178566 -50.253717) (xy 178.178968 -50.292) (xy 178.178527 -50.332047) (xy 178.171353 -50.411819)
			(xy 178.157035 -50.490623) (xy 178.13569 -50.567821) (xy 178.10749 -50.642787) (xy 178.072665 -50.714913)
			(xy 178.031495 -50.783617) (xy 177.984315 -50.84834) (xy 177.958242 -50.87874) (xy 177.952472 -50.885825)
			(xy 177.945964 -50.902886) (xy 177.945542 -50.912014) (xy 177.945542 -50.941986) (xy 177.945985 -50.951108)
			(xy 177.9525 -50.968158) (xy 177.958242 -50.97526) (xy 177.984295 -51.005677) (xy 178.031476 -51.070398)
			(xy 178.072647 -51.139099) (xy 178.107476 -51.211223) (xy 178.13568 -51.286186) (xy 178.15703 -51.363381)
			(xy 178.171355 -51.442183) (xy 178.178537 -51.521953) (xy 178.178968 -51.562) (xy 178.178577 -51.600284)
			(xy 178.172038 -51.676573) (xy 178.158958 -51.752015) (xy 178.139432 -51.826052) (xy 178.126898 -51.862228)
			(xy 178.124245 -51.870664) (xy 178.124245 -51.888336) (xy 178.126898 -51.896772) (xy 178.139422 -51.932951)
			(xy 178.15893 -52.00699) (xy 178.172011 -52.082431) (xy 178.178566 -52.158717) (xy 178.178968 -52.197)
			(xy 181.860952 -52.197) (xy 181.861342 -52.158716) (xy 181.867881 -52.082427) (xy 181.880962 -52.006985)
			(xy 181.900487 -51.932948) (xy 181.913022 -51.896772) (xy 181.915674 -51.888335) (xy 181.915674 -51.870665)
			(xy 181.913022 -51.862228) (xy 181.900495 -51.82605) (xy 181.880988 -51.75201) (xy 181.867909 -51.676569)
			(xy 181.861354 -51.600283) (xy 181.860952 -51.562) (xy 181.861388 -51.521953) (xy 181.868563 -51.44218)
			(xy 181.882881 -51.363376) (xy 181.904226 -51.286178) (xy 181.932427 -51.211212) (xy 181.967253 -51.139086)
			(xy 182.008423 -51.070383) (xy 182.055604 -51.00566) (xy 182.081678 -50.97526) (xy 182.087439 -50.968167)
			(xy 182.093954 -50.951113) (xy 182.094378 -50.941986) (xy 182.094378 -50.912014) (xy 182.093931 -50.902892)
			(xy 182.087419 -50.885843) (xy 182.081678 -50.87874) (xy 182.055628 -50.84832) (xy 182.008447 -50.7836)
			(xy 181.967274 -50.714899) (xy 181.932445 -50.642776) (xy 181.904241 -50.567813) (xy 181.88289 -50.490618)
			(xy 181.868565 -50.411817) (xy 181.861383 -50.332047) (xy 181.860952 -50.292) (xy 181.861342 -50.253716)
			(xy 181.867881 -50.177427) (xy 181.880962 -50.101985) (xy 181.900487 -50.027948) (xy 181.913022 -49.991772)
			(xy 181.915674 -49.983335) (xy 181.915674 -49.965665) (xy 181.913022 -49.957228) (xy 181.900495 -49.92105)
			(xy 181.880988 -49.84701) (xy 181.867909 -49.771569) (xy 181.861354 -49.695283) (xy 181.860952 -49.657)
			(xy 181.861456 -49.614652) (xy 181.869507 -49.530338) (xy 181.885536 -49.447172) (xy 181.909397 -49.365905)
			(xy 181.940876 -49.287275) (xy 181.979687 -49.211994) (xy 182.025477 -49.140742) (xy 182.077833 -49.074166)
			(xy 182.136281 -49.012868) (xy 182.200291 -48.957403) (xy 182.269283 -48.908274) (xy 182.342633 -48.865925)
			(xy 182.419676 -48.830741) (xy 182.499715 -48.803039) (xy 182.582024 -48.783071) (xy 182.665859 -48.771018)
			(xy 182.75046 -48.766988) (xy 182.835061 -48.771018) (xy 182.918896 -48.783071) (xy 183.001205 -48.803039)
			(xy 183.081244 -48.830741) (xy 183.158287 -48.865925) (xy 183.231637 -48.908274) (xy 183.300629 -48.957403)
			(xy 183.364639 -49.012868) (xy 183.423087 -49.074166) (xy 183.475443 -49.140742) (xy 183.521233 -49.211994)
			(xy 183.560044 -49.287275) (xy 183.591523 -49.365905) (xy 183.615384 -49.447172) (xy 183.631413 -49.530338)
			(xy 183.639464 -49.614652) (xy 183.639968 -49.657) (xy 183.639577 -49.695284) (xy 183.633038 -49.771573)
			(xy 183.619958 -49.847015) (xy 183.600432 -49.921052) (xy 183.587898 -49.957228) (xy 183.585245 -49.965664)
			(xy 183.585245 -49.983336) (xy 183.587898 -49.991772) (xy 183.600422 -50.027951) (xy 183.61993 -50.10199)
			(xy 183.633011 -50.177431) (xy 183.639566 -50.253717) (xy 183.639791 -50.275179) (xy 257.330698 -50.275179)
			(xy 257.330698 -50.190457) (xy 257.338751 -50.10612) (xy 257.354785 -50.02293) (xy 257.378653 -49.94164)
			(xy 257.410141 -49.862988) (xy 257.448963 -49.787685) (xy 257.494766 -49.716413) (xy 257.547137 -49.649817)
			(xy 257.605602 -49.588502) (xy 257.66963 -49.533021) (xy 257.738642 -49.483878) (xy 257.812012 -49.441518)
			(xy 257.889077 -49.406323) (xy 257.969139 -49.378614) (xy 258.051472 -49.35864) (xy 258.135331 -49.346583)
			(xy 258.219956 -49.342552) (xy 258.304581 -49.346583) (xy 258.38844 -49.35864) (xy 258.470773 -49.378614)
			(xy 258.550835 -49.406323) (xy 258.6279 -49.441518) (xy 258.70127 -49.483878) (xy 258.770282 -49.533021)
			(xy 258.83431 -49.588502) (xy 258.892775 -49.649817) (xy 258.945146 -49.716413) (xy 258.990949 -49.787685)
			(xy 259.029771 -49.862988) (xy 259.061259 -49.94164) (xy 259.085127 -50.02293) (xy 259.101161 -50.10612)
			(xy 259.109214 -50.190457) (xy 259.109718 -50.232818) (xy 259.109214 -50.275179) (xy 259.101161 -50.359516)
			(xy 259.085127 -50.442706) (xy 259.061259 -50.523996) (xy 259.029771 -50.602648) (xy 258.990949 -50.677951)
			(xy 258.945146 -50.749223) (xy 258.892775 -50.815819) (xy 258.83431 -50.877134) (xy 258.770282 -50.932615)
			(xy 258.70127 -50.981758) (xy 258.6279 -51.024118) (xy 258.562469 -51.054) (xy 275.335492 -51.054)
			(xy 275.336075 -51.007604) (xy 275.34572 -50.915316) (xy 275.364916 -50.824532) (xy 275.393454 -50.736239)
			(xy 275.411692 -50.693574) (xy 275.415498 -50.683632) (xy 275.415498 -50.662368) (xy 275.411692 -50.652426)
			(xy 275.393447 -50.609764) (xy 275.364903 -50.521471) (xy 275.34571 -50.430686) (xy 275.336077 -50.338396)
			(xy 275.335492 -50.292) (xy 275.335996 -50.249652) (xy 275.344047 -50.165338) (xy 275.360076 -50.082172)
			(xy 275.383937 -50.000905) (xy 275.415416 -49.922275) (xy 275.454227 -49.846994) (xy 275.500017 -49.775742)
			(xy 275.552373 -49.709166) (xy 275.610821 -49.647868) (xy 275.674831 -49.592403) (xy 275.743823 -49.543274)
			(xy 275.817173 -49.500925) (xy 275.894216 -49.465741) (xy 275.974255 -49.438039) (xy 276.056564 -49.418071)
			(xy 276.140399 -49.406018) (xy 276.225 -49.401988) (xy 276.309601 -49.406018) (xy 276.393436 -49.418071)
			(xy 276.475745 -49.438039) (xy 276.555784 -49.465741) (xy 276.632827 -49.500925) (xy 276.706177 -49.543274)
			(xy 276.775169 -49.592403) (xy 276.839179 -49.647868) (xy 276.897627 -49.709166) (xy 276.949983 -49.775742)
			(xy 276.995773 -49.846994) (xy 277.034584 -49.922275) (xy 277.066063 -50.000905) (xy 277.089924 -50.082172)
			(xy 277.105953 -50.165338) (xy 277.114004 -50.249652) (xy 277.114508 -50.292) (xy 277.113925 -50.338396)
			(xy 277.10428 -50.430684) (xy 277.085084 -50.521468) (xy 277.056546 -50.609761) (xy 277.038308 -50.652426)
			(xy 277.034502 -50.662368) (xy 277.034502 -50.683632) (xy 277.038308 -50.693574) (xy 277.056553 -50.736236)
			(xy 277.085097 -50.824529) (xy 277.10429 -50.915314) (xy 277.113923 -51.007604) (xy 277.114508 -51.054)
			(xy 277.114004 -51.096348) (xy 277.105953 -51.180662) (xy 277.089924 -51.263828) (xy 277.066063 -51.345095)
			(xy 277.034584 -51.423725) (xy 276.995773 -51.499006) (xy 276.949983 -51.570258) (xy 276.897627 -51.636834)
			(xy 276.839179 -51.698132) (xy 276.775169 -51.753597) (xy 276.706177 -51.802726) (xy 276.632827 -51.845075)
			(xy 276.555784 -51.880259) (xy 276.475745 -51.907961) (xy 276.393436 -51.927929) (xy 276.309601 -51.939982)
			(xy 276.225 -51.944013) (xy 276.140399 -51.939982) (xy 276.056564 -51.927929) (xy 275.974255 -51.907961)
			(xy 275.894216 -51.880259) (xy 275.817173 -51.845075) (xy 275.743823 -51.802726) (xy 275.674831 -51.753597)
			(xy 275.610821 -51.698132) (xy 275.552373 -51.636834) (xy 275.500017 -51.570258) (xy 275.454227 -51.499006)
			(xy 275.415416 -51.423725) (xy 275.383937 -51.345095) (xy 275.360076 -51.263828) (xy 275.344047 -51.180662)
			(xy 275.335996 -51.096348) (xy 275.335492 -51.054) (xy 258.562469 -51.054) (xy 258.550835 -51.059313)
			(xy 258.470773 -51.087022) (xy 258.38844 -51.106996) (xy 258.304581 -51.119053) (xy 258.219956 -51.123085)
			(xy 258.135331 -51.119053) (xy 258.051472 -51.106996) (xy 257.969139 -51.087022) (xy 257.889077 -51.059313)
			(xy 257.812012 -51.024118) (xy 257.738642 -50.981758) (xy 257.66963 -50.932615) (xy 257.605602 -50.877134)
			(xy 257.547137 -50.815819) (xy 257.494766 -50.749223) (xy 257.448963 -50.677951) (xy 257.410141 -50.602648)
			(xy 257.378653 -50.523996) (xy 257.354785 -50.442706) (xy 257.338751 -50.359516) (xy 257.330698 -50.275179)
			(xy 183.639791 -50.275179) (xy 183.639968 -50.292) (xy 183.639527 -50.332047) (xy 183.632353 -50.411819)
			(xy 183.618035 -50.490623) (xy 183.59669 -50.567821) (xy 183.56849 -50.642787) (xy 183.533665 -50.714913)
			(xy 183.492495 -50.783617) (xy 183.445315 -50.84834) (xy 183.419242 -50.87874) (xy 183.413472 -50.885825)
			(xy 183.406964 -50.902886) (xy 183.406542 -50.912014) (xy 183.406542 -50.941986) (xy 183.406985 -50.951108)
			(xy 183.4135 -50.968158) (xy 183.419242 -50.97526) (xy 183.445295 -51.005677) (xy 183.492476 -51.070398)
			(xy 183.533647 -51.139099) (xy 183.568476 -51.211223) (xy 183.59668 -51.286186) (xy 183.61803 -51.363381)
			(xy 183.632355 -51.442183) (xy 183.639537 -51.521953) (xy 183.639968 -51.562) (xy 183.639577 -51.600284)
			(xy 183.633038 -51.676573) (xy 183.619958 -51.752015) (xy 183.600432 -51.826052) (xy 183.587898 -51.862228)
			(xy 183.585245 -51.870664) (xy 183.585245 -51.888336) (xy 183.587898 -51.896772) (xy 183.600422 -51.932951)
			(xy 183.61993 -52.00699) (xy 183.633011 -52.082431) (xy 183.639566 -52.158717) (xy 183.639968 -52.197)
			(xy 183.639464 -52.239348) (xy 183.631413 -52.323662) (xy 183.615384 -52.406828) (xy 183.591523 -52.488095)
			(xy 183.560044 -52.566725) (xy 183.521233 -52.642006) (xy 183.475443 -52.713258) (xy 183.423087 -52.779834)
			(xy 183.364639 -52.841132) (xy 183.300629 -52.896597) (xy 183.231637 -52.945726) (xy 183.158287 -52.988075)
			(xy 183.081244 -53.023259) (xy 183.001205 -53.050961) (xy 182.918896 -53.070929) (xy 182.835061 -53.082982)
			(xy 182.75046 -53.087013) (xy 182.665859 -53.082982) (xy 182.582024 -53.070929) (xy 182.499715 -53.050961)
			(xy 182.419676 -53.023259) (xy 182.342633 -52.988075) (xy 182.269283 -52.945726) (xy 182.200291 -52.896597)
			(xy 182.136281 -52.841132) (xy 182.077833 -52.779834) (xy 182.025477 -52.713258) (xy 181.979687 -52.642006)
			(xy 181.940876 -52.566725) (xy 181.909397 -52.488095) (xy 181.885536 -52.406828) (xy 181.869507 -52.323662)
			(xy 181.861456 -52.239348) (xy 181.860952 -52.197) (xy 178.178968 -52.197) (xy 178.178464 -52.239348)
			(xy 178.170413 -52.323662) (xy 178.154384 -52.406828) (xy 178.130523 -52.488095) (xy 178.099044 -52.566725)
			(xy 178.060233 -52.642006) (xy 178.014443 -52.713258) (xy 177.962087 -52.779834) (xy 177.903639 -52.841132)
			(xy 177.839629 -52.896597) (xy 177.770637 -52.945726) (xy 177.697287 -52.988075) (xy 177.620244 -53.023259)
			(xy 177.540205 -53.050961) (xy 177.457896 -53.070929) (xy 177.374061 -53.082982) (xy 177.28946 -53.087013)
			(xy 177.204859 -53.082982) (xy 177.121024 -53.070929) (xy 177.038715 -53.050961) (xy 176.958676 -53.023259)
			(xy 176.881633 -52.988075) (xy 176.808283 -52.945726) (xy 176.739291 -52.896597) (xy 176.675281 -52.841132)
			(xy 176.616833 -52.779834) (xy 176.564477 -52.713258) (xy 176.518687 -52.642006) (xy 176.479876 -52.566725)
			(xy 176.448397 -52.488095) (xy 176.424536 -52.406828) (xy 176.408507 -52.323662) (xy 176.400456 -52.239348)
			(xy 176.399952 -52.197) (xy 172.720508 -52.197) (xy 172.720004 -52.239348) (xy 172.711953 -52.323662)
			(xy 172.695924 -52.406828) (xy 172.672063 -52.488095) (xy 172.640584 -52.566725) (xy 172.601773 -52.642006)
			(xy 172.555983 -52.713258) (xy 172.503627 -52.779834) (xy 172.445179 -52.841132) (xy 172.381169 -52.896597)
			(xy 172.312177 -52.945726) (xy 172.238827 -52.988075) (xy 172.161784 -53.023259) (xy 172.081745 -53.050961)
			(xy 171.999436 -53.070929) (xy 171.915601 -53.082982) (xy 171.831 -53.087013) (xy 171.746399 -53.082982)
			(xy 171.662564 -53.070929) (xy 171.580255 -53.050961) (xy 171.500216 -53.023259) (xy 171.423173 -52.988075)
			(xy 171.349823 -52.945726) (xy 171.280831 -52.896597) (xy 171.216821 -52.841132) (xy 171.158373 -52.779834)
			(xy 171.106017 -52.713258) (xy 171.060227 -52.642006) (xy 171.021416 -52.566725) (xy 170.989937 -52.488095)
			(xy 170.966076 -52.406828) (xy 170.950047 -52.323662) (xy 170.941996 -52.239348) (xy 170.941492 -52.197)
			(xy 167.259508 -52.197) (xy 167.259004 -52.239348) (xy 167.250953 -52.323662) (xy 167.234924 -52.406828)
			(xy 167.211063 -52.488095) (xy 167.179584 -52.566725) (xy 167.140773 -52.642006) (xy 167.094983 -52.713258)
			(xy 167.042627 -52.779834) (xy 166.984179 -52.841132) (xy 166.920169 -52.896597) (xy 166.851177 -52.945726)
			(xy 166.777827 -52.988075) (xy 166.700784 -53.023259) (xy 166.620745 -53.050961) (xy 166.538436 -53.070929)
			(xy 166.454601 -53.082982) (xy 166.37 -53.087013) (xy 166.285399 -53.082982) (xy 166.201564 -53.070929)
			(xy 166.119255 -53.050961) (xy 166.039216 -53.023259) (xy 165.962173 -52.988075) (xy 165.888823 -52.945726)
			(xy 165.819831 -52.896597) (xy 165.755821 -52.841132) (xy 165.697373 -52.779834) (xy 165.645017 -52.713258)
			(xy 165.599227 -52.642006) (xy 165.560416 -52.566725) (xy 165.528937 -52.488095) (xy 165.505076 -52.406828)
			(xy 165.489047 -52.323662) (xy 165.480996 -52.239348) (xy 165.480492 -52.197) (xy 161.798508 -52.197)
			(xy 161.798004 -52.239348) (xy 161.789953 -52.323662) (xy 161.773924 -52.406828) (xy 161.750063 -52.488095)
			(xy 161.718584 -52.566725) (xy 161.679773 -52.642006) (xy 161.633983 -52.713258) (xy 161.581627 -52.779834)
			(xy 161.523179 -52.841132) (xy 161.459169 -52.896597) (xy 161.390177 -52.945726) (xy 161.316827 -52.988075)
			(xy 161.239784 -53.023259) (xy 161.159745 -53.050961) (xy 161.077436 -53.070929) (xy 160.993601 -53.082982)
			(xy 160.909 -53.087013) (xy 160.824399 -53.082982) (xy 160.740564 -53.070929) (xy 160.658255 -53.050961)
			(xy 160.578216 -53.023259) (xy 160.501173 -52.988075) (xy 160.427823 -52.945726) (xy 160.358831 -52.896597)
			(xy 160.294821 -52.841132) (xy 160.236373 -52.779834) (xy 160.184017 -52.713258) (xy 160.138227 -52.642006)
			(xy 160.099416 -52.566725) (xy 160.067937 -52.488095) (xy 160.044076 -52.406828) (xy 160.028047 -52.323662)
			(xy 160.019996 -52.239348) (xy 160.019492 -52.197) (xy 156.337508 -52.197) (xy 156.337004 -52.239348)
			(xy 156.328953 -52.323662) (xy 156.312924 -52.406828) (xy 156.289063 -52.488095) (xy 156.257584 -52.566725)
			(xy 156.218773 -52.642006) (xy 156.172983 -52.713258) (xy 156.120627 -52.779834) (xy 156.062179 -52.841132)
			(xy 155.998169 -52.896597) (xy 155.929177 -52.945726) (xy 155.855827 -52.988075) (xy 155.778784 -53.023259)
			(xy 155.698745 -53.050961) (xy 155.616436 -53.070929) (xy 155.532601 -53.082982) (xy 155.448 -53.087013)
			(xy 155.363399 -53.082982) (xy 155.279564 -53.070929) (xy 155.197255 -53.050961) (xy 155.117216 -53.023259)
			(xy 155.040173 -52.988075) (xy 154.966823 -52.945726) (xy 154.897831 -52.896597) (xy 154.833821 -52.841132)
			(xy 154.775373 -52.779834) (xy 154.723017 -52.713258) (xy 154.677227 -52.642006) (xy 154.638416 -52.566725)
			(xy 154.606937 -52.488095) (xy 154.583076 -52.406828) (xy 154.567047 -52.323662) (xy 154.558996 -52.239348)
			(xy 154.558492 -52.197) (xy 150.876508 -52.197) (xy 150.876004 -52.239348) (xy 150.867953 -52.323662)
			(xy 150.851924 -52.406828) (xy 150.828063 -52.488095) (xy 150.796584 -52.566725) (xy 150.757773 -52.642006)
			(xy 150.711983 -52.713258) (xy 150.659627 -52.779834) (xy 150.601179 -52.841132) (xy 150.537169 -52.896597)
			(xy 150.468177 -52.945726) (xy 150.394827 -52.988075) (xy 150.317784 -53.023259) (xy 150.237745 -53.050961)
			(xy 150.155436 -53.070929) (xy 150.071601 -53.082982) (xy 149.987 -53.087013) (xy 149.902399 -53.082982)
			(xy 149.818564 -53.070929) (xy 149.736255 -53.050961) (xy 149.656216 -53.023259) (xy 149.579173 -52.988075)
			(xy 149.505823 -52.945726) (xy 149.436831 -52.896597) (xy 149.372821 -52.841132) (xy 149.314373 -52.779834)
			(xy 149.262017 -52.713258) (xy 149.216227 -52.642006) (xy 149.177416 -52.566725) (xy 149.145937 -52.488095)
			(xy 149.122076 -52.406828) (xy 149.106047 -52.323662) (xy 149.097996 -52.239348) (xy 149.097492 -52.197)
			(xy 105.528396 -52.197) (xy 105.530551 -52.209431) (xy 105.537106 -52.285717) (xy 105.537508 -52.324)
			(xy 105.537004 -52.366348) (xy 105.528953 -52.450662) (xy 105.512924 -52.533828) (xy 105.489063 -52.615095)
			(xy 105.457584 -52.693725) (xy 105.418773 -52.769006) (xy 105.372983 -52.840258) (xy 105.320627 -52.906834)
			(xy 105.262179 -52.968132) (xy 105.198169 -53.023597) (xy 105.129177 -53.072726) (xy 105.055827 -53.115075)
			(xy 104.978784 -53.150259) (xy 104.898745 -53.177961) (xy 104.816436 -53.197929) (xy 104.732601 -53.209982)
			(xy 104.648 -53.214013) (xy 104.563399 -53.209982) (xy 104.479564 -53.197929) (xy 104.397255 -53.177961)
			(xy 104.317216 -53.150259) (xy 104.240173 -53.115075) (xy 104.166823 -53.072726) (xy 104.097831 -53.023597)
			(xy 104.033821 -52.968132) (xy 103.975373 -52.906834) (xy 103.923017 -52.840258) (xy 103.877227 -52.769006)
			(xy 103.838416 -52.693725) (xy 103.806937 -52.615095) (xy 103.783076 -52.533828) (xy 103.767047 -52.450662)
			(xy 103.758996 -52.366348) (xy 103.758492 -52.324) (xy 100.076508 -52.324) (xy 100.076004 -52.366348)
			(xy 100.067953 -52.450662) (xy 100.051924 -52.533828) (xy 100.028063 -52.615095) (xy 99.996584 -52.693725)
			(xy 99.957773 -52.769006) (xy 99.911983 -52.840258) (xy 99.859627 -52.906834) (xy 99.801179 -52.968132)
			(xy 99.737169 -53.023597) (xy 99.668177 -53.072726) (xy 99.594827 -53.115075) (xy 99.517784 -53.150259)
			(xy 99.437745 -53.177961) (xy 99.355436 -53.197929) (xy 99.271601 -53.209982) (xy 99.187 -53.214013)
			(xy 99.102399 -53.209982) (xy 99.018564 -53.197929) (xy 98.936255 -53.177961) (xy 98.856216 -53.150259)
			(xy 98.779173 -53.115075) (xy 98.705823 -53.072726) (xy 98.636831 -53.023597) (xy 98.572821 -52.968132)
			(xy 98.514373 -52.906834) (xy 98.462017 -52.840258) (xy 98.416227 -52.769006) (xy 98.377416 -52.693725)
			(xy 98.345937 -52.615095) (xy 98.322076 -52.533828) (xy 98.306047 -52.450662) (xy 98.297996 -52.366348)
			(xy 98.297492 -52.324) (xy 94.615508 -52.324) (xy 94.615004 -52.366348) (xy 94.606953 -52.450662)
			(xy 94.590924 -52.533828) (xy 94.567063 -52.615095) (xy 94.535584 -52.693725) (xy 94.496773 -52.769006)
			(xy 94.450983 -52.840258) (xy 94.398627 -52.906834) (xy 94.340179 -52.968132) (xy 94.276169 -53.023597)
			(xy 94.207177 -53.072726) (xy 94.133827 -53.115075) (xy 94.056784 -53.150259) (xy 93.976745 -53.177961)
			(xy 93.894436 -53.197929) (xy 93.810601 -53.209982) (xy 93.726 -53.214013) (xy 93.641399 -53.209982)
			(xy 93.557564 -53.197929) (xy 93.475255 -53.177961) (xy 93.395216 -53.150259) (xy 93.318173 -53.115075)
			(xy 93.244823 -53.072726) (xy 93.175831 -53.023597) (xy 93.111821 -52.968132) (xy 93.053373 -52.906834)
			(xy 93.001017 -52.840258) (xy 92.955227 -52.769006) (xy 92.916416 -52.693725) (xy 92.884937 -52.615095)
			(xy 92.861076 -52.533828) (xy 92.845047 -52.450662) (xy 92.836996 -52.366348) (xy 92.836492 -52.324)
			(xy 89.154508 -52.324) (xy 89.154004 -52.366348) (xy 89.145953 -52.450662) (xy 89.129924 -52.533828)
			(xy 89.106063 -52.615095) (xy 89.074584 -52.693725) (xy 89.035773 -52.769006) (xy 88.989983 -52.840258)
			(xy 88.937627 -52.906834) (xy 88.879179 -52.968132) (xy 88.815169 -53.023597) (xy 88.746177 -53.072726)
			(xy 88.672827 -53.115075) (xy 88.595784 -53.150259) (xy 88.515745 -53.177961) (xy 88.433436 -53.197929)
			(xy 88.349601 -53.209982) (xy 88.265 -53.214013) (xy 88.180399 -53.209982) (xy 88.096564 -53.197929)
			(xy 88.014255 -53.177961) (xy 87.934216 -53.150259) (xy 87.857173 -53.115075) (xy 87.783823 -53.072726)
			(xy 87.714831 -53.023597) (xy 87.650821 -52.968132) (xy 87.592373 -52.906834) (xy 87.540017 -52.840258)
			(xy 87.494227 -52.769006) (xy 87.455416 -52.693725) (xy 87.423937 -52.615095) (xy 87.400076 -52.533828)
			(xy 87.384047 -52.450662) (xy 87.375996 -52.366348) (xy 87.375492 -52.324) (xy 83.693508 -52.324)
			(xy 83.693004 -52.366348) (xy 83.684953 -52.450662) (xy 83.668924 -52.533828) (xy 83.645063 -52.615095)
			(xy 83.613584 -52.693725) (xy 83.574773 -52.769006) (xy 83.528983 -52.840258) (xy 83.476627 -52.906834)
			(xy 83.418179 -52.968132) (xy 83.354169 -53.023597) (xy 83.285177 -53.072726) (xy 83.211827 -53.115075)
			(xy 83.134784 -53.150259) (xy 83.054745 -53.177961) (xy 82.972436 -53.197929) (xy 82.888601 -53.209982)
			(xy 82.804 -53.214013) (xy 82.719399 -53.209982) (xy 82.635564 -53.197929) (xy 82.553255 -53.177961)
			(xy 82.473216 -53.150259) (xy 82.396173 -53.115075) (xy 82.322823 -53.072726) (xy 82.253831 -53.023597)
			(xy 82.189821 -52.968132) (xy 82.131373 -52.906834) (xy 82.079017 -52.840258) (xy 82.033227 -52.769006)
			(xy 81.994416 -52.693725) (xy 81.962937 -52.615095) (xy 81.939076 -52.533828) (xy 81.923047 -52.450662)
			(xy 81.914996 -52.366348) (xy 81.914492 -52.324) (xy 78.232508 -52.324) (xy 78.232004 -52.366348)
			(xy 78.223953 -52.450662) (xy 78.207924 -52.533828) (xy 78.184063 -52.615095) (xy 78.152584 -52.693725)
			(xy 78.113773 -52.769006) (xy 78.067983 -52.840258) (xy 78.015627 -52.906834) (xy 77.957179 -52.968132)
			(xy 77.893169 -53.023597) (xy 77.824177 -53.072726) (xy 77.750827 -53.115075) (xy 77.673784 -53.150259)
			(xy 77.593745 -53.177961) (xy 77.511436 -53.197929) (xy 77.427601 -53.209982) (xy 77.343 -53.214013)
			(xy 77.258399 -53.209982) (xy 77.174564 -53.197929) (xy 77.092255 -53.177961) (xy 77.012216 -53.150259)
			(xy 76.935173 -53.115075) (xy 76.861823 -53.072726) (xy 76.792831 -53.023597) (xy 76.728821 -52.968132)
			(xy 76.670373 -52.906834) (xy 76.618017 -52.840258) (xy 76.572227 -52.769006) (xy 76.533416 -52.693725)
			(xy 76.501937 -52.615095) (xy 76.478076 -52.533828) (xy 76.462047 -52.450662) (xy 76.453996 -52.366348)
			(xy 76.453492 -52.324) (xy 72.771508 -52.324) (xy 72.771004 -52.366348) (xy 72.762953 -52.450662)
			(xy 72.746924 -52.533828) (xy 72.723063 -52.615095) (xy 72.691584 -52.693725) (xy 72.652773 -52.769006)
			(xy 72.606983 -52.840258) (xy 72.554627 -52.906834) (xy 72.496179 -52.968132) (xy 72.432169 -53.023597)
			(xy 72.363177 -53.072726) (xy 72.289827 -53.115075) (xy 72.212784 -53.150259) (xy 72.132745 -53.177961)
			(xy 72.050436 -53.197929) (xy 71.966601 -53.209982) (xy 71.882 -53.214013) (xy 71.797399 -53.209982)
			(xy 71.713564 -53.197929) (xy 71.631255 -53.177961) (xy 71.551216 -53.150259) (xy 71.474173 -53.115075)
			(xy 71.400823 -53.072726) (xy 71.331831 -53.023597) (xy 71.267821 -52.968132) (xy 71.209373 -52.906834)
			(xy 71.157017 -52.840258) (xy 71.111227 -52.769006) (xy 71.072416 -52.693725) (xy 71.040937 -52.615095)
			(xy 71.017076 -52.533828) (xy 71.001047 -52.450662) (xy 70.992996 -52.366348) (xy 70.992492 -52.324)
			(xy 51.706282 -52.324) (xy 51.700727 -52.350268) (xy 51.672187 -52.438562) (xy 51.653948 -52.481226)
			(xy 51.65014 -52.491168) (xy 51.65014 -52.512432) (xy 51.653948 -52.522374) (xy 51.672195 -52.565035)
			(xy 51.700738 -52.653328) (xy 51.71993 -52.744113) (xy 51.729563 -52.836404) (xy 51.730148 -52.8828)
			(xy 51.729633 -52.923901) (xy 51.722049 -53.005753) (xy 51.706945 -53.086556) (xy 51.684449 -53.165621)
			(xy 51.654755 -53.242273) (xy 51.618115 -53.315858) (xy 51.574842 -53.385749) (xy 51.525305 -53.451349)
			(xy 51.469927 -53.512099) (xy 51.40918 -53.56748) (xy 51.343582 -53.61702) (xy 51.273693 -53.660296)
			(xy 51.20011 -53.696939) (xy 51.123459 -53.726637) (xy 51.044395 -53.749136) (xy 50.963593 -53.764243)
			(xy 50.881741 -53.771832) (xy 50.84064 -53.772308) (xy 50.794245 -53.771711) (xy 50.701957 -53.76207)
			(xy 50.611173 -53.742878) (xy 50.522879 -53.714344) (xy 50.480214 -53.696108) (xy 50.470272 -53.692302)
			(xy 50.449008 -53.692302) (xy 50.439066 -53.696108) (xy 50.396398 -53.71434) (xy 50.308108 -53.742887)
			(xy 50.217325 -53.762084) (xy 50.125036 -53.771721) (xy 50.07864 -53.772308) (xy 50.032245 -53.771711)
			(xy 49.939957 -53.76207) (xy 49.849173 -53.742878) (xy 49.760879 -53.714344) (xy 49.718214 -53.696108)
			(xy 49.708272 -53.692302) (xy 49.687008 -53.692302) (xy 49.677066 -53.696108) (xy 49.634398 -53.71434)
			(xy 49.546108 -53.742887) (xy 49.455325 -53.762084) (xy 49.363036 -53.771721) (xy 49.31664 -53.772308)
			(xy 49.275537 -53.77181) (xy 49.193683 -53.764228) (xy 49.112877 -53.749126) (xy 49.033809 -53.726633)
			(xy 48.957154 -53.69694) (xy 48.883566 -53.6603) (xy 48.813673 -53.617027) (xy 48.748071 -53.567489)
			(xy 48.687319 -53.512109) (xy 48.631937 -53.45136) (xy 48.582396 -53.38576) (xy 48.53912 -53.315869)
			(xy 48.502477 -53.242282) (xy 48.47278 -53.165629) (xy 48.450283 -53.086562) (xy 48.435177 -53.005757)
			(xy 48.427592 -52.923902) (xy 48.427132 -52.8828) (xy 47.945068 -52.8828) (xy 47.945548 -52.9209)
			(xy 47.945044 -52.963248) (xy 47.936993 -53.047562) (xy 47.920964 -53.130728) (xy 47.897103 -53.211995)
			(xy 47.865624 -53.290625) (xy 47.826813 -53.365906) (xy 47.781023 -53.437158) (xy 47.728667 -53.503734)
			(xy 47.670219 -53.565032) (xy 47.606209 -53.620497) (xy 47.537217 -53.669626) (xy 47.463867 -53.711975)
			(xy 47.386824 -53.747159) (xy 47.306785 -53.774861) (xy 47.224476 -53.794829) (xy 47.140641 -53.806882)
			(xy 47.05604 -53.810913) (xy 46.971439 -53.806882) (xy 46.887604 -53.794829) (xy 46.805295 -53.774861)
			(xy 46.725256 -53.747159) (xy 46.648213 -53.711975) (xy 46.574863 -53.669626) (xy 46.505871 -53.620497)
			(xy 46.441861 -53.565032) (xy 46.383413 -53.503734) (xy 46.331057 -53.437158) (xy 46.285267 -53.365906)
			(xy 46.246456 -53.290625) (xy 46.214977 -53.211995) (xy 46.191116 -53.130728) (xy 46.175087 -53.047562)
			(xy 46.167036 -52.963248) (xy 46.166532 -52.9209) (xy 44.986526 -52.9209) (xy 44.977819 -52.930032)
			(xy 44.913809 -52.985497) (xy 44.844817 -53.034626) (xy 44.771467 -53.076975) (xy 44.694424 -53.112159)
			(xy 44.614385 -53.139861) (xy 44.532076 -53.159829) (xy 44.448241 -53.171882) (xy 44.36364 -53.175913)
			(xy 44.279039 -53.171882) (xy 44.195204 -53.159829) (xy 44.112895 -53.139861) (xy 44.032856 -53.112159)
			(xy 43.955813 -53.076975) (xy 43.882463 -53.034626) (xy 43.813471 -52.985497) (xy 43.749461 -52.930032)
			(xy 43.691013 -52.868734) (xy 43.638657 -52.802158) (xy 43.592867 -52.730906) (xy 43.554056 -52.655625)
			(xy 43.522577 -52.576995) (xy 43.498716 -52.495728) (xy 43.482687 -52.412562) (xy 43.474636 -52.328248)
			(xy 43.474132 -52.2859) (xy 0.509016 -52.2859) (xy 0.509016 -54.399942) (xy 3.446023 -54.399942)
			(xy 3.450044 -54.28608) (xy 3.462086 -54.172786) (xy 3.482091 -54.060624) (xy 3.509957 -53.950152)
			(xy 3.545546 -53.84192) (xy 3.588681 -53.736469) (xy 3.639147 -53.634323) (xy 3.696693 -53.535992)
			(xy 3.761032 -53.441964) (xy 3.831843 -53.352709) (xy 3.908773 -53.268672) (xy 3.99144 -53.19027)
			(xy 4.079431 -53.117895) (xy 4.172308 -53.051907) (xy 4.269609 -52.992635) (xy 4.370848 -52.940374)
			(xy 4.475522 -52.895384) (xy 4.583108 -52.85789) (xy 4.693071 -52.828079) (xy 4.804864 -52.806098)
			(xy 4.917928 -52.792058) (xy 5.0317 -52.786028) (xy 5.145615 -52.788039) (xy 5.259104 -52.79808)
			(xy 5.371603 -52.816102) (xy 5.482549 -52.842014) (xy 5.591392 -52.875688) (xy 5.697588 -52.916955)
			(xy 5.800608 -52.965611) (xy 5.89994 -53.021412) (xy 5.995089 -53.084081) (xy 6.085579 -53.153306)
			(xy 6.170961 -53.228741) (xy 6.25081 -53.310012) (xy 6.324727 -53.396712) (xy 6.392343 -53.48841)
			(xy 6.453324 -53.584649) (xy 6.507363 -53.684951) (xy 6.554193 -53.788814) (xy 6.59358 -53.895722)
			(xy 6.625327 -54.005142) (xy 6.649277 -54.116528) (xy 6.665311 -54.229327) (xy 6.673347 -54.342976)
			(xy 6.67385 -54.399942) (xy 6.673347 -54.456908) (xy 6.665311 -54.570557) (xy 6.649277 -54.683356)
			(xy 6.625327 -54.794742) (xy 6.59358 -54.904162) (xy 6.554193 -55.01107) (xy 6.507363 -55.114933)
			(xy 6.453324 -55.215235) (xy 6.392343 -55.311474) (xy 6.324727 -55.403172) (xy 6.25081 -55.489872)
			(xy 6.170961 -55.571143) (xy 6.090758 -55.642002) (xy 37.371528 -55.642002) (xy 37.372032 -55.599654)
			(xy 37.380083 -55.51534) (xy 37.396112 -55.432174) (xy 37.419973 -55.350907) (xy 37.451452 -55.272277)
			(xy 37.490263 -55.196996) (xy 37.536053 -55.125744) (xy 37.588409 -55.059168) (xy 37.646857 -54.99787)
			(xy 37.710867 -54.942405) (xy 37.779859 -54.893276) (xy 37.853209 -54.850927) (xy 37.930252 -54.815743)
			(xy 38.010291 -54.788041) (xy 38.0926 -54.768073) (xy 38.176435 -54.75602) (xy 38.261036 -54.75199)
			(xy 38.345637 -54.75602) (xy 38.429472 -54.768073) (xy 38.511781 -54.788041) (xy 38.59182 -54.815743)
			(xy 38.668863 -54.850927) (xy 38.742213 -54.893276) (xy 38.811205 -54.942405) (xy 38.875215 -54.99787)
			(xy 38.933663 -55.059168) (xy 38.986019 -55.125744) (xy 39.031809 -55.196996) (xy 39.07062 -55.272277)
			(xy 39.102099 -55.350907) (xy 39.12596 -55.432174) (xy 39.141989 -55.51534) (xy 39.15004 -55.599654)
			(xy 39.150544 -55.642002) (xy 39.149888 -55.692156) (xy 39.13869 -55.791837) (xy 39.128192 -55.840884)
			(xy 39.126403 -55.851401) (xy 39.130519 -55.872305) (xy 39.142729 -55.889765) (xy 39.15156 -55.895748)
			(xy 39.188993 -55.918893) (xy 39.259542 -55.971521) (xy 39.324556 -56.030851) (xy 39.383399 -56.096306)
			(xy 39.409878 -56.13146) (xy 39.416788 -56.140033) (xy 39.436031 -56.150694) (xy 39.446962 -56.152034)
			(xy 39.488331 -56.155768) (xy 39.570195 -56.169853) (xy 39.65039 -56.191507) (xy 39.728218 -56.220543)
			(xy 39.802999 -56.256707) (xy 39.874084 -56.299685) (xy 39.940853 -56.349102) (xy 40.002725 -56.404528)
			(xy 40.05916 -56.465481) (xy 40.109668 -56.531428) (xy 40.153809 -56.601797) (xy 40.191198 -56.675974)
			(xy 40.221509 -56.753314) (xy 40.244479 -56.833142) (xy 40.259907 -56.914764) (xy 40.267659 -56.997468)
			(xy 40.268144 -57.039002) (xy 40.267664 -57.082792) (xy 40.259099 -57.169952) (xy 40.242002 -57.255846)
			(xy 40.216539 -57.339643) (xy 40.182958 -57.420528) (xy 40.162734 -57.459372) (xy 40.157312 -57.470837)
			(xy 40.157313 -57.496166) (xy 40.162734 -57.507632) (xy 40.182954 -57.546475) (xy 40.216507 -57.627369)
			(xy 40.241955 -57.711167) (xy 40.259051 -57.797058) (xy 40.267631 -57.884214) (xy 40.268144 -57.928002)
			(xy 40.267664 -57.971792) (xy 40.259099 -58.058952) (xy 40.242002 -58.144846) (xy 40.216539 -58.228643)
			(xy 40.182958 -58.309528) (xy 40.162734 -58.348372) (xy 40.157312 -58.359837) (xy 40.157313 -58.385166)
			(xy 40.162734 -58.396632) (xy 40.182954 -58.435475) (xy 40.216507 -58.516369) (xy 40.241955 -58.600167)
			(xy 40.242899 -58.604912) (xy 40.474392 -58.604912) (xy 40.474903 -58.560519) (xy 40.483698 -58.472169)
			(xy 40.50125 -58.385135) (xy 40.527387 -58.300283) (xy 40.561847 -58.218457) (xy 40.582596 -58.179208)
			(xy 40.586434 -58.171656) (xy 40.589251 -58.154957) (xy 40.586406 -58.138263) (xy 40.582596 -58.130694)
			(xy 40.561847 -58.091445) (xy 40.527387 -58.009619) (xy 40.501251 -57.924767) (xy 40.483698 -57.837733)
			(xy 40.474903 -57.749383) (xy 40.474392 -57.70499) (xy 40.474894 -57.660596) (xy 40.48369 -57.572247)
			(xy 40.501245 -57.485213) (xy 40.527384 -57.400361) (xy 40.561846 -57.318535) (xy 40.582596 -57.279286)
			(xy 40.586376 -57.271708) (xy 40.589213 -57.255026) (xy 40.586393 -57.23834) (xy 40.582596 -57.230772)
			(xy 40.561839 -57.191527) (xy 40.52738 -57.1097) (xy 40.501246 -57.024847) (xy 40.483694 -56.937812)
			(xy 40.474902 -56.849462) (xy 40.474392 -56.805068) (xy 40.474941 -56.760669) (xy 40.483788 -56.672313)
			(xy 40.501391 -56.585278) (xy 40.527575 -56.500428) (xy 40.562079 -56.418608) (xy 40.58285 -56.379364)
			(xy 40.586655 -56.371754) (xy 40.589465 -56.354982) (xy 40.586644 -56.338212) (xy 40.58285 -56.330596)
			(xy 40.56208 -56.291351) (xy 40.527568 -56.209533) (xy 40.501379 -56.124684) (xy 40.483774 -56.037648)
			(xy 40.474928 -55.949291) (xy 40.474392 -55.904892) (xy 40.474795 -55.863896) (xy 40.482332 -55.782251)
			(xy 40.497352 -55.701646) (xy 40.519727 -55.622766) (xy 40.549266 -55.546279) (xy 40.585719 -55.472836)
			(xy 40.628776 -55.40306) (xy 40.678073 -55.337542) (xy 40.73319 -55.276839) (xy 40.79366 -55.221467)
			(xy 40.85897 -55.171895) (xy 40.928564 -55.128544) (xy 41.001853 -55.091782) (xy 41.078215 -55.061921)
			(xy 41.157 -55.039215) (xy 41.237541 -55.023856) (xy 41.278302 -55.019448) (xy 41.294304 -55.017924)
			(xy 41.318434 -54.997604) (xy 41.351708 -54.874922) (xy 41.341294 -54.845204) (xy 41.328086 -54.835806)
			(xy 41.294308 -54.810762) (xy 41.231103 -54.755296) (xy 41.173413 -54.694112) (xy 41.121754 -54.627759)
			(xy 41.076587 -54.556826) (xy 41.038314 -54.481948) (xy 41.007278 -54.403793) (xy 40.983755 -54.323058)
			(xy 40.967956 -54.240463) (xy 40.960021 -54.156746) (xy 40.959532 -54.1147) (xy 40.95995 -54.074933)
			(xy 40.96699 -53.995711) (xy 40.981077 -53.917434) (xy 41.002099 -53.840728) (xy 41.029886 -53.766206)
			(xy 41.046654 -53.730144) (xy 41.050985 -53.719643) (xy 41.050985 -53.696957) (xy 41.046654 -53.686456)
			(xy 41.029913 -53.650383) (xy 41.002132 -53.57586) (xy 40.981109 -53.499157) (xy 40.967012 -53.420884)
			(xy 40.959954 -53.341666) (xy 40.959532 -53.3019) (xy 40.959952 -53.260796) (xy 40.967538 -53.178938)
			(xy 40.982644 -53.098129) (xy 41.005142 -53.019059) (xy 41.03484 -52.942402) (xy 41.071485 -52.868812)
			(xy 41.114763 -52.798917) (xy 41.164306 -52.733314) (xy 41.219691 -52.672563) (xy 41.280445 -52.61718)
			(xy 41.34605 -52.56764) (xy 41.415947 -52.524365) (xy 41.489538 -52.487724) (xy 41.566197 -52.458029)
			(xy 41.645268 -52.435535) (xy 41.726077 -52.420432) (xy 41.807936 -52.41285) (xy 41.84904 -52.412392)
			(xy 41.893805 -52.412911) (xy 41.982887 -52.421844) (xy 42.07062 -52.439686) (xy 42.156115 -52.466255)
			(xy 42.197528 -52.483258) (xy 42.207119 -52.486823) (xy 42.227561 -52.486823) (xy 42.237152 -52.483258)
			(xy 42.278569 -52.466265) (xy 42.364066 -52.439708) (xy 42.451797 -52.421867) (xy 42.540876 -52.412923)
			(xy 42.58564 -52.412392) (xy 42.626743 -52.412828) (xy 42.708598 -52.420417) (xy 42.789404 -52.435526)
			(xy 42.868472 -52.458025) (xy 42.945126 -52.487724) (xy 43.018713 -52.524369) (xy 43.088605 -52.567647)
			(xy 43.154206 -52.617189) (xy 43.214955 -52.672573) (xy 43.270336 -52.733325) (xy 43.319875 -52.798928)
			(xy 43.36315 -52.868822) (xy 43.399792 -52.942411) (xy 43.429487 -53.019066) (xy 43.451984 -53.098134)
			(xy 43.467089 -53.178941) (xy 43.474673 -53.260797) (xy 43.475148 -53.3019) (xy 43.474732 -53.341667)
			(xy 43.467691 -53.42089) (xy 43.453604 -53.499166) (xy 43.432582 -53.575872) (xy 43.404794 -53.650394)
			(xy 43.388026 -53.686456) (xy 43.383691 -53.696957) (xy 43.383691 -53.719643) (xy 43.388026 -53.730144)
			(xy 43.404773 -53.766215) (xy 43.432551 -53.840738) (xy 43.453572 -53.917442) (xy 43.467668 -53.995715)
			(xy 43.474726 -54.074934) (xy 43.475148 -54.1147) (xy 43.474633 -54.155801) (xy 43.467049 -54.237653)
			(xy 43.451945 -54.318456) (xy 43.429449 -54.397521) (xy 43.399755 -54.474173) (xy 43.363115 -54.547758)
			(xy 43.319842 -54.617649) (xy 43.270305 -54.683249) (xy 43.214927 -54.743999) (xy 43.15418 -54.79938)
			(xy 43.088582 -54.84892) (xy 43.018693 -54.892196) (xy 42.94511 -54.928839) (xy 42.868459 -54.958537)
			(xy 42.789395 -54.981036) (xy 42.708593 -54.996143) (xy 42.626741 -55.003732) (xy 42.58564 -55.004208)
			(xy 42.540875 -55.003695) (xy 42.451793 -54.994761) (xy 42.36406 -54.976917) (xy 42.278565 -54.950346)
			(xy 42.237152 -54.933342) (xy 42.227561 -54.929777) (xy 42.207119 -54.929777) (xy 42.197528 -54.933342)
			(xy 42.182542 -54.939438) (xy 42.17275 -54.944035) (xy 42.157834 -54.959663) (xy 42.150643 -54.980036)
			(xy 42.152446 -55.001564) (xy 42.162924 -55.020457) (xy 42.180232 -55.033387) (xy 42.19067 -55.036212)
			(xy 42.232544 -55.046034) (xy 42.314349 -55.072611) (xy 42.393207 -55.106959) (xy 42.468382 -55.148756)
			(xy 42.539173 -55.197614) (xy 42.604918 -55.253075) (xy 42.665004 -55.314623) (xy 42.718869 -55.381682)
			(xy 42.766012 -55.453626) (xy 42.805991 -55.529784) (xy 42.838434 -55.609444) (xy 42.863037 -55.691864)
			(xy 42.879572 -55.776274) (xy 42.887883 -55.861885) (xy 42.888408 -55.904892) (xy 42.887885 -55.949292)
			(xy 42.879032 -56.037648) (xy 42.861423 -56.124684) (xy 42.835233 -56.209533) (xy 42.800723 -56.291352)
			(xy 42.77995 -56.330596) (xy 42.776174 -56.338218) (xy 42.773354 -56.354982) (xy 42.776163 -56.371748)
			(xy 42.77995 -56.379364) (xy 42.800704 -56.418617) (xy 42.835219 -56.500433) (xy 42.861411 -56.585279)
			(xy 42.87902 -56.672314) (xy 42.88787 -56.760669) (xy 42.888408 -56.805068) (xy 42.887888 -56.849461)
			(xy 42.879096 -56.93781) (xy 42.861545 -57.024844) (xy 42.83541 -57.109696) (xy 42.800952 -57.191523)
			(xy 42.780204 -57.230772) (xy 42.774742 -57.242292) (xy 42.774755 -57.267758) (xy 42.780204 -57.279286)
			(xy 42.800945 -57.318539) (xy 42.835407 -57.400364) (xy 42.861545 -57.485215) (xy 42.8791 -57.572248)
			(xy 42.887896 -57.660597) (xy 42.888408 -57.70499) (xy 42.887898 -57.749383) (xy 42.879103 -57.837733)
			(xy 42.86155 -57.924767) (xy 42.835413 -58.009619) (xy 42.800953 -58.091445) (xy 42.780204 -58.130694)
			(xy 42.774796 -58.142234) (xy 42.774774 -58.167681) (xy 42.780204 -58.179208) (xy 42.800954 -58.218457)
			(xy 42.835413 -58.300283) (xy 42.86155 -58.385135) (xy 42.879103 -58.472169) (xy 42.887897 -58.560519)
			(xy 42.888408 -58.604912) (xy 42.887945 -58.646015) (xy 42.880359 -58.727869) (xy 42.865253 -58.808675)
			(xy 42.842755 -58.887742) (xy 42.813058 -58.964396) (xy 42.776416 -59.037983) (xy 42.733139 -59.107875)
			(xy 42.683599 -59.173476) (xy 42.628217 -59.234226) (xy 42.567466 -59.289607) (xy 42.501865 -59.339146)
			(xy 42.431972 -59.382421) (xy 42.358385 -59.419063) (xy 42.28173 -59.448759) (xy 42.202663 -59.471255)
			(xy 42.121857 -59.48636) (xy 42.040003 -59.493945) (xy 41.9989 -59.49442) (xy 41.960616 -59.494032)
			(xy 41.884327 -59.487493) (xy 41.808885 -59.474411) (xy 41.734848 -59.454885) (xy 41.698672 -59.44235)
			(xy 41.690235 -59.439699) (xy 41.672565 -59.439699) (xy 41.664128 -59.44235) (xy 41.62795 -59.454876)
			(xy 41.55391 -59.474383) (xy 41.478469 -59.487463) (xy 41.402183 -59.494018) (xy 41.3639 -59.49442)
			(xy 41.322798 -59.493933) (xy 41.240944 -59.486349) (xy 41.16014 -59.471244) (xy 41.081073 -59.448748)
			(xy 41.00442 -59.419052) (xy 40.930834 -59.382411) (xy 40.860942 -59.339136) (xy 40.795341 -59.289598)
			(xy 40.734591 -59.234217) (xy 40.67921 -59.173468) (xy 40.62967 -59.107868) (xy 40.586395 -59.037977)
			(xy 40.549753 -58.964391) (xy 40.520056 -58.887738) (xy 40.497559 -58.808672) (xy 40.482453 -58.727868)
			(xy 40.474867 -58.646014) (xy 40.474392 -58.604912) (xy 40.242899 -58.604912) (xy 40.259051 -58.686058)
			(xy 40.267631 -58.773214) (xy 40.268144 -58.817002) (xy 40.267689 -58.858109) (xy 40.260105 -58.939973)
			(xy 40.245 -59.020789) (xy 40.222505 -59.099866) (xy 40.19281 -59.17653) (xy 40.156169 -59.250129)
			(xy 40.112895 -59.320033) (xy 40.063357 -59.385647) (xy 40.007977 -59.446411) (xy 39.947227 -59.501807)
			(xy 39.881626 -59.551363) (xy 39.811733 -59.594655) (xy 39.738145 -59.631315) (xy 39.661488 -59.66103)
			(xy 39.582416 -59.683546) (xy 39.501605 -59.698672) (xy 39.419743 -59.706279) (xy 39.378636 -59.706764)
			(xy 39.336929 -59.706247) (xy 39.253882 -59.698432) (xy 39.17193 -59.682877) (xy 39.091796 -59.659718)
			(xy 39.014181 -59.629158) (xy 38.939768 -59.591467) (xy 38.86921 -59.546974) (xy 38.803128 -59.496072)
			(xy 38.742101 -59.439206) (xy 38.686666 -59.376878) (xy 38.661594 -59.343544) (xy 38.654652 -59.335001)
			(xy 38.635433 -59.324324) (xy 38.62451 -59.32297) (xy 38.583139 -59.319256) (xy 38.501275 -59.305169)
			(xy 38.42108 -59.283512) (xy 38.343252 -59.254474) (xy 38.268471 -59.218308) (xy 38.197386 -59.175329)
			(xy 38.130618 -59.12591) (xy 38.068746 -59.070482) (xy 38.012311 -59.009529) (xy 37.961804 -58.94358)
			(xy 37.917663 -58.873211) (xy 37.880275 -58.799033) (xy 37.849964 -58.721692) (xy 37.826994 -58.641864)
			(xy 37.811565 -58.560241) (xy 37.803813 -58.477536) (xy 37.803328 -58.436002) (xy 37.803813 -58.392212)
			(xy 37.812377 -58.305053) (xy 37.829473 -58.219158) (xy 37.854935 -58.135362) (xy 37.888515 -58.054476)
			(xy 37.908738 -58.015632) (xy 37.914152 -58.004165) (xy 37.914153 -57.978839) (xy 37.908738 -57.967372)
			(xy 37.888517 -57.928529) (xy 37.854964 -57.847635) (xy 37.829517 -57.763837) (xy 37.812421 -57.677946)
			(xy 37.803841 -57.59079) (xy 37.803328 -57.547002) (xy 37.803813 -57.503212) (xy 37.812377 -57.416053)
			(xy 37.829473 -57.330158) (xy 37.854935 -57.246362) (xy 37.888515 -57.165476) (xy 37.908738 -57.126632)
			(xy 37.914152 -57.115165) (xy 37.914153 -57.089839) (xy 37.908738 -57.078372) (xy 37.888517 -57.039529)
			(xy 37.854964 -56.958635) (xy 37.829517 -56.874837) (xy 37.812421 -56.788946) (xy 37.803841 -56.70179)
			(xy 37.803328 -56.658002) (xy 37.803969 -56.607847) (xy 37.815177 -56.508167) (xy 37.82568 -56.45912)
			(xy 37.827479 -56.448604) (xy 37.823362 -56.427696) (xy 37.811147 -56.410236) (xy 37.802312 -56.404256)
			(xy 37.766912 -56.382369) (xy 37.699929 -56.332962) (xy 37.637853 -56.277515) (xy 37.581226 -56.216513)
			(xy 37.530544 -56.15049) (xy 37.48625 -56.080021) (xy 37.44873 -56.005724) (xy 37.418313 -55.928248)
			(xy 37.395264 -55.84827) (xy 37.379785 -55.766488) (xy 37.372012 -55.683619) (xy 37.371528 -55.642002)
			(xy 6.090758 -55.642002) (xy 6.085579 -55.646578) (xy 5.995089 -55.715803) (xy 5.89994 -55.778472)
			(xy 5.800608 -55.834273) (xy 5.697588 -55.882929) (xy 5.591392 -55.924196) (xy 5.482549 -55.95787)
			(xy 5.371603 -55.983782) (xy 5.259104 -56.001804) (xy 5.145615 -56.011845) (xy 5.0317 -56.013856)
			(xy 4.917928 -56.007826) (xy 4.804864 -55.993786) (xy 4.693071 -55.971805) (xy 4.583108 -55.941994)
			(xy 4.475522 -55.9045) (xy 4.370848 -55.85951) (xy 4.269609 -55.807249) (xy 4.172308 -55.747977)
			(xy 4.079431 -55.681989) (xy 3.99144 -55.609614) (xy 3.908773 -55.531212) (xy 3.831843 -55.447175)
			(xy 3.761032 -55.35792) (xy 3.696693 -55.263892) (xy 3.639147 -55.165561) (xy 3.588681 -55.063415)
			(xy 3.545546 -54.957964) (xy 3.509957 -54.849732) (xy 3.482091 -54.73926) (xy 3.462086 -54.627098)
			(xy 3.450044 -54.513804) (xy 3.446023 -54.399942) (xy 0.509016 -54.399942) (xy 0.509016 -60.96) (xy 66.673737 -60.96)
			(xy 66.677742 -60.854251) (xy 66.689732 -60.749108) (xy 66.709641 -60.645173) (xy 66.737352 -60.543041)
			(xy 66.772709 -60.443297) (xy 66.815507 -60.346513) (xy 66.865503 -60.253243) (xy 66.92241 -60.164022)
			(xy 66.985901 -60.079359) (xy 67.055613 -59.999741) (xy 67.131147 -59.925623) (xy 67.21207 -59.85743)
			(xy 67.297919 -59.795552) (xy 67.388202 -59.740345) (xy 67.482401 -59.692123) (xy 67.579978 -59.651163)
			(xy 67.680373 -59.617701) (xy 67.783011 -59.591927) (xy 67.887304 -59.573989) (xy 67.992655 -59.56399)
			(xy 68.098461 -59.561987) (xy 68.204115 -59.567992) (xy 68.309012 -59.581971) (xy 68.412552 -59.603842)
			(xy 68.514141 -59.633482) (xy 68.613198 -59.67072) (xy 68.709155 -59.715342) (xy 68.801462 -59.767094)
			(xy 68.889591 -59.825679) (xy 68.973037 -59.890761) (xy 69.051321 -59.961967) (xy 69.123996 -60.03889)
			(xy 69.190646 -60.12109) (xy 69.250888 -60.208094) (xy 69.304377 -60.299405) (xy 69.350808 -60.3945)
			(xy 69.389913 -60.492834) (xy 69.42147 -60.593845) (xy 69.445297 -60.696952) (xy 69.461258 -60.801566)
			(xy 69.469262 -60.907088) (xy 69.469762 -60.96) (xy 77.976737 -60.96) (xy 77.980742 -60.854251) (xy 77.992732 -60.749108)
			(xy 78.012641 -60.645173) (xy 78.040352 -60.543041) (xy 78.075709 -60.443297) (xy 78.118507 -60.346513)
			(xy 78.168503 -60.253243) (xy 78.22541 -60.164022) (xy 78.288901 -60.079359) (xy 78.358613 -59.999741)
			(xy 78.434147 -59.925623) (xy 78.51507 -59.85743) (xy 78.600919 -59.795552) (xy 78.691202 -59.740345)
			(xy 78.785401 -59.692123) (xy 78.882978 -59.651163) (xy 78.983373 -59.617701) (xy 79.086011 -59.591927)
			(xy 79.190304 -59.573989) (xy 79.295655 -59.56399) (xy 79.401461 -59.561987) (xy 79.507115 -59.567992)
			(xy 79.612012 -59.581971) (xy 79.715552 -59.603842) (xy 79.817141 -59.633482) (xy 79.916198 -59.67072)
			(xy 80.012155 -59.715342) (xy 80.104462 -59.767094) (xy 80.192591 -59.825679) (xy 80.276037 -59.890761)
			(xy 80.354321 -59.961967) (xy 80.426996 -60.03889) (xy 80.493646 -60.12109) (xy 80.553888 -60.208094)
			(xy 80.607377 -60.299405) (xy 80.653808 -60.3945) (xy 80.692913 -60.492834) (xy 80.72447 -60.593845)
			(xy 80.748297 -60.696952) (xy 80.764258 -60.801566) (xy 80.772262 -60.907088) (xy 80.772762 -60.96)
			(xy 89.279737 -60.96) (xy 89.283742 -60.854251) (xy 89.295732 -60.749108) (xy 89.315641 -60.645173)
			(xy 89.343352 -60.543041) (xy 89.378709 -60.443297) (xy 89.421507 -60.346513) (xy 89.471503 -60.253243)
			(xy 89.52841 -60.164022) (xy 89.591901 -60.079359) (xy 89.661613 -59.999741) (xy 89.737147 -59.925623)
			(xy 89.81807 -59.85743) (xy 89.903919 -59.795552) (xy 89.994202 -59.740345) (xy 90.088401 -59.692123)
			(xy 90.185978 -59.651163) (xy 90.286373 -59.617701) (xy 90.389011 -59.591927) (xy 90.493304 -59.573989)
			(xy 90.598655 -59.56399) (xy 90.704461 -59.561987) (xy 90.810115 -59.567992) (xy 90.915012 -59.581971)
			(xy 91.018552 -59.603842) (xy 91.120141 -59.633482) (xy 91.219198 -59.67072) (xy 91.315155 -59.715342)
			(xy 91.407462 -59.767094) (xy 91.495591 -59.825679) (xy 91.579037 -59.890761) (xy 91.657321 -59.961967)
			(xy 91.729996 -60.03889) (xy 91.796646 -60.12109) (xy 91.856888 -60.208094) (xy 91.910377 -60.299405)
			(xy 91.956808 -60.3945) (xy 91.995913 -60.492834) (xy 92.02747 -60.593845) (xy 92.051297 -60.696952)
			(xy 92.067258 -60.801566) (xy 92.075262 -60.907088) (xy 92.075762 -60.96) (xy 107.440737 -60.96)
			(xy 107.444742 -60.854251) (xy 107.456732 -60.749108) (xy 107.476641 -60.645173) (xy 107.504352 -60.543041)
			(xy 107.539709 -60.443297) (xy 107.582507 -60.346513) (xy 107.632503 -60.253243) (xy 107.68941 -60.164022)
			(xy 107.752901 -60.079359) (xy 107.822613 -59.999741) (xy 107.898147 -59.925623) (xy 107.97907 -59.85743)
			(xy 108.064919 -59.795552) (xy 108.155202 -59.740345) (xy 108.249401 -59.692123) (xy 108.346978 -59.651163)
			(xy 108.447373 -59.617701) (xy 108.550011 -59.591927) (xy 108.654304 -59.573989) (xy 108.759655 -59.56399)
			(xy 108.865461 -59.561987) (xy 108.971115 -59.567992) (xy 109.076012 -59.581971) (xy 109.179552 -59.603842)
			(xy 109.281141 -59.633482) (xy 109.380198 -59.67072) (xy 109.476155 -59.715342) (xy 109.568462 -59.767094)
			(xy 109.656591 -59.825679) (xy 109.740037 -59.890761) (xy 109.818321 -59.961967) (xy 109.890996 -60.03889)
			(xy 109.957646 -60.12109) (xy 110.017888 -60.208094) (xy 110.071377 -60.299405) (xy 110.117808 -60.3945)
			(xy 110.156913 -60.492834) (xy 110.18847 -60.593845) (xy 110.212297 -60.696952) (xy 110.228258 -60.801566)
			(xy 110.236262 -60.907088) (xy 110.236762 -60.96) (xy 118.616737 -60.96) (xy 118.620742 -60.854251)
			(xy 118.632732 -60.749108) (xy 118.652641 -60.645173) (xy 118.680352 -60.543041) (xy 118.715709 -60.443297)
			(xy 118.758507 -60.346513) (xy 118.808503 -60.253243) (xy 118.86541 -60.164022) (xy 118.928901 -60.079359)
			(xy 118.998613 -59.999741) (xy 119.074147 -59.925623) (xy 119.15507 -59.85743) (xy 119.240919 -59.795552)
			(xy 119.331202 -59.740345) (xy 119.425401 -59.692123) (xy 119.522978 -59.651163) (xy 119.623373 -59.617701)
			(xy 119.726011 -59.591927) (xy 119.830304 -59.573989) (xy 119.935655 -59.56399) (xy 120.041461 -59.561987)
			(xy 120.147115 -59.567992) (xy 120.252012 -59.581971) (xy 120.355552 -59.603842) (xy 120.457141 -59.633482)
			(xy 120.556198 -59.67072) (xy 120.652155 -59.715342) (xy 120.744462 -59.767094) (xy 120.832591 -59.825679)
			(xy 120.916037 -59.890761) (xy 120.994321 -59.961967) (xy 121.066996 -60.03889) (xy 121.133646 -60.12109)
			(xy 121.193888 -60.208094) (xy 121.247377 -60.299405) (xy 121.293808 -60.3945) (xy 121.332913 -60.492834)
			(xy 121.36447 -60.593845) (xy 121.388297 -60.696952) (xy 121.404258 -60.801566) (xy 121.412262 -60.907088)
			(xy 121.412762 -60.96) (xy 129.792737 -60.96) (xy 129.796742 -60.854251) (xy 129.808732 -60.749108)
			(xy 129.828641 -60.645173) (xy 129.856352 -60.543041) (xy 129.891709 -60.443297) (xy 129.934507 -60.346513)
			(xy 129.984503 -60.253243) (xy 130.04141 -60.164022) (xy 130.104901 -60.079359) (xy 130.174613 -59.999741)
			(xy 130.250147 -59.925623) (xy 130.33107 -59.85743) (xy 130.416919 -59.795552) (xy 130.507202 -59.740345)
			(xy 130.601401 -59.692123) (xy 130.698978 -59.651163) (xy 130.799373 -59.617701) (xy 130.902011 -59.591927)
			(xy 131.006304 -59.573989) (xy 131.111655 -59.56399) (xy 131.217461 -59.561987) (xy 131.323115 -59.567992)
			(xy 131.428012 -59.581971) (xy 131.531552 -59.603842) (xy 131.633141 -59.633482) (xy 131.732198 -59.67072)
			(xy 131.828155 -59.715342) (xy 131.920462 -59.767094) (xy 132.008591 -59.825679) (xy 132.092037 -59.890761)
			(xy 132.170321 -59.961967) (xy 132.242996 -60.03889) (xy 132.309646 -60.12109) (xy 132.369888 -60.208094)
			(xy 132.423377 -60.299405) (xy 132.469808 -60.3945) (xy 132.508913 -60.492834) (xy 132.54047 -60.593845)
			(xy 132.564297 -60.696952) (xy 132.580258 -60.801566) (xy 132.588262 -60.907088) (xy 132.588762 -60.96)
			(xy 145.540737 -60.96) (xy 145.544742 -60.854251) (xy 145.556732 -60.749108) (xy 145.576641 -60.645173)
			(xy 145.604352 -60.543041) (xy 145.639709 -60.443297) (xy 145.682507 -60.346513) (xy 145.732503 -60.253243)
			(xy 145.78941 -60.164022) (xy 145.852901 -60.079359) (xy 145.922613 -59.999741) (xy 145.998147 -59.925623)
			(xy 146.07907 -59.85743) (xy 146.164919 -59.795552) (xy 146.255202 -59.740345) (xy 146.349401 -59.692123)
			(xy 146.446978 -59.651163) (xy 146.547373 -59.617701) (xy 146.650011 -59.591927) (xy 146.754304 -59.573989)
			(xy 146.859655 -59.56399) (xy 146.965461 -59.561987) (xy 147.071115 -59.567992) (xy 147.176012 -59.581971)
			(xy 147.279552 -59.603842) (xy 147.381141 -59.633482) (xy 147.480198 -59.67072) (xy 147.576155 -59.715342)
			(xy 147.668462 -59.767094) (xy 147.756591 -59.825679) (xy 147.840037 -59.890761) (xy 147.918321 -59.961967)
			(xy 147.990996 -60.03889) (xy 148.057646 -60.12109) (xy 148.117888 -60.208094) (xy 148.171377 -60.299405)
			(xy 148.217808 -60.3945) (xy 148.256913 -60.492834) (xy 148.28847 -60.593845) (xy 148.312297 -60.696952)
			(xy 148.328258 -60.801566) (xy 148.336262 -60.907088) (xy 148.336762 -60.96) (xy 156.716737 -60.96)
			(xy 156.720742 -60.854251) (xy 156.732732 -60.749108) (xy 156.752641 -60.645173) (xy 156.780352 -60.543041)
			(xy 156.815709 -60.443297) (xy 156.858507 -60.346513) (xy 156.908503 -60.253243) (xy 156.96541 -60.164022)
			(xy 157.028901 -60.079359) (xy 157.098613 -59.999741) (xy 157.174147 -59.925623) (xy 157.25507 -59.85743)
			(xy 157.340919 -59.795552) (xy 157.431202 -59.740345) (xy 157.525401 -59.692123) (xy 157.622978 -59.651163)
			(xy 157.723373 -59.617701) (xy 157.826011 -59.591927) (xy 157.930304 -59.573989) (xy 158.035655 -59.56399)
			(xy 158.141461 -59.561987) (xy 158.247115 -59.567992) (xy 158.352012 -59.581971) (xy 158.455552 -59.603842)
			(xy 158.557141 -59.633482) (xy 158.656198 -59.67072) (xy 158.752155 -59.715342) (xy 158.844462 -59.767094)
			(xy 158.932591 -59.825679) (xy 159.016037 -59.890761) (xy 159.094321 -59.961967) (xy 159.166996 -60.03889)
			(xy 159.233646 -60.12109) (xy 159.293888 -60.208094) (xy 159.347377 -60.299405) (xy 159.393808 -60.3945)
			(xy 159.432913 -60.492834) (xy 159.46447 -60.593845) (xy 159.488297 -60.696952) (xy 159.504258 -60.801566)
			(xy 159.512262 -60.907088) (xy 159.512762 -60.96) (xy 167.892737 -60.96) (xy 167.896742 -60.854251)
			(xy 167.908732 -60.749108) (xy 167.928641 -60.645173) (xy 167.956352 -60.543041) (xy 167.991709 -60.443297)
			(xy 168.034507 -60.346513) (xy 168.084503 -60.253243) (xy 168.14141 -60.164022) (xy 168.204901 -60.079359)
			(xy 168.274613 -59.999741) (xy 168.350147 -59.925623) (xy 168.43107 -59.85743) (xy 168.516919 -59.795552)
			(xy 168.607202 -59.740345) (xy 168.701401 -59.692123) (xy 168.798978 -59.651163) (xy 168.899373 -59.617701)
			(xy 169.002011 -59.591927) (xy 169.106304 -59.573989) (xy 169.211655 -59.56399) (xy 169.317461 -59.561987)
			(xy 169.423115 -59.567992) (xy 169.528012 -59.581971) (xy 169.631552 -59.603842) (xy 169.733141 -59.633482)
			(xy 169.832198 -59.67072) (xy 169.928155 -59.715342) (xy 170.020462 -59.767094) (xy 170.108591 -59.825679)
			(xy 170.192037 -59.890761) (xy 170.270321 -59.961967) (xy 170.342996 -60.03889) (xy 170.409646 -60.12109)
			(xy 170.469888 -60.208094) (xy 170.523377 -60.299405) (xy 170.569808 -60.3945) (xy 170.608913 -60.492834)
			(xy 170.64047 -60.593845) (xy 170.664297 -60.696952) (xy 170.680258 -60.801566) (xy 170.688262 -60.907088)
			(xy 170.688762 -60.96) (xy 185.540911 -60.96) (xy 185.544916 -60.854251) (xy 185.556906 -60.749108)
			(xy 185.576815 -60.645173) (xy 185.604526 -60.543041) (xy 185.639883 -60.443297) (xy 185.682681 -60.346513)
			(xy 185.732677 -60.253243) (xy 185.789584 -60.164022) (xy 185.853075 -60.079359) (xy 185.922787 -59.999741)
			(xy 185.998321 -59.925623) (xy 186.079244 -59.85743) (xy 186.165093 -59.795552) (xy 186.255376 -59.740345)
			(xy 186.349575 -59.692123) (xy 186.447152 -59.651163) (xy 186.547547 -59.617701) (xy 186.650185 -59.591927)
			(xy 186.754478 -59.573989) (xy 186.859829 -59.56399) (xy 186.965635 -59.561987) (xy 187.071289 -59.567992)
			(xy 187.176186 -59.581971) (xy 187.279726 -59.603842) (xy 187.381315 -59.633482) (xy 187.480372 -59.67072)
			(xy 187.576329 -59.715342) (xy 187.668636 -59.767094) (xy 187.756765 -59.825679) (xy 187.840211 -59.890761)
			(xy 187.918495 -59.961967) (xy 187.99117 -60.03889) (xy 188.05782 -60.12109) (xy 188.118062 -60.208094)
			(xy 188.171551 -60.299405) (xy 188.217982 -60.3945) (xy 188.257087 -60.492834) (xy 188.288644 -60.593845)
			(xy 188.312471 -60.696952) (xy 188.328432 -60.801566) (xy 188.336436 -60.907088) (xy 188.336936 -60.96)
			(xy 196.716911 -60.96) (xy 196.720916 -60.854251) (xy 196.732906 -60.749108) (xy 196.752815 -60.645173)
			(xy 196.780526 -60.543041) (xy 196.815883 -60.443297) (xy 196.858681 -60.346513) (xy 196.908677 -60.253243)
			(xy 196.965584 -60.164022) (xy 197.029075 -60.079359) (xy 197.098787 -59.999741) (xy 197.174321 -59.925623)
			(xy 197.255244 -59.85743) (xy 197.341093 -59.795552) (xy 197.431376 -59.740345) (xy 197.525575 -59.692123)
			(xy 197.623152 -59.651163) (xy 197.723547 -59.617701) (xy 197.826185 -59.591927) (xy 197.930478 -59.573989)
			(xy 198.035829 -59.56399) (xy 198.141635 -59.561987) (xy 198.247289 -59.567992) (xy 198.352186 -59.581971)
			(xy 198.455726 -59.603842) (xy 198.557315 -59.633482) (xy 198.656372 -59.67072) (xy 198.752329 -59.715342)
			(xy 198.844636 -59.767094) (xy 198.932765 -59.825679) (xy 199.016211 -59.890761) (xy 199.094495 -59.961967)
			(xy 199.16717 -60.03889) (xy 199.23382 -60.12109) (xy 199.294062 -60.208094) (xy 199.347551 -60.299405)
			(xy 199.393982 -60.3945) (xy 199.433087 -60.492834) (xy 199.464644 -60.593845) (xy 199.488471 -60.696952)
			(xy 199.504432 -60.801566) (xy 199.512436 -60.907088) (xy 199.512936 -60.96) (xy 207.892911 -60.96)
			(xy 207.896916 -60.854251) (xy 207.908906 -60.749108) (xy 207.928815 -60.645173) (xy 207.956526 -60.543041)
			(xy 207.991883 -60.443297) (xy 208.034681 -60.346513) (xy 208.084677 -60.253243) (xy 208.141584 -60.164022)
			(xy 208.205075 -60.079359) (xy 208.274787 -59.999741) (xy 208.350321 -59.925623) (xy 208.431244 -59.85743)
			(xy 208.517093 -59.795552) (xy 208.607376 -59.740345) (xy 208.701575 -59.692123) (xy 208.799152 -59.651163)
			(xy 208.899547 -59.617701) (xy 209.002185 -59.591927) (xy 209.106478 -59.573989) (xy 209.211829 -59.56399)
			(xy 209.317635 -59.561987) (xy 209.423289 -59.567992) (xy 209.528186 -59.581971) (xy 209.631726 -59.603842)
			(xy 209.733315 -59.633482) (xy 209.832372 -59.67072) (xy 209.928329 -59.715342) (xy 210.020636 -59.767094)
			(xy 210.108765 -59.825679) (xy 210.192211 -59.890761) (xy 210.270495 -59.961967) (xy 210.34317 -60.03889)
			(xy 210.40982 -60.12109) (xy 210.470062 -60.208094) (xy 210.523551 -60.299405) (xy 210.569982 -60.3945)
			(xy 210.609087 -60.492834) (xy 210.640644 -60.593845) (xy 210.664471 -60.696952) (xy 210.680432 -60.801566)
			(xy 210.688436 -60.907088) (xy 210.688936 -60.96) (xy 210.688436 -61.012912) (xy 210.680432 -61.118434)
			(xy 210.664471 -61.223048) (xy 210.640644 -61.326155) (xy 210.609087 -61.427166) (xy 210.569982 -61.5255)
			(xy 210.523551 -61.620595) (xy 210.470062 -61.711906) (xy 210.40982 -61.79891) (xy 210.34317 -61.88111)
			(xy 210.270495 -61.958033) (xy 210.192211 -62.029239) (xy 210.108765 -62.094321) (xy 210.020636 -62.152906)
			(xy 209.928329 -62.204658) (xy 209.832372 -62.24928) (xy 209.733315 -62.286518) (xy 209.631726 -62.316158)
			(xy 209.528186 -62.338029) (xy 209.423289 -62.352008) (xy 209.317635 -62.358013) (xy 209.211829 -62.35601)
			(xy 209.106478 -62.346011) (xy 209.002185 -62.328073) (xy 208.899547 -62.302299) (xy 208.799152 -62.268837)
			(xy 208.701575 -62.227877) (xy 208.607376 -62.179655) (xy 208.517093 -62.124448) (xy 208.431244 -62.06257)
			(xy 208.350321 -61.994377) (xy 208.274787 -61.920259) (xy 208.205075 -61.840641) (xy 208.141584 -61.755978)
			(xy 208.084677 -61.666757) (xy 208.034681 -61.573487) (xy 207.991883 -61.476703) (xy 207.956526 -61.376959)
			(xy 207.928815 -61.274827) (xy 207.908906 -61.170892) (xy 207.896916 -61.065749) (xy 207.892911 -60.96)
			(xy 199.512936 -60.96) (xy 199.512436 -61.012912) (xy 199.504432 -61.118434) (xy 199.488471 -61.223048)
			(xy 199.464644 -61.326155) (xy 199.433087 -61.427166) (xy 199.393982 -61.5255) (xy 199.347551 -61.620595)
			(xy 199.294062 -61.711906) (xy 199.23382 -61.79891) (xy 199.16717 -61.88111) (xy 199.094495 -61.958033)
			(xy 199.016211 -62.029239) (xy 198.932765 -62.094321) (xy 198.844636 -62.152906) (xy 198.752329 -62.204658)
			(xy 198.656372 -62.24928) (xy 198.557315 -62.286518) (xy 198.455726 -62.316158) (xy 198.352186 -62.338029)
			(xy 198.247289 -62.352008) (xy 198.141635 -62.358013) (xy 198.035829 -62.35601) (xy 197.930478 -62.346011)
			(xy 197.826185 -62.328073) (xy 197.723547 -62.302299) (xy 197.623152 -62.268837) (xy 197.525575 -62.227877)
			(xy 197.431376 -62.179655) (xy 197.341093 -62.124448) (xy 197.255244 -62.06257) (xy 197.174321 -61.994377)
			(xy 197.098787 -61.920259) (xy 197.029075 -61.840641) (xy 196.965584 -61.755978) (xy 196.908677 -61.666757)
			(xy 196.858681 -61.573487) (xy 196.815883 -61.476703) (xy 196.780526 -61.376959) (xy 196.752815 -61.274827)
			(xy 196.732906 -61.170892) (xy 196.720916 -61.065749) (xy 196.716911 -60.96) (xy 188.336936 -60.96)
			(xy 188.336436 -61.012912) (xy 188.328432 -61.118434) (xy 188.312471 -61.223048) (xy 188.288644 -61.326155)
			(xy 188.257087 -61.427166) (xy 188.217982 -61.5255) (xy 188.171551 -61.620595) (xy 188.118062 -61.711906)
			(xy 188.05782 -61.79891) (xy 187.99117 -61.88111) (xy 187.918495 -61.958033) (xy 187.840211 -62.029239)
			(xy 187.756765 -62.094321) (xy 187.668636 -62.152906) (xy 187.576329 -62.204658) (xy 187.480372 -62.24928)
			(xy 187.381315 -62.286518) (xy 187.279726 -62.316158) (xy 187.176186 -62.338029) (xy 187.071289 -62.352008)
			(xy 186.965635 -62.358013) (xy 186.859829 -62.35601) (xy 186.754478 -62.346011) (xy 186.650185 -62.328073)
			(xy 186.547547 -62.302299) (xy 186.447152 -62.268837) (xy 186.349575 -62.227877) (xy 186.255376 -62.179655)
			(xy 186.165093 -62.124448) (xy 186.079244 -62.06257) (xy 185.998321 -61.994377) (xy 185.922787 -61.920259)
			(xy 185.853075 -61.840641) (xy 185.789584 -61.755978) (xy 185.732677 -61.666757) (xy 185.682681 -61.573487)
			(xy 185.639883 -61.476703) (xy 185.604526 -61.376959) (xy 185.576815 -61.274827) (xy 185.556906 -61.170892)
			(xy 185.544916 -61.065749) (xy 185.540911 -60.96) (xy 170.688762 -60.96) (xy 170.688262 -61.012912)
			(xy 170.680258 -61.118434) (xy 170.664297 -61.223048) (xy 170.64047 -61.326155) (xy 170.608913 -61.427166)
			(xy 170.569808 -61.5255) (xy 170.523377 -61.620595) (xy 170.469888 -61.711906) (xy 170.409646 -61.79891)
			(xy 170.342996 -61.88111) (xy 170.270321 -61.958033) (xy 170.192037 -62.029239) (xy 170.108591 -62.094321)
			(xy 170.020462 -62.152906) (xy 169.928155 -62.204658) (xy 169.832198 -62.24928) (xy 169.733141 -62.286518)
			(xy 169.631552 -62.316158) (xy 169.528012 -62.338029) (xy 169.423115 -62.352008) (xy 169.317461 -62.358013)
			(xy 169.211655 -62.35601) (xy 169.106304 -62.346011) (xy 169.002011 -62.328073) (xy 168.899373 -62.302299)
			(xy 168.798978 -62.268837) (xy 168.701401 -62.227877) (xy 168.607202 -62.179655) (xy 168.516919 -62.124448)
			(xy 168.43107 -62.06257) (xy 168.350147 -61.994377) (xy 168.274613 -61.920259) (xy 168.204901 -61.840641)
			(xy 168.14141 -61.755978) (xy 168.084503 -61.666757) (xy 168.034507 -61.573487) (xy 167.991709 -61.476703)
			(xy 167.956352 -61.376959) (xy 167.928641 -61.274827) (xy 167.908732 -61.170892) (xy 167.896742 -61.065749)
			(xy 167.892737 -60.96) (xy 159.512762 -60.96) (xy 159.512262 -61.012912) (xy 159.504258 -61.118434)
			(xy 159.488297 -61.223048) (xy 159.46447 -61.326155) (xy 159.432913 -61.427166) (xy 159.393808 -61.5255)
			(xy 159.347377 -61.620595) (xy 159.293888 -61.711906) (xy 159.233646 -61.79891) (xy 159.166996 -61.88111)
			(xy 159.094321 -61.958033) (xy 159.016037 -62.029239) (xy 158.932591 -62.094321) (xy 158.844462 -62.152906)
			(xy 158.752155 -62.204658) (xy 158.656198 -62.24928) (xy 158.557141 -62.286518) (xy 158.455552 -62.316158)
			(xy 158.352012 -62.338029) (xy 158.247115 -62.352008) (xy 158.141461 -62.358013) (xy 158.035655 -62.35601)
			(xy 157.930304 -62.346011) (xy 157.826011 -62.328073) (xy 157.723373 -62.302299) (xy 157.622978 -62.268837)
			(xy 157.525401 -62.227877) (xy 157.431202 -62.179655) (xy 157.340919 -62.124448) (xy 157.25507 -62.06257)
			(xy 157.174147 -61.994377) (xy 157.098613 -61.920259) (xy 157.028901 -61.840641) (xy 156.96541 -61.755978)
			(xy 156.908503 -61.666757) (xy 156.858507 -61.573487) (xy 156.815709 -61.476703) (xy 156.780352 -61.376959)
			(xy 156.752641 -61.274827) (xy 156.732732 -61.170892) (xy 156.720742 -61.065749) (xy 156.716737 -60.96)
			(xy 148.336762 -60.96) (xy 148.336262 -61.012912) (xy 148.328258 -61.118434) (xy 148.312297 -61.223048)
			(xy 148.28847 -61.326155) (xy 148.256913 -61.427166) (xy 148.217808 -61.5255) (xy 148.171377 -61.620595)
			(xy 148.117888 -61.711906) (xy 148.057646 -61.79891) (xy 147.990996 -61.88111) (xy 147.918321 -61.958033)
			(xy 147.840037 -62.029239) (xy 147.756591 -62.094321) (xy 147.668462 -62.152906) (xy 147.576155 -62.204658)
			(xy 147.480198 -62.24928) (xy 147.381141 -62.286518) (xy 147.279552 -62.316158) (xy 147.176012 -62.338029)
			(xy 147.071115 -62.352008) (xy 146.965461 -62.358013) (xy 146.859655 -62.35601) (xy 146.754304 -62.346011)
			(xy 146.650011 -62.328073) (xy 146.547373 -62.302299) (xy 146.446978 -62.268837) (xy 146.349401 -62.227877)
			(xy 146.255202 -62.179655) (xy 146.164919 -62.124448) (xy 146.07907 -62.06257) (xy 145.998147 -61.994377)
			(xy 145.922613 -61.920259) (xy 145.852901 -61.840641) (xy 145.78941 -61.755978) (xy 145.732503 -61.666757)
			(xy 145.682507 -61.573487) (xy 145.639709 -61.476703) (xy 145.604352 -61.376959) (xy 145.576641 -61.274827)
			(xy 145.556732 -61.170892) (xy 145.544742 -61.065749) (xy 145.540737 -60.96) (xy 132.588762 -60.96)
			(xy 132.588262 -61.012912) (xy 132.580258 -61.118434) (xy 132.564297 -61.223048) (xy 132.54047 -61.326155)
			(xy 132.508913 -61.427166) (xy 132.469808 -61.5255) (xy 132.423377 -61.620595) (xy 132.369888 -61.711906)
			(xy 132.309646 -61.79891) (xy 132.242996 -61.88111) (xy 132.170321 -61.958033) (xy 132.092037 -62.029239)
			(xy 132.008591 -62.094321) (xy 131.920462 -62.152906) (xy 131.828155 -62.204658) (xy 131.732198 -62.24928)
			(xy 131.633141 -62.286518) (xy 131.531552 -62.316158) (xy 131.428012 -62.338029) (xy 131.323115 -62.352008)
			(xy 131.217461 -62.358013) (xy 131.111655 -62.35601) (xy 131.006304 -62.346011) (xy 130.902011 -62.328073)
			(xy 130.799373 -62.302299) (xy 130.698978 -62.268837) (xy 130.601401 -62.227877) (xy 130.507202 -62.179655)
			(xy 130.416919 -62.124448) (xy 130.33107 -62.06257) (xy 130.250147 -61.994377) (xy 130.174613 -61.920259)
			(xy 130.104901 -61.840641) (xy 130.04141 -61.755978) (xy 129.984503 -61.666757) (xy 129.934507 -61.573487)
			(xy 129.891709 -61.476703) (xy 129.856352 -61.376959) (xy 129.828641 -61.274827) (xy 129.808732 -61.170892)
			(xy 129.796742 -61.065749) (xy 129.792737 -60.96) (xy 121.412762 -60.96) (xy 121.412262 -61.012912)
			(xy 121.404258 -61.118434) (xy 121.388297 -61.223048) (xy 121.36447 -61.326155) (xy 121.332913 -61.427166)
			(xy 121.293808 -61.5255) (xy 121.247377 -61.620595) (xy 121.193888 -61.711906) (xy 121.133646 -61.79891)
			(xy 121.066996 -61.88111) (xy 120.994321 -61.958033) (xy 120.916037 -62.029239) (xy 120.832591 -62.094321)
			(xy 120.744462 -62.152906) (xy 120.652155 -62.204658) (xy 120.556198 -62.24928) (xy 120.457141 -62.286518)
			(xy 120.355552 -62.316158) (xy 120.252012 -62.338029) (xy 120.147115 -62.352008) (xy 120.041461 -62.358013)
			(xy 119.935655 -62.35601) (xy 119.830304 -62.346011) (xy 119.726011 -62.328073) (xy 119.623373 -62.302299)
			(xy 119.522978 -62.268837) (xy 119.425401 -62.227877) (xy 119.331202 -62.179655) (xy 119.240919 -62.124448)
			(xy 119.15507 -62.06257) (xy 119.074147 -61.994377) (xy 118.998613 -61.920259) (xy 118.928901 -61.840641)
			(xy 118.86541 -61.755978) (xy 118.808503 -61.666757) (xy 118.758507 -61.573487) (xy 118.715709 -61.476703)
			(xy 118.680352 -61.376959) (xy 118.652641 -61.274827) (xy 118.632732 -61.170892) (xy 118.620742 -61.065749)
			(xy 118.616737 -60.96) (xy 110.236762 -60.96) (xy 110.236262 -61.012912) (xy 110.228258 -61.118434)
			(xy 110.212297 -61.223048) (xy 110.18847 -61.326155) (xy 110.156913 -61.427166) (xy 110.117808 -61.5255)
			(xy 110.071377 -61.620595) (xy 110.017888 -61.711906) (xy 109.957646 -61.79891) (xy 109.890996 -61.88111)
			(xy 109.818321 -61.958033) (xy 109.740037 -62.029239) (xy 109.656591 -62.094321) (xy 109.568462 -62.152906)
			(xy 109.476155 -62.204658) (xy 109.380198 -62.24928) (xy 109.281141 -62.286518) (xy 109.179552 -62.316158)
			(xy 109.076012 -62.338029) (xy 108.971115 -62.352008) (xy 108.865461 -62.358013) (xy 108.759655 -62.35601)
			(xy 108.654304 -62.346011) (xy 108.550011 -62.328073) (xy 108.447373 -62.302299) (xy 108.346978 -62.268837)
			(xy 108.249401 -62.227877) (xy 108.155202 -62.179655) (xy 108.064919 -62.124448) (xy 107.97907 -62.06257)
			(xy 107.898147 -61.994377) (xy 107.822613 -61.920259) (xy 107.752901 -61.840641) (xy 107.68941 -61.755978)
			(xy 107.632503 -61.666757) (xy 107.582507 -61.573487) (xy 107.539709 -61.476703) (xy 107.504352 -61.376959)
			(xy 107.476641 -61.274827) (xy 107.456732 -61.170892) (xy 107.444742 -61.065749) (xy 107.440737 -60.96)
			(xy 92.075762 -60.96) (xy 92.075262 -61.012912) (xy 92.067258 -61.118434) (xy 92.051297 -61.223048)
			(xy 92.02747 -61.326155) (xy 91.995913 -61.427166) (xy 91.956808 -61.5255) (xy 91.910377 -61.620595)
			(xy 91.856888 -61.711906) (xy 91.796646 -61.79891) (xy 91.729996 -61.88111) (xy 91.657321 -61.958033)
			(xy 91.579037 -62.029239) (xy 91.495591 -62.094321) (xy 91.407462 -62.152906) (xy 91.315155 -62.204658)
			(xy 91.219198 -62.24928) (xy 91.120141 -62.286518) (xy 91.018552 -62.316158) (xy 90.915012 -62.338029)
			(xy 90.810115 -62.352008) (xy 90.704461 -62.358013) (xy 90.598655 -62.35601) (xy 90.493304 -62.346011)
			(xy 90.389011 -62.328073) (xy 90.286373 -62.302299) (xy 90.185978 -62.268837) (xy 90.088401 -62.227877)
			(xy 89.994202 -62.179655) (xy 89.903919 -62.124448) (xy 89.81807 -62.06257) (xy 89.737147 -61.994377)
			(xy 89.661613 -61.920259) (xy 89.591901 -61.840641) (xy 89.52841 -61.755978) (xy 89.471503 -61.666757)
			(xy 89.421507 -61.573487) (xy 89.378709 -61.476703) (xy 89.343352 -61.376959) (xy 89.315641 -61.274827)
			(xy 89.295732 -61.170892) (xy 89.283742 -61.065749) (xy 89.279737 -60.96) (xy 80.772762 -60.96) (xy 80.772262 -61.012912)
			(xy 80.764258 -61.118434) (xy 80.748297 -61.223048) (xy 80.72447 -61.326155) (xy 80.692913 -61.427166)
			(xy 80.653808 -61.5255) (xy 80.607377 -61.620595) (xy 80.553888 -61.711906) (xy 80.493646 -61.79891)
			(xy 80.426996 -61.88111) (xy 80.354321 -61.958033) (xy 80.276037 -62.029239) (xy 80.192591 -62.094321)
			(xy 80.104462 -62.152906) (xy 80.012155 -62.204658) (xy 79.916198 -62.24928) (xy 79.817141 -62.286518)
			(xy 79.715552 -62.316158) (xy 79.612012 -62.338029) (xy 79.507115 -62.352008) (xy 79.401461 -62.358013)
			(xy 79.295655 -62.35601) (xy 79.190304 -62.346011) (xy 79.086011 -62.328073) (xy 78.983373 -62.302299)
			(xy 78.882978 -62.268837) (xy 78.785401 -62.227877) (xy 78.691202 -62.179655) (xy 78.600919 -62.124448)
			(xy 78.51507 -62.06257) (xy 78.434147 -61.994377) (xy 78.358613 -61.920259) (xy 78.288901 -61.840641)
			(xy 78.22541 -61.755978) (xy 78.168503 -61.666757) (xy 78.118507 -61.573487) (xy 78.075709 -61.476703)
			(xy 78.040352 -61.376959) (xy 78.012641 -61.274827) (xy 77.992732 -61.170892) (xy 77.980742 -61.065749)
			(xy 77.976737 -60.96) (xy 69.469762 -60.96) (xy 69.469262 -61.012912) (xy 69.461258 -61.118434) (xy 69.445297 -61.223048)
			(xy 69.42147 -61.326155) (xy 69.389913 -61.427166) (xy 69.350808 -61.5255) (xy 69.304377 -61.620595)
			(xy 69.250888 -61.711906) (xy 69.190646 -61.79891) (xy 69.123996 -61.88111) (xy 69.051321 -61.958033)
			(xy 68.973037 -62.029239) (xy 68.889591 -62.094321) (xy 68.801462 -62.152906) (xy 68.709155 -62.204658)
			(xy 68.613198 -62.24928) (xy 68.514141 -62.286518) (xy 68.412552 -62.316158) (xy 68.309012 -62.338029)
			(xy 68.204115 -62.352008) (xy 68.098461 -62.358013) (xy 67.992655 -62.35601) (xy 67.887304 -62.346011)
			(xy 67.783011 -62.328073) (xy 67.680373 -62.302299) (xy 67.579978 -62.268837) (xy 67.482401 -62.227877)
			(xy 67.388202 -62.179655) (xy 67.297919 -62.124448) (xy 67.21207 -62.06257) (xy 67.131147 -61.994377)
			(xy 67.055613 -61.920259) (xy 66.985901 -61.840641) (xy 66.92241 -61.755978) (xy 66.865503 -61.666757)
			(xy 66.815507 -61.573487) (xy 66.772709 -61.476703) (xy 66.737352 -61.376959) (xy 66.709641 -61.274827)
			(xy 66.689732 -61.170892) (xy 66.677742 -61.065749) (xy 66.673737 -60.96) (xy 0.509016 -60.96) (xy 0.509016 -62.203781)
			(xy 38.440102 -62.203781) (xy 38.440102 -62.119059) (xy 38.448155 -62.034722) (xy 38.464189 -61.951532)
			(xy 38.488057 -61.870242) (xy 38.519545 -61.79159) (xy 38.558367 -61.716287) (xy 38.60417 -61.645015)
			(xy 38.656541 -61.578419) (xy 38.715006 -61.517104) (xy 38.779034 -61.461623) (xy 38.848046 -61.41248)
			(xy 38.921416 -61.37012) (xy 38.998481 -61.334925) (xy 39.078543 -61.307216) (xy 39.160876 -61.287242)
			(xy 39.244735 -61.275185) (xy 39.32936 -61.271154) (xy 39.413985 -61.275185) (xy 39.497844 -61.287242)
			(xy 39.580177 -61.307216) (xy 39.660239 -61.334925) (xy 39.737304 -61.37012) (xy 39.810674 -61.41248)
			(xy 39.879686 -61.461623) (xy 39.943714 -61.517104) (xy 40.002179 -61.578419) (xy 40.05455 -61.645015)
			(xy 40.100353 -61.716287) (xy 40.139175 -61.79159) (xy 40.170663 -61.870242) (xy 40.194531 -61.951532)
			(xy 40.210565 -62.034722) (xy 40.218618 -62.119059) (xy 40.219122 -62.16142) (xy 40.218618 -62.203781)
			(xy 40.210565 -62.288118) (xy 40.194531 -62.371308) (xy 40.170663 -62.452598) (xy 40.139175 -62.53125)
			(xy 40.100353 -62.606553) (xy 40.05455 -62.677825) (xy 40.002179 -62.744421) (xy 39.943714 -62.805736)
			(xy 39.879686 -62.861217) (xy 39.810674 -62.91036) (xy 39.737304 -62.95272) (xy 39.660239 -62.987915)
			(xy 39.580177 -63.015624) (xy 39.497844 -63.035598) (xy 39.413985 -63.047655) (xy 39.32936 -63.051687)
			(xy 39.244735 -63.047655) (xy 39.160876 -63.035598) (xy 39.078543 -63.015624) (xy 38.998481 -62.987915)
			(xy 38.921416 -62.95272) (xy 38.848046 -62.91036) (xy 38.779034 -62.861217) (xy 38.715006 -62.805736)
			(xy 38.656541 -62.744421) (xy 38.60417 -62.677825) (xy 38.558367 -62.606553) (xy 38.519545 -62.53125)
			(xy 38.488057 -62.452598) (xy 38.464189 -62.371308) (xy 38.448155 -62.288118) (xy 38.440102 -62.203781)
			(xy 0.509016 -62.203781) (xy 0.509016 -66.43624) (xy 26.694892 -66.43624) (xy 26.695489 -66.389845)
			(xy 26.70513 -66.297557) (xy 26.724322 -66.206773) (xy 26.752856 -66.118479) (xy 26.771092 -66.075814)
			(xy 26.774874 -66.065864) (xy 26.774889 -66.044608) (xy 26.771092 -66.034666) (xy 26.75286 -65.991998)
			(xy 26.724313 -65.903708) (xy 26.705116 -65.812925) (xy 26.695479 -65.720636) (xy 26.694892 -65.67424)
			(xy 26.695489 -65.627845) (xy 26.70513 -65.535557) (xy 26.724322 -65.444773) (xy 26.752856 -65.356479)
			(xy 26.771092 -65.313814) (xy 26.774874 -65.303864) (xy 26.774889 -65.282608) (xy 26.771092 -65.272666)
			(xy 26.75286 -65.229998) (xy 26.724313 -65.141708) (xy 26.705116 -65.050925) (xy 26.695479 -64.958636)
			(xy 26.694892 -64.91224) (xy 26.69539 -64.871137) (xy 26.702972 -64.789283) (xy 26.718074 -64.708477)
			(xy 26.740567 -64.629409) (xy 26.77026 -64.552754) (xy 26.8069 -64.479166) (xy 26.850173 -64.409273)
			(xy 26.899711 -64.343671) (xy 26.955091 -64.282919) (xy 27.01584 -64.227537) (xy 27.08144 -64.177996)
			(xy 27.151331 -64.13472) (xy 27.224918 -64.098077) (xy 27.301571 -64.06838) (xy 27.380638 -64.045883)
			(xy 27.461443 -64.030777) (xy 27.543298 -64.023192) (xy 27.5844 -64.022732) (xy 27.630796 -64.023311)
			(xy 27.723084 -64.032957) (xy 27.813868 -64.052154) (xy 27.902161 -64.080693) (xy 27.944826 -64.098932)
			(xy 27.954768 -64.102738) (xy 27.976032 -64.102738) (xy 27.985974 -64.098932) (xy 28.028637 -64.08069)
			(xy 28.116929 -64.052144) (xy 28.207714 -64.032951) (xy 28.300004 -64.023317) (xy 28.3464 -64.022732)
			(xy 28.387504 -64.023152) (xy 28.469362 -64.030738) (xy 28.550171 -64.045844) (xy 28.629241 -64.068342)
			(xy 28.705898 -64.09804) (xy 28.779488 -64.134685) (xy 28.849383 -64.177963) (xy 28.914986 -64.227506)
			(xy 28.975737 -64.282891) (xy 29.03112 -64.343645) (xy 29.08066 -64.40925) (xy 29.123935 -64.479147)
			(xy 29.160576 -64.552738) (xy 29.190271 -64.629397) (xy 29.212765 -64.708468) (xy 29.227868 -64.789277)
			(xy 29.23545 -64.871136) (xy 29.235908 -64.91224) (xy 29.235304 -64.958635) (xy 29.225665 -65.050923)
			(xy 29.206475 -65.141707) (xy 29.177943 -65.230001) (xy 29.159708 -65.272666) (xy 29.155879 -65.282601)
			(xy 29.155894 -65.303871) (xy 29.159708 -65.313814) (xy 29.177966 -65.356471) (xy 29.206507 -65.444765)
			(xy 29.224945 -65.532) (xy 268.350492 -65.532) (xy 268.351075 -65.485604) (xy 268.36072 -65.393316)
			(xy 268.379916 -65.302532) (xy 268.408454 -65.214239) (xy 268.426692 -65.171574) (xy 268.430498 -65.161632)
			(xy 268.430498 -65.140368) (xy 268.426692 -65.130426) (xy 268.408447 -65.087764) (xy 268.379903 -64.999471)
			(xy 268.36071 -64.908686) (xy 268.351077 -64.816396) (xy 268.350492 -64.77) (xy 268.351075 -64.723604)
			(xy 268.36072 -64.631316) (xy 268.379916 -64.540532) (xy 268.408454 -64.452239) (xy 268.426692 -64.409574)
			(xy 268.430498 -64.399632) (xy 268.430498 -64.378368) (xy 268.426692 -64.368426) (xy 268.408447 -64.325764)
			(xy 268.379903 -64.237471) (xy 268.36071 -64.146686) (xy 268.351077 -64.054396) (xy 268.350492 -64.008)
			(xy 268.351075 -63.961604) (xy 268.36072 -63.869316) (xy 268.379916 -63.778532) (xy 268.408454 -63.690239)
			(xy 268.426692 -63.647574) (xy 268.430498 -63.637632) (xy 268.430498 -63.616368) (xy 268.426692 -63.606426)
			(xy 268.408447 -63.563764) (xy 268.379903 -63.475471) (xy 268.36071 -63.384686) (xy 268.351077 -63.292396)
			(xy 268.350492 -63.246) (xy 268.351075 -63.199604) (xy 268.36072 -63.107316) (xy 268.379916 -63.016532)
			(xy 268.408454 -62.928239) (xy 268.426692 -62.885574) (xy 268.430498 -62.875632) (xy 268.430498 -62.854368)
			(xy 268.426692 -62.844426) (xy 268.408447 -62.801764) (xy 268.379903 -62.713471) (xy 268.36071 -62.622686)
			(xy 268.351077 -62.530396) (xy 268.350492 -62.484) (xy 268.351075 -62.437604) (xy 268.36072 -62.345316)
			(xy 268.379916 -62.254532) (xy 268.408454 -62.166239) (xy 268.426692 -62.123574) (xy 268.430498 -62.113632)
			(xy 268.430498 -62.092368) (xy 268.426692 -62.082426) (xy 268.408447 -62.039764) (xy 268.379903 -61.951471)
			(xy 268.36071 -61.860686) (xy 268.351077 -61.768396) (xy 268.350492 -61.722) (xy 268.350967 -61.680898)
			(xy 268.358552 -61.599043) (xy 268.373657 -61.518238) (xy 268.396153 -61.439171) (xy 268.425849 -61.362517)
			(xy 268.462491 -61.28893) (xy 268.505766 -61.219038) (xy 268.555306 -61.153437) (xy 268.610687 -61.092687)
			(xy 268.671437 -61.037306) (xy 268.737038 -60.987766) (xy 268.80693 -60.944491) (xy 268.880517 -60.907849)
			(xy 268.957171 -60.878153) (xy 269.036238 -60.855657) (xy 269.117043 -60.840552) (xy 269.198898 -60.832967)
			(xy 269.24 -60.832492) (xy 269.286396 -60.833075) (xy 269.378684 -60.84272) (xy 269.469468 -60.861916)
			(xy 269.557761 -60.890454) (xy 269.600426 -60.908692) (xy 269.610368 -60.912498) (xy 269.631632 -60.912498)
			(xy 269.641574 -60.908692) (xy 269.684236 -60.890447) (xy 269.772529 -60.861903) (xy 269.863314 -60.84271)
			(xy 269.955604 -60.833077) (xy 270.002 -60.832492) (xy 270.048396 -60.833075) (xy 270.140684 -60.84272)
			(xy 270.231468 -60.861916) (xy 270.319761 -60.890454) (xy 270.362426 -60.908692) (xy 270.372368 -60.912498)
			(xy 270.393632 -60.912498) (xy 270.403574 -60.908692) (xy 270.446236 -60.890447) (xy 270.534529 -60.861903)
			(xy 270.625314 -60.84271) (xy 270.717604 -60.833077) (xy 270.764 -60.832492) (xy 270.810396 -60.833075)
			(xy 270.902684 -60.84272) (xy 270.993468 -60.861916) (xy 271.081761 -60.890454) (xy 271.124426 -60.908692)
			(xy 271.134368 -60.912498) (xy 271.155632 -60.912498) (xy 271.165574 -60.908692) (xy 271.208236 -60.890447)
			(xy 271.296529 -60.861903) (xy 271.387314 -60.84271) (xy 271.479604 -60.833077) (xy 271.526 -60.832492)
			(xy 271.572396 -60.833075) (xy 271.664684 -60.84272) (xy 271.755468 -60.861916) (xy 271.843761 -60.890454)
			(xy 271.886426 -60.908692) (xy 271.896368 -60.912498) (xy 271.917632 -60.912498) (xy 271.927574 -60.908692)
			(xy 271.970236 -60.890447) (xy 272.058529 -60.861903) (xy 272.149314 -60.84271) (xy 272.241604 -60.833077)
			(xy 272.288 -60.832492) (xy 272.329102 -60.832967) (xy 272.410957 -60.840552) (xy 272.491762 -60.855657)
			(xy 272.570829 -60.878153) (xy 272.647483 -60.907849) (xy 272.72107 -60.944491) (xy 272.790962 -60.987766)
			(xy 272.856563 -61.037306) (xy 272.917313 -61.092687) (xy 272.972694 -61.153437) (xy 273.022234 -61.219038)
			(xy 273.065509 -61.28893) (xy 273.102151 -61.362517) (xy 273.131847 -61.439171) (xy 273.154343 -61.518238)
			(xy 273.169448 -61.599043) (xy 273.177033 -61.680898) (xy 273.177508 -61.722) (xy 273.176925 -61.768396)
			(xy 273.16728 -61.860684) (xy 273.148084 -61.951468) (xy 273.119546 -62.039761) (xy 273.101308 -62.082426)
			(xy 273.097502 -62.092368) (xy 273.097502 -62.113632) (xy 273.101308 -62.123574) (xy 273.119553 -62.166236)
			(xy 273.148097 -62.254529) (xy 273.16729 -62.345314) (xy 273.176923 -62.437604) (xy 273.177508 -62.484)
			(xy 273.177033 -62.525102) (xy 273.169448 -62.606957) (xy 273.154343 -62.687762) (xy 273.131847 -62.766829)
			(xy 273.102151 -62.843483) (xy 273.065509 -62.91707) (xy 273.022234 -62.986962) (xy 272.972694 -63.052563)
			(xy 272.917313 -63.113313) (xy 272.856563 -63.168694) (xy 272.790962 -63.218234) (xy 272.72107 -63.261509)
			(xy 272.647483 -63.298151) (xy 272.570829 -63.327847) (xy 272.491762 -63.350343) (xy 272.410957 -63.365448)
			(xy 272.329102 -63.373033) (xy 272.288 -63.373508) (xy 272.241604 -63.372925) (xy 272.149316 -63.36328)
			(xy 272.058532 -63.344084) (xy 271.970239 -63.315546) (xy 271.927574 -63.297308) (xy 271.917632 -63.293502)
			(xy 271.896368 -63.293502) (xy 271.886426 -63.297308) (xy 271.853507 -63.311537) (xy 271.785822 -63.335257)
			(xy 271.716442 -63.353437) (xy 271.681194 -63.360046) (xy 271.67107 -63.362344) (xy 271.653749 -63.373749)
			(xy 271.642344 -63.39107) (xy 271.640046 -63.401194) (xy 271.633416 -63.436437) (xy 271.61522 -63.50581)
			(xy 271.591513 -63.573498) (xy 271.577308 -63.606426) (xy 271.573502 -63.616368) (xy 271.573502 -63.637632)
			(xy 271.577308 -63.647574) (xy 271.591537 -63.680493) (xy 271.615257 -63.748178) (xy 271.633437 -63.817558)
			(xy 271.640046 -63.852806) (xy 271.642344 -63.86293) (xy 271.653749 -63.880251) (xy 271.67107 -63.891656)
			(xy 271.681194 -63.893954) (xy 271.716437 -63.900584) (xy 271.78581 -63.91878) (xy 271.853498 -63.942487)
			(xy 271.886426 -63.956692) (xy 271.896368 -63.960498) (xy 271.917632 -63.960498) (xy 271.927574 -63.956692)
			(xy 271.970236 -63.938447) (xy 272.058529 -63.909903) (xy 272.149314 -63.89071) (xy 272.241604 -63.881077)
			(xy 272.288 -63.880492) (xy 272.329102 -63.880967) (xy 272.410957 -63.888552) (xy 272.491762 -63.903657)
			(xy 272.570829 -63.926153) (xy 272.647483 -63.955849) (xy 272.72107 -63.992491) (xy 272.790962 -64.035766)
			(xy 272.856563 -64.085306) (xy 272.917313 -64.140687) (xy 272.972694 -64.201437) (xy 273.022234 -64.267038)
			(xy 273.065509 -64.33693) (xy 273.102151 -64.410517) (xy 273.131847 -64.487171) (xy 273.154343 -64.566238)
			(xy 273.169448 -64.647043) (xy 273.177033 -64.728898) (xy 273.177508 -64.77) (xy 273.176925 -64.816396)
			(xy 273.16728 -64.908684) (xy 273.148084 -64.999468) (xy 273.119546 -65.087761) (xy 273.101308 -65.130426)
			(xy 273.097502 -65.140368) (xy 273.097502 -65.161632) (xy 273.101308 -65.171574) (xy 273.119553 -65.214236)
			(xy 273.148097 -65.302529) (xy 273.16729 -65.393314) (xy 273.176923 -65.485604) (xy 273.177508 -65.532)
			(xy 273.177033 -65.573102) (xy 273.169448 -65.654957) (xy 273.154343 -65.735762) (xy 273.131847 -65.814829)
			(xy 273.102151 -65.891483) (xy 273.065509 -65.96507) (xy 273.022234 -66.034962) (xy 272.972694 -66.100563)
			(xy 272.917313 -66.161313) (xy 272.856563 -66.216694) (xy 272.790962 -66.266234) (xy 272.72107 -66.309509)
			(xy 272.647483 -66.346151) (xy 272.570829 -66.375847) (xy 272.491762 -66.398343) (xy 272.410957 -66.413448)
			(xy 272.329102 -66.421033) (xy 272.288 -66.421508) (xy 272.241604 -66.420925) (xy 272.149316 -66.41128)
			(xy 272.058532 -66.392084) (xy 271.970239 -66.363546) (xy 271.927574 -66.345308) (xy 271.917632 -66.341502)
			(xy 271.896368 -66.341502) (xy 271.886426 -66.345308) (xy 271.843764 -66.363553) (xy 271.755471 -66.392097)
			(xy 271.664686 -66.41129) (xy 271.572396 -66.420923) (xy 271.526 -66.421508) (xy 271.479604 -66.420925)
			(xy 271.387316 -66.41128) (xy 271.296532 -66.392084) (xy 271.208239 -66.363546) (xy 271.165574 -66.345308)
			(xy 271.155632 -66.341502) (xy 271.134368 -66.341502) (xy 271.124426 -66.345308) (xy 271.081764 -66.363553)
			(xy 270.993471 -66.392097) (xy 270.902686 -66.41129) (xy 270.810396 -66.420923) (xy 270.764 -66.421508)
			(xy 270.717604 -66.420925) (xy 270.625316 -66.41128) (xy 270.534532 -66.392084) (xy 270.446239 -66.363546)
			(xy 270.403574 -66.345308) (xy 270.393632 -66.341502) (xy 270.372368 -66.341502) (xy 270.362426 -66.345308)
			(xy 270.319764 -66.363553) (xy 270.231471 -66.392097) (xy 270.140686 -66.41129) (xy 270.048396 -66.420923)
			(xy 270.002 -66.421508) (xy 269.955604 -66.420925) (xy 269.863316 -66.41128) (xy 269.772532 -66.392084)
			(xy 269.684239 -66.363546) (xy 269.641574 -66.345308) (xy 269.631632 -66.341502) (xy 269.610368 -66.341502)
			(xy 269.600426 -66.345308) (xy 269.557764 -66.363553) (xy 269.469471 -66.392097) (xy 269.378686 -66.41129)
			(xy 269.286396 -66.420923) (xy 269.24 -66.421508) (xy 269.198898 -66.421033) (xy 269.117043 -66.413448)
			(xy 269.036238 -66.398343) (xy 268.957171 -66.375847) (xy 268.880517 -66.346151) (xy 268.80693 -66.309509)
			(xy 268.737038 -66.266234) (xy 268.671437 -66.216694) (xy 268.610687 -66.161313) (xy 268.555306 -66.100563)
			(xy 268.505766 -66.034962) (xy 268.462491 -65.96507) (xy 268.425849 -65.891483) (xy 268.396153 -65.814829)
			(xy 268.373657 -65.735762) (xy 268.358552 -65.654957) (xy 268.350967 -65.573102) (xy 268.350492 -65.532)
			(xy 29.224945 -65.532) (xy 29.225696 -65.535552) (xy 29.235325 -65.627843) (xy 29.235908 -65.67424)
			(xy 29.235304 -65.720635) (xy 29.225665 -65.812923) (xy 29.206475 -65.903707) (xy 29.177943 -65.992001)
			(xy 29.159708 -66.034666) (xy 29.155879 -66.044601) (xy 29.155894 -66.065871) (xy 29.159708 -66.075814)
			(xy 29.177966 -66.118471) (xy 29.206507 -66.206765) (xy 29.225696 -66.297552) (xy 29.235325 -66.389843)
			(xy 29.235908 -66.43624) (xy 29.235472 -66.477343) (xy 29.227883 -66.559198) (xy 29.212774 -66.640004)
			(xy 29.190275 -66.719072) (xy 29.160576 -66.795726) (xy 29.123931 -66.869313) (xy 29.080653 -66.939205)
			(xy 29.031111 -67.004806) (xy 28.975727 -67.065555) (xy 28.914975 -67.120936) (xy 28.849372 -67.170475)
			(xy 28.779478 -67.21375) (xy 28.705889 -67.250392) (xy 28.629234 -67.280087) (xy 28.550166 -67.302584)
			(xy 28.469359 -67.317689) (xy 28.387503 -67.325273) (xy 28.3464 -67.325748) (xy 28.300004 -67.32517)
			(xy 28.207716 -67.315524) (xy 28.116932 -67.296327) (xy 28.028638 -67.267787) (xy 27.985974 -67.249548)
			(xy 27.976032 -67.245742) (xy 27.954768 -67.245742) (xy 27.944826 -67.249548) (xy 27.902165 -67.267795)
			(xy 27.813872 -67.296338) (xy 27.723087 -67.31553) (xy 27.630796 -67.325163) (xy 27.5844 -67.325748)
			(xy 27.543299 -67.325233) (xy 27.461447 -67.317649) (xy 27.380644 -67.302545) (xy 27.301579 -67.280049)
			(xy 27.224927 -67.250355) (xy 27.151342 -67.213715) (xy 27.081451 -67.170442) (xy 27.015851 -67.120905)
			(xy 26.955101 -67.065527) (xy 26.89972 -67.00478) (xy 26.85018 -66.939182) (xy 26.806904 -66.869293)
			(xy 26.770261 -66.79571) (xy 26.740563 -66.719059) (xy 26.718064 -66.639995) (xy 26.702957 -66.559193)
			(xy 26.695368 -66.477341) (xy 26.694892 -66.43624) (xy 0.509016 -66.43624) (xy 0.509016 -70.939914)
			(xy 8.478012 -70.939914) (xy 8.478545 -70.885007) (xy 8.487299 -70.775543) (xy 8.504775 -70.667129)
			(xy 8.530863 -70.56046) (xy 8.565395 -70.456217) (xy 8.608149 -70.355068) (xy 8.658854 -70.257662)
			(xy 8.717182 -70.16462) (xy 8.749538 -70.120256) (xy 8.755682 -70.111222) (xy 8.760349 -70.089902)
			(xy 8.755684 -70.068582) (xy 8.749538 -70.05955) (xy 8.717186 -70.015184) (xy 8.65886 -69.922141)
			(xy 8.608158 -69.824733) (xy 8.565404 -69.723585) (xy 8.530872 -69.619343) (xy 8.504782 -69.512674)
			(xy 8.487302 -69.404262) (xy 8.478544 -69.294799) (xy 8.478012 -69.239892) (xy 8.478453 -69.188568)
			(xy 8.486124 -69.086208) (xy 8.501424 -68.984707) (xy 8.524266 -68.884633) (xy 8.554522 -68.786547)
			(xy 8.592024 -68.690995) (xy 8.636562 -68.598513) (xy 8.687887 -68.509618) (xy 8.745711 -68.424808)
			(xy 8.809711 -68.344555) (xy 8.87953 -68.26931) (xy 8.954776 -68.199493) (xy 9.03503 -68.135494)
			(xy 9.119842 -68.077672) (xy 9.208738 -68.026349) (xy 9.301221 -67.981813) (xy 9.396773 -67.944313)
			(xy 9.49486 -67.914058) (xy 9.594935 -67.891218) (xy 9.696436 -67.875921) (xy 9.798796 -67.868252)
			(xy 9.85012 -67.867784) (xy 9.901023 -67.868245) (xy 10.00255 -67.875789) (xy 10.103239 -67.890838)
			(xy 10.202535 -67.913308) (xy 10.299893 -67.943077) (xy 10.394776 -67.97998) (xy 10.486663 -68.023815)
			(xy 10.575047 -68.074339) (xy 10.659444 -68.131276) (xy 10.739389 -68.194313) (xy 10.814441 -68.263101)
			(xy 10.884187 -68.337263) (xy 10.948245 -68.416391) (xy 11.006262 -68.500049) (xy 11.03249 -68.543678)
			(xy 11.039348 -68.555362) (xy 11.062716 -68.56857) (xy 11.177524 -68.56857) (xy 11.200892 -68.555362)
			(xy 11.20775 -68.543678) (xy 11.233971 -68.500045) (xy 11.291989 -68.416388) (xy 11.356048 -68.337261)
			(xy 11.425796 -68.2631) (xy 11.500849 -68.194313) (xy 11.580794 -68.131277) (xy 11.665192 -68.074341)
			(xy 11.753577 -68.023817) (xy 11.845464 -67.979983) (xy 11.940347 -67.94308) (xy 12.037705 -67.913311)
			(xy 12.137001 -67.890841) (xy 12.23769 -67.875792) (xy 12.339217 -67.868247) (xy 12.39012 -67.867784)
			(xy 12.441443 -67.868253) (xy 12.462296 -67.869816) (xy 61.553852 -67.869816) (xy 61.554352 -67.818909)
			(xy 61.56234 -67.71741) (xy 61.578267 -67.61685) (xy 61.602035 -67.517849) (xy 61.633497 -67.421019)
			(xy 61.672459 -67.326956) (xy 61.718682 -67.236239) (xy 61.771879 -67.149429) (xy 61.831723 -67.06706)
			(xy 61.897846 -66.989641) (xy 61.969839 -66.917648) (xy 62.047258 -66.851525) (xy 62.129627 -66.791681)
			(xy 62.216437 -66.738484) (xy 62.307154 -66.692261) (xy 62.401217 -66.653299) (xy 62.498047 -66.621837)
			(xy 62.597048 -66.598069) (xy 62.697608 -66.582142) (xy 62.799107 -66.574154) (xy 62.900921 -66.574154)
			(xy 63.00242 -66.582142) (xy 63.10298 -66.598069) (xy 63.201981 -66.621837) (xy 63.298811 -66.653299)
			(xy 63.392874 -66.692261) (xy 63.483591 -66.738484) (xy 63.570401 -66.791681) (xy 63.65277 -66.851525)
			(xy 63.730189 -66.917648) (xy 63.802182 -66.989641) (xy 63.868305 -67.06706) (xy 63.928149 -67.149429)
			(xy 63.981346 -67.236239) (xy 64.027569 -67.326956) (xy 64.066531 -67.421019) (xy 64.097993 -67.517849)
			(xy 64.121761 -67.61685) (xy 64.137688 -67.71741) (xy 64.145676 -67.818909) (xy 64.146176 -67.869816)
			(xy 101.553772 -67.869816) (xy 101.554272 -67.818909) (xy 101.56226 -67.71741) (xy 101.578187 -67.61685)
			(xy 101.601955 -67.517849) (xy 101.633417 -67.421019) (xy 101.672379 -67.326956) (xy 101.718602 -67.236239)
			(xy 101.771799 -67.149429) (xy 101.831643 -67.06706) (xy 101.897766 -66.989641) (xy 101.969759 -66.917648)
			(xy 102.047178 -66.851525) (xy 102.129547 -66.791681) (xy 102.216357 -66.738484) (xy 102.307074 -66.692261)
			(xy 102.401137 -66.653299) (xy 102.497967 -66.621837) (xy 102.596968 -66.598069) (xy 102.697528 -66.582142)
			(xy 102.799027 -66.574154) (xy 102.900841 -66.574154) (xy 103.00234 -66.582142) (xy 103.1029 -66.598069)
			(xy 103.201901 -66.621837) (xy 103.298731 -66.653299) (xy 103.392794 -66.692261) (xy 103.483511 -66.738484)
			(xy 103.570321 -66.791681) (xy 103.65269 -66.851525) (xy 103.730109 -66.917648) (xy 103.802102 -66.989641)
			(xy 103.868225 -67.06706) (xy 103.928069 -67.149429) (xy 103.981266 -67.236239) (xy 104.027489 -67.326956)
			(xy 104.066451 -67.421019) (xy 104.097913 -67.517849) (xy 104.121681 -67.61685) (xy 104.137608 -67.71741)
			(xy 104.145596 -67.818909) (xy 104.146096 -67.869816) (xy 141.5542 -67.869816) (xy 141.554699 -67.818919)
			(xy 141.562686 -67.71744) (xy 141.57861 -67.616899) (xy 141.602373 -67.517918) (xy 141.633829 -67.421107)
			(xy 141.672784 -67.327062) (xy 141.718997 -67.236364) (xy 141.772184 -67.14957) (xy 141.832017 -67.067218)
			(xy 141.898126 -66.989813) (xy 141.970105 -66.917834) (xy 142.04751 -66.851725) (xy 142.129862 -66.791892)
			(xy 142.216656 -66.738705) (xy 142.307354 -66.692492) (xy 142.401399 -66.653537) (xy 142.49821 -66.622081)
			(xy 142.597191 -66.598318) (xy 142.697732 -66.582394) (xy 142.799211 -66.574407) (xy 142.901005 -66.574407)
			(xy 143.002484 -66.582394) (xy 143.103025 -66.598318) (xy 143.202006 -66.622081) (xy 143.298817 -66.653537)
			(xy 143.392862 -66.692492) (xy 143.48356 -66.738705) (xy 143.570354 -66.791892) (xy 143.652706 -66.851725)
			(xy 143.730111 -66.917834) (xy 143.80209 -66.989813) (xy 143.868199 -67.067218) (xy 143.928032 -67.14957)
			(xy 143.981219 -67.236364) (xy 144.027432 -67.327062) (xy 144.066387 -67.421107) (xy 144.097843 -67.517918)
			(xy 144.121606 -67.616899) (xy 144.13753 -67.71744) (xy 144.145517 -67.818919) (xy 144.146016 -67.869816)
			(xy 181.55412 -67.869816) (xy 181.55462 -67.818909) (xy 181.562608 -67.71741) (xy 181.578535 -67.61685)
			(xy 181.602303 -67.517849) (xy 181.633765 -67.421019) (xy 181.672727 -67.326956) (xy 181.71895 -67.236239)
			(xy 181.772147 -67.149429) (xy 181.831991 -67.06706) (xy 181.898114 -66.989641) (xy 181.970107 -66.917648)
			(xy 182.047526 -66.851525) (xy 182.129895 -66.791681) (xy 182.216705 -66.738484) (xy 182.307422 -66.692261)
			(xy 182.401485 -66.653299) (xy 182.498315 -66.621837) (xy 182.597316 -66.598069) (xy 182.697876 -66.582142)
			(xy 182.799375 -66.574154) (xy 182.901189 -66.574154) (xy 183.002688 -66.582142) (xy 183.103248 -66.598069)
			(xy 183.202249 -66.621837) (xy 183.299079 -66.653299) (xy 183.393142 -66.692261) (xy 183.483859 -66.738484)
			(xy 183.570669 -66.791681) (xy 183.653038 -66.851525) (xy 183.730457 -66.917648) (xy 183.80245 -66.989641)
			(xy 183.868573 -67.06706) (xy 183.928417 -67.149429) (xy 183.981614 -67.236239) (xy 184.027837 -67.326956)
			(xy 184.066799 -67.421019) (xy 184.098261 -67.517849) (xy 184.122029 -67.61685) (xy 184.137956 -67.71741)
			(xy 184.145944 -67.818909) (xy 184.146444 -67.869816) (xy 184.145789 -67.929021) (xy 184.134974 -68.046936)
			(xy 184.124854 -68.105274) (xy 184.122568 -68.117212) (xy 184.129172 -68.140072) (xy 184.201308 -68.217796)
			(xy 184.223406 -68.225924) (xy 184.235598 -68.224654) (xy 184.294095 -68.218798) (xy 184.411506 -68.212572)
			(xy 184.470294 -68.212208) (xy 184.537362 -68.212707) (xy 184.671248 -68.220881) (xy 184.804386 -68.237206)
			(xy 184.936281 -68.26162) (xy 185.066442 -68.294033) (xy 185.194383 -68.334324) (xy 185.319629 -68.382343)
			(xy 185.441713 -68.437912) (xy 185.56018 -68.500822) (xy 185.674591 -68.570841) (xy 185.784518 -68.647707)
			(xy 185.889552 -68.731135) (xy 185.989302 -68.820813) (xy 186.083398 -68.916407) (xy 186.171488 -69.017563)
			(xy 186.253245 -69.123903) (xy 186.29122 -69.179186) (xy 186.298332 -69.1896) (xy 186.32043 -69.201538)
			(xy 186.430158 -69.201538) (xy 186.452256 -69.1896) (xy 186.459368 -69.179186) (xy 186.497355 -69.12391)
			(xy 186.579103 -69.017561) (xy 186.667186 -68.916397) (xy 186.761276 -68.820795) (xy 186.861022 -68.731111)
			(xy 186.966054 -68.647678) (xy 187.07598 -68.570807) (xy 187.19039 -68.500785) (xy 187.308858 -68.437873)
			(xy 187.430944 -68.382304) (xy 187.556192 -68.334287) (xy 187.684136 -68.293999) (xy 187.814299 -68.26159)
			(xy 187.946196 -68.237182) (xy 188.079337 -68.220866) (xy 188.213225 -68.212701) (xy 188.280294 -68.212208)
			(xy 188.346684 -68.212667) (xy 188.479223 -68.220684) (xy 188.611036 -68.236689) (xy 188.741642 -68.260623)
			(xy 188.870565 -68.292399) (xy 188.997333 -68.331901) (xy 189.121486 -68.378986) (xy 189.242569 -68.433481)
			(xy 189.360141 -68.495187) (xy 189.473772 -68.563879) (xy 189.583049 -68.639307) (xy 189.687572 -68.721195)
			(xy 189.702736 -68.734629) (xy 270.306796 -68.734629) (xy 270.306796 -68.649907) (xy 270.314849 -68.56557)
			(xy 270.330883 -68.48238) (xy 270.354751 -68.40109) (xy 270.386239 -68.322438) (xy 270.425061 -68.247135)
			(xy 270.470864 -68.175863) (xy 270.523235 -68.109267) (xy 270.5817 -68.047952) (xy 270.645728 -67.992471)
			(xy 270.71474 -67.943328) (xy 270.78811 -67.900968) (xy 270.865175 -67.865773) (xy 270.945237 -67.838064)
			(xy 271.02757 -67.81809) (xy 271.111429 -67.806033) (xy 271.196054 -67.802002) (xy 271.280679 -67.806033)
			(xy 271.364538 -67.81809) (xy 271.446871 -67.838064) (xy 271.526933 -67.865773) (xy 271.603998 -67.900968)
			(xy 271.677368 -67.943328) (xy 271.74638 -67.992471) (xy 271.810408 -68.047952) (xy 271.868873 -68.109267)
			(xy 271.921244 -68.175863) (xy 271.967047 -68.247135) (xy 272.005869 -68.322438) (xy 272.037357 -68.40109)
			(xy 272.061225 -68.48238) (xy 272.077259 -68.56557) (xy 272.085312 -68.649907) (xy 272.085816 -68.692268)
			(xy 272.085312 -68.734629) (xy 272.077259 -68.818966) (xy 272.061225 -68.902156) (xy 272.037357 -68.983446)
			(xy 272.005869 -69.062098) (xy 271.967047 -69.137401) (xy 271.921244 -69.208673) (xy 271.868873 -69.275269)
			(xy 271.810408 -69.336584) (xy 271.74638 -69.392065) (xy 271.677368 -69.441208) (xy 271.603998 -69.483568)
			(xy 271.526933 -69.518763) (xy 271.446871 -69.546472) (xy 271.364538 -69.566446) (xy 271.280679 -69.578503)
			(xy 271.196054 -69.582535) (xy 271.111429 -69.578503) (xy 271.02757 -69.566446) (xy 270.945237 -69.546472)
			(xy 270.865175 -69.518763) (xy 270.78811 -69.483568) (xy 270.71474 -69.441208) (xy 270.645728 -69.392065)
			(xy 270.5817 -69.336584) (xy 270.523235 -69.275269) (xy 270.470864 -69.208673) (xy 270.425061 -69.137401)
			(xy 270.386239 -69.062098) (xy 270.354751 -68.983446) (xy 270.330883 -68.902156) (xy 270.314849 -68.818966)
			(xy 270.306796 -68.734629) (xy 189.702736 -68.734629) (xy 189.78696 -68.809245) (xy 189.880851 -68.903136)
			(xy 189.968901 -69.002523) (xy 190.050789 -69.107046) (xy 190.126218 -69.216323) (xy 190.19491 -69.329954)
			(xy 190.256617 -69.447526) (xy 190.311112 -69.568609) (xy 190.358197 -69.692761) (xy 190.397699 -69.81953)
			(xy 190.429476 -69.948452) (xy 190.453411 -70.079058) (xy 190.469047 -70.207829) (xy 268.757142 -70.207829)
			(xy 268.757142 -70.123107) (xy 268.765195 -70.03877) (xy 268.781229 -69.95558) (xy 268.805097 -69.87429)
			(xy 268.836585 -69.795638) (xy 268.875407 -69.720335) (xy 268.92121 -69.649063) (xy 268.973581 -69.582467)
			(xy 269.032046 -69.521152) (xy 269.096074 -69.465671) (xy 269.165086 -69.416528) (xy 269.238456 -69.374168)
			(xy 269.315521 -69.338973) (xy 269.395583 -69.311264) (xy 269.477916 -69.29129) (xy 269.561775 -69.279233)
			(xy 269.6464 -69.275202) (xy 269.731025 -69.279233) (xy 269.814884 -69.29129) (xy 269.897217 -69.311264)
			(xy 269.977279 -69.338973) (xy 270.054344 -69.374168) (xy 270.127714 -69.416528) (xy 270.196726 -69.465671)
			(xy 270.260754 -69.521152) (xy 270.319219 -69.582467) (xy 270.37159 -69.649063) (xy 270.417393 -69.720335)
			(xy 270.456215 -69.795638) (xy 270.487703 -69.87429) (xy 270.511571 -69.95558) (xy 270.527605 -70.03877)
			(xy 270.535658 -70.123107) (xy 270.536162 -70.165468) (xy 270.535658 -70.207829) (xy 270.527605 -70.292166)
			(xy 270.511571 -70.375356) (xy 270.487703 -70.456646) (xy 270.456215 -70.535298) (xy 270.417393 -70.610601)
			(xy 270.37159 -70.681873) (xy 270.319219 -70.748469) (xy 270.260754 -70.809784) (xy 270.196726 -70.865265)
			(xy 270.127714 -70.914408) (xy 270.054344 -70.956768) (xy 269.977279 -70.991963) (xy 269.897217 -71.019672)
			(xy 269.814884 -71.039646) (xy 269.731025 -71.051703) (xy 269.6464 -71.055735) (xy 269.561775 -71.051703)
			(xy 269.477916 -71.039646) (xy 269.395583 -71.019672) (xy 269.315521 -70.991963) (xy 269.238456 -70.956768)
			(xy 269.165086 -70.914408) (xy 269.096074 -70.865265) (xy 269.032046 -70.809784) (xy 268.973581 -70.748469)
			(xy 268.92121 -70.681873) (xy 268.875407 -70.610601) (xy 268.836585 -70.535298) (xy 268.805097 -70.456646)
			(xy 268.781229 -70.375356) (xy 268.765195 -70.292166) (xy 268.757142 -70.207829) (xy 190.469047 -70.207829)
			(xy 190.469416 -70.210871) (xy 190.477433 -70.34341) (xy 190.477433 -70.47619) (xy 190.469416 -70.608729)
			(xy 190.453411 -70.740542) (xy 190.429476 -70.871148) (xy 190.397699 -71.00007) (xy 190.358197 -71.126839)
			(xy 190.311112 -71.250991) (xy 190.256617 -71.372074) (xy 190.19491 -71.489646) (xy 190.126218 -71.603277)
			(xy 190.050789 -71.712554) (xy 189.968901 -71.817077) (xy 189.880851 -71.916464) (xy 189.78696 -72.010355)
			(xy 189.687572 -72.098405) (xy 189.583049 -72.180293) (xy 189.473772 -72.255721) (xy 189.360141 -72.324413)
			(xy 189.242569 -72.386119) (xy 189.121486 -72.440614) (xy 188.997333 -72.487699) (xy 188.870565 -72.527201)
			(xy 188.741642 -72.558977) (xy 188.611036 -72.582911) (xy 188.479223 -72.598916) (xy 188.346684 -72.606933)
			(xy 188.280294 -72.607424) (xy 188.213225 -72.606965) (xy 188.079338 -72.598789) (xy 187.946198 -72.582463)
			(xy 187.814302 -72.558047) (xy 187.684141 -72.525633) (xy 187.556198 -72.485339) (xy 187.430952 -72.437318)
			(xy 187.308867 -72.381747) (xy 187.1904 -72.318834) (xy 187.075989 -72.248812) (xy 186.966063 -72.171943)
			(xy 186.861029 -72.088513) (xy 186.76128 -71.998831) (xy 186.667185 -71.903233) (xy 186.579097 -71.802074)
			(xy 186.497342 -71.695731) (xy 186.459368 -71.640446) (xy 186.452256 -71.630032) (xy 186.430158 -71.618094)
			(xy 186.32043 -71.618094) (xy 186.298332 -71.630032) (xy 186.29122 -71.640446) (xy 186.253252 -71.695735)
			(xy 186.171502 -71.802083) (xy 186.083417 -71.903246) (xy 185.989326 -71.998848) (xy 185.889577 -72.088531)
			(xy 185.784544 -72.171964) (xy 185.674617 -72.248833) (xy 185.560206 -72.318854) (xy 185.441736 -72.381766)
			(xy 185.319649 -72.437333) (xy 185.194401 -72.48535) (xy 185.066456 -72.525637) (xy 184.936292 -72.558045)
			(xy 184.804393 -72.582452) (xy 184.671252 -72.598768) (xy 184.537363 -72.606931) (xy 184.470294 -72.607424)
			(xy 184.403901 -72.606967) (xy 184.271357 -72.598949) (xy 184.139539 -72.582944) (xy 184.008927 -72.55901)
			(xy 183.879999 -72.527234) (xy 183.753224 -72.487732) (xy 183.629066 -72.440648) (xy 183.507977 -72.386153)
			(xy 183.390399 -72.324448) (xy 183.276761 -72.255756) (xy 183.167477 -72.180329) (xy 183.062946 -72.098441)
			(xy 182.963551 -72.010392) (xy 182.869652 -71.916502) (xy 182.781593 -71.817115) (xy 182.699696 -71.712592)
			(xy 182.624258 -71.603316) (xy 182.555555 -71.489684) (xy 182.493839 -71.372112) (xy 182.439333 -71.251028)
			(xy 182.392237 -71.126874) (xy 182.352723 -71.000103) (xy 182.320934 -70.871178) (xy 182.296987 -70.740569)
			(xy 182.28097 -70.608752) (xy 182.27294 -70.476209) (xy 182.272432 -70.409816) (xy 182.27291 -70.34359)
			(xy 182.280893 -70.211378) (xy 182.296826 -70.079888) (xy 182.32065 -69.949596) (xy 182.35228 -69.820975)
			(xy 182.391599 -69.694494) (xy 182.438466 -69.57061) (xy 182.49271 -69.449775) (xy 182.554135 -69.332426)
			(xy 182.5879 -69.275452) (xy 182.59425 -69.265038) (xy 182.596028 -69.241416) (xy 182.555896 -69.143372)
			(xy 182.538116 -69.127878) (xy 182.526178 -69.124576) (xy 182.477646 -69.111541) (xy 182.382574 -69.078966)
			(xy 182.290311 -69.039123) (xy 182.201411 -68.992253) (xy 182.116409 -68.938637) (xy 182.035816 -68.878598)
			(xy 181.960117 -68.812496) (xy 181.889765 -68.740729) (xy 181.825184 -68.663727) (xy 181.766762 -68.581954)
			(xy 181.71485 -68.495901) (xy 181.66976 -68.406086) (xy 181.631763 -68.313047) (xy 181.601088 -68.217345)
			(xy 181.577918 -68.119554) (xy 181.562394 -68.020262) (xy 181.554607 -67.920065) (xy 181.55412 -67.869816)
			(xy 144.146016 -67.869816) (xy 144.145413 -67.929016) (xy 144.134729 -68.04693) (xy 144.12468 -68.105274)
			(xy 144.122394 -68.117212) (xy 144.128998 -68.140072) (xy 144.201134 -68.217796) (xy 144.223232 -68.225924)
			(xy 144.235424 -68.224654) (xy 144.293921 -68.218796) (xy 144.411332 -68.212571) (xy 144.47012 -68.212208)
			(xy 144.537188 -68.212686) (xy 144.671075 -68.220862) (xy 144.804214 -68.237188) (xy 144.936109 -68.261604)
			(xy 145.066269 -68.294019) (xy 145.194211 -68.334311) (xy 145.319457 -68.382332) (xy 145.441541 -68.437901)
			(xy 145.560008 -68.500813) (xy 145.674419 -68.570833) (xy 145.784345 -68.647701) (xy 145.889379 -68.73113)
			(xy 145.98913 -68.820809) (xy 146.083225 -68.916405) (xy 146.171315 -69.017562) (xy 146.253071 -69.123902)
			(xy 146.291046 -69.179186) (xy 146.298158 -69.1896) (xy 146.320256 -69.201538) (xy 146.429984 -69.201538)
			(xy 146.452082 -69.1896) (xy 146.459194 -69.179186) (xy 146.497163 -69.123898) (xy 146.578913 -69.017549)
			(xy 146.666997 -68.916385) (xy 146.761088 -68.820783) (xy 146.860836 -68.731099) (xy 146.965869 -68.647667)
			(xy 147.075796 -68.570797) (xy 147.190207 -68.500775) (xy 147.308677 -68.437864) (xy 147.430764 -68.382296)
			(xy 147.556013 -68.334279) (xy 147.683957 -68.293992) (xy 147.814122 -68.261585) (xy 147.94602 -68.237179)
			(xy 148.079162 -68.220863) (xy 148.213051 -68.2127) (xy 148.28012 -68.212208) (xy 148.34651 -68.212678)
			(xy 148.479047 -68.220696) (xy 148.610858 -68.236702) (xy 148.741462 -68.260637) (xy 148.870383 -68.292414)
			(xy 148.99715 -68.331918) (xy 149.1213 -68.379003) (xy 149.242381 -68.433498) (xy 149.359951 -68.495204)
			(xy 149.473581 -68.563897) (xy 149.582855 -68.639324) (xy 149.687377 -68.721212) (xy 149.786763 -68.809262)
			(xy 149.880652 -68.903152) (xy 149.9687 -69.002539) (xy 150.050587 -69.107061) (xy 150.126014 -69.216336)
			(xy 150.194706 -69.329966) (xy 150.256411 -69.447537) (xy 150.310905 -69.568618) (xy 150.357989 -69.692769)
			(xy 150.397491 -69.819537) (xy 150.429267 -69.948458) (xy 150.453201 -70.079062) (xy 150.469206 -70.210873)
			(xy 150.477223 -70.34341) (xy 150.477223 -70.47619) (xy 150.469206 -70.608727) (xy 150.453201 -70.740538)
			(xy 150.429267 -70.871142) (xy 150.397491 -71.000063) (xy 150.357989 -71.126831) (xy 150.310905 -71.250982)
			(xy 150.256411 -71.372063) (xy 150.194706 -71.489634) (xy 150.126014 -71.603264) (xy 150.050587 -71.712539)
			(xy 149.9687 -71.817061) (xy 149.880652 -71.916448) (xy 149.786763 -72.010338) (xy 149.687377 -72.098388)
			(xy 149.582855 -72.180276) (xy 149.473581 -72.255703) (xy 149.359951 -72.324396) (xy 149.242381 -72.386102)
			(xy 149.1213 -72.440597) (xy 148.99715 -72.487682) (xy 148.870383 -72.527186) (xy 148.741462 -72.558963)
			(xy 148.610858 -72.582898) (xy 148.479047 -72.598904) (xy 148.34651 -72.606922) (xy 148.28012 -72.607424)
			(xy 148.213052 -72.606944) (xy 148.079165 -72.59877) (xy 147.946025 -72.582446) (xy 147.81413 -72.558031)
			(xy 147.683968 -72.525618) (xy 147.556026 -72.485326) (xy 147.43078 -72.437306) (xy 147.308695 -72.381737)
			(xy 147.190228 -72.318825) (xy 147.075817 -72.248805) (xy 146.96589 -72.171937) (xy 146.860857 -72.088508)
			(xy 146.761107 -71.998827) (xy 146.667012 -71.90323) (xy 146.578923 -71.802072) (xy 146.497168 -71.69573)
			(xy 146.459194 -71.640446) (xy 146.452082 -71.630032) (xy 146.429984 -71.618094) (xy 146.320256 -71.618094)
			(xy 146.298158 -71.630032) (xy 146.291046 -71.640446) (xy 146.253061 -71.695723) (xy 146.171312 -71.802071)
			(xy 146.083229 -71.903234) (xy 145.989138 -71.998836) (xy 145.889391 -72.08852) (xy 145.784359 -72.171952)
			(xy 145.674433 -72.248823) (xy 145.560023 -72.318844) (xy 145.441555 -72.381756) (xy 145.319469 -72.437325)
			(xy 145.194221 -72.485343) (xy 145.066278 -72.525631) (xy 144.936115 -72.55804) (xy 144.804217 -72.582448)
			(xy 144.671077 -72.598765) (xy 144.537189 -72.606931) (xy 144.47012 -72.607424) (xy 144.403731 -72.606897)
			(xy 144.271194 -72.598882) (xy 144.139383 -72.582878) (xy 144.008779 -72.558945) (xy 143.879859 -72.52717)
			(xy 143.753092 -72.487669) (xy 143.628941 -72.440586) (xy 143.50786 -72.386093) (xy 143.39029 -72.324389)
			(xy 143.27666 -72.255699) (xy 143.167384 -72.180273) (xy 143.062862 -72.098386) (xy 142.963475 -72.010339)
			(xy 142.869586 -71.916451) (xy 142.781537 -71.817065) (xy 142.699649 -71.712545) (xy 142.624221 -71.603271)
			(xy 142.555529 -71.489642) (xy 142.493822 -71.372072) (xy 142.439327 -71.250992) (xy 142.392242 -71.126842)
			(xy 142.352739 -71.000076) (xy 142.320962 -70.871156) (xy 142.297027 -70.740552) (xy 142.281022 -70.608742)
			(xy 142.273004 -70.476205) (xy 142.272512 -70.409816) (xy 142.272989 -70.343594) (xy 142.280942 -70.211388)
			(xy 142.296845 -70.079902) (xy 142.320639 -69.949613) (xy 142.352238 -69.820993) (xy 142.391527 -69.694511)
			(xy 142.438365 -69.570624) (xy 142.492579 -69.449784) (xy 142.553975 -69.33243) (xy 142.587726 -69.275452)
			(xy 142.594076 -69.265038) (xy 142.595854 -69.241416) (xy 142.555722 -69.143372) (xy 142.537942 -69.127878)
			(xy 142.526004 -69.124576) (xy 142.477475 -69.111555) (xy 142.382423 -69.078958) (xy 142.29018 -69.039098)
			(xy 142.201302 -68.992213) (xy 142.116322 -68.938586) (xy 142.03575 -68.878538) (xy 141.960071 -68.81243)
			(xy 141.88974 -68.740659) (xy 141.825178 -68.663658) (xy 141.766774 -68.581887) (xy 141.714878 -68.495838)
			(xy 141.669802 -68.406029) (xy 141.631818 -68.312998) (xy 141.601152 -68.217305) (xy 141.57799 -68.119525)
			(xy 141.562471 -68.020244) (xy 141.554687 -67.920059) (xy 141.5542 -67.869816) (xy 104.146096 -67.869816)
			(xy 104.14544 -67.929021) (xy 104.134626 -68.046936) (xy 104.124506 -68.105274) (xy 104.12222 -68.117212)
			(xy 104.128824 -68.140072) (xy 104.20096 -68.217796) (xy 104.223058 -68.225924) (xy 104.23525 -68.224654)
			(xy 104.293747 -68.218802) (xy 104.411158 -68.212573) (xy 104.469946 -68.212208) (xy 104.537013 -68.212745)
			(xy 104.670898 -68.220917) (xy 104.804036 -68.237238) (xy 104.93593 -68.26165) (xy 105.06609 -68.29406)
			(xy 105.194031 -68.334348) (xy 105.319277 -68.382365) (xy 105.441361 -68.43793) (xy 105.559829 -68.500839)
			(xy 105.674239 -68.570855) (xy 105.784166 -68.647719) (xy 105.889201 -68.731144) (xy 105.988952 -68.82082)
			(xy 106.083048 -68.916412) (xy 106.171139 -69.017566) (xy 106.252896 -69.123904) (xy 106.290872 -69.179186)
			(xy 106.297984 -69.1896) (xy 106.320082 -69.201538) (xy 106.42981 -69.201538) (xy 106.451908 -69.1896)
			(xy 106.45902 -69.179186) (xy 106.496972 -69.123886) (xy 106.578722 -69.017537) (xy 106.666808 -68.916373)
			(xy 106.7609 -68.820772) (xy 106.86065 -68.731088) (xy 106.965684 -68.647656) (xy 107.075612 -68.570786)
			(xy 107.190025 -68.500765) (xy 107.308495 -68.437855) (xy 107.430583 -68.382288) (xy 107.555833 -68.334272)
			(xy 107.683779 -68.293986) (xy 107.813945 -68.26158) (xy 107.945844 -68.237175) (xy 108.078987 -68.220861)
			(xy 108.212877 -68.212699) (xy 108.279946 -68.212208) (xy 108.346561 -68.21269) (xy 108.479549 -68.220738)
			(xy 108.611805 -68.236826) (xy 108.742843 -68.260895) (xy 108.872183 -68.292856) (xy 108.99935 -68.332592)
			(xy 109.123877 -68.379958) (xy 109.245307 -68.434779) (xy 109.363193 -68.496853) (xy 109.420406 -68.530978)
			(xy 109.42955 -68.536566) (xy 109.450632 -68.53936) (xy 109.543088 -68.512436) (xy 109.559598 -68.49872)
			(xy 109.56417 -68.489068) (xy 109.58283 -68.45221) (xy 109.625989 -68.381762) (xy 109.675492 -68.315617)
			(xy 109.730913 -68.254346) (xy 109.791775 -68.198475) (xy 109.857554 -68.148486) (xy 109.927683 -68.10481)
			(xy 110.001559 -68.067822) (xy 110.078545 -68.037842) (xy 110.157978 -68.015126) (xy 110.239175 -67.999871)
			(xy 110.321437 -67.992208) (xy 110.362746 -67.991736) (xy 110.405055 -67.992204) (xy 110.489292 -68.000211)
			(xy 110.572388 -68.016178) (xy 110.653594 -68.039959) (xy 110.732177 -68.071342) (xy 110.807426 -68.110041)
			(xy 110.843314 -68.132452) (xy 110.851703 -68.137335) (xy 110.870746 -68.141006) (xy 110.889789 -68.137335)
			(xy 110.898178 -68.132452) (xy 110.934072 -68.110048) (xy 111.009313 -68.071332) (xy 111.087892 -68.039941)
			(xy 111.169099 -68.01616) (xy 111.252198 -68.000202) (xy 111.336437 -67.992213) (xy 111.378746 -67.991736)
			(xy 111.421055 -67.992204) (xy 111.505292 -68.000211) (xy 111.588388 -68.016178) (xy 111.669594 -68.039959)
			(xy 111.748177 -68.071342) (xy 111.823426 -68.110041) (xy 111.859314 -68.132452) (xy 111.867703 -68.137335)
			(xy 111.886746 -68.141006) (xy 111.905789 -68.137335) (xy 111.914178 -68.132452) (xy 111.950072 -68.110048)
			(xy 112.025313 -68.071332) (xy 112.103892 -68.039941) (xy 112.185099 -68.01616) (xy 112.268198 -68.000202)
			(xy 112.352437 -67.992213) (xy 112.394746 -67.991736) (xy 112.435853 -67.992169) (xy 112.517717 -67.999757)
			(xy 112.598532 -68.014865) (xy 112.677609 -68.037364) (xy 112.754273 -68.067061) (xy 112.827871 -68.103704)
			(xy 112.897774 -68.146979) (xy 112.963387 -68.196519) (xy 113.024151 -68.251901) (xy 113.079547 -68.312651)
			(xy 113.129102 -68.378253) (xy 113.172394 -68.448146) (xy 113.209054 -68.521735) (xy 113.23877 -68.598392)
			(xy 113.261287 -68.677463) (xy 113.276414 -68.758274) (xy 113.284022 -68.840137) (xy 113.284508 -68.881244)
			(xy 113.284026 -68.923559) (xy 113.275992 -69.007808) (xy 113.25999 -69.090912) (xy 113.236165 -69.17212)
			(xy 113.204733 -69.250697) (xy 113.165978 -69.325933) (xy 113.143538 -69.361812) (xy 113.138619 -69.370183)
			(xy 113.134959 -69.389237) (xy 113.138646 -69.408287) (xy 113.143538 -69.416676) (xy 113.166016 -69.452532)
			(xy 113.204764 -69.527773) (xy 113.236192 -69.606354) (xy 113.260013 -69.687564) (xy 113.276014 -69.770671)
			(xy 113.284049 -69.854921) (xy 113.284045 -69.939553) (xy 113.276003 -70.023803) (xy 113.259996 -70.106908)
			(xy 113.236167 -70.188116) (xy 113.204734 -70.266695) (xy 113.165979 -70.341932) (xy 113.143538 -70.377812)
			(xy 113.138619 -70.386183) (xy 113.134959 -70.405237) (xy 113.138646 -70.424287) (xy 113.143538 -70.432676)
			(xy 113.166016 -70.468532) (xy 113.204764 -70.543773) (xy 113.236192 -70.622354) (xy 113.260013 -70.703564)
			(xy 113.276014 -70.786671) (xy 113.284049 -70.870921) (xy 113.284045 -70.955553) (xy 113.276003 -71.039803)
			(xy 113.259996 -71.122908) (xy 113.236167 -71.204116) (xy 113.204734 -71.282695) (xy 113.165979 -71.357932)
			(xy 113.143538 -71.393812) (xy 113.138619 -71.402183) (xy 113.134959 -71.421237) (xy 113.138646 -71.440287)
			(xy 113.143538 -71.448676) (xy 113.165961 -71.484564) (xy 113.204707 -71.559802) (xy 113.236134 -71.638378)
			(xy 113.259957 -71.719584) (xy 113.275962 -71.802685) (xy 113.284004 -71.88693) (xy 113.284508 -71.929244)
			(xy 113.28409 -71.970355) (xy 113.276498 -72.052227) (xy 113.261383 -72.133048) (xy 113.238875 -72.21213)
			(xy 113.209164 -72.288798) (xy 113.172506 -72.362396) (xy 113.129212 -72.432297) (xy 113.079652 -72.497905)
			(xy 113.024249 -72.55866) (xy 112.963476 -72.614042) (xy 112.897851 -72.66358) (xy 112.827936 -72.706851)
			(xy 112.754325 -72.743485) (xy 112.677648 -72.773169) (xy 112.598558 -72.795651) (xy 112.517732 -72.810739)
			(xy 112.435857 -72.818303) (xy 112.394746 -72.818752) (xy 112.352437 -72.81829) (xy 112.2682 -72.810282)
			(xy 112.185103 -72.794314) (xy 112.103897 -72.770532) (xy 112.025315 -72.739148) (xy 111.950066 -72.700448)
			(xy 111.914178 -72.678036) (xy 111.905789 -72.673153) (xy 111.886746 -72.669482) (xy 111.867703 -72.673153)
			(xy 111.859314 -72.678036) (xy 111.823421 -72.700442) (xy 111.74818 -72.739158) (xy 111.669601 -72.770548)
			(xy 111.588394 -72.79433) (xy 111.505295 -72.810287) (xy 111.421055 -72.818276) (xy 111.378746 -72.818752)
			(xy 111.336437 -72.81829) (xy 111.2522 -72.810282) (xy 111.169103 -72.794314) (xy 111.087897 -72.770532)
			(xy 111.009315 -72.739148) (xy 110.934066 -72.700448) (xy 110.898178 -72.678036) (xy 110.889789 -72.673153)
			(xy 110.870746 -72.669482) (xy 110.851703 -72.673153) (xy 110.843314 -72.678036) (xy 110.807421 -72.700442)
			(xy 110.73218 -72.739158) (xy 110.653601 -72.770548) (xy 110.572394 -72.79433) (xy 110.489295 -72.810287)
			(xy 110.405055 -72.818276) (xy 110.362746 -72.818752) (xy 110.321736 -72.818307) (xy 110.240064 -72.81076)
			(xy 110.159434 -72.795726) (xy 110.08053 -72.773333) (xy 110.004023 -72.74377) (xy 109.930563 -72.70729)
			(xy 109.860773 -72.664201) (xy 109.795246 -72.614871) (xy 109.734539 -72.559717) (xy 109.679168 -72.499208)
			(xy 109.629603 -72.433859) (xy 109.586264 -72.364224) (xy 109.567472 -72.32777) (xy 109.562392 -72.318118)
			(xy 109.54639 -72.304656) (xy 109.45368 -72.277986) (xy 109.432852 -72.28078) (xy 109.423708 -72.286622)
			(xy 109.366375 -72.320967) (xy 109.24821 -72.383438) (xy 109.126467 -72.438611) (xy 109.001595 -72.486281)
			(xy 108.874056 -72.526273) (xy 108.744322 -72.558439) (xy 108.612872 -72.58266) (xy 108.480194 -72.598845)
			(xy 108.346777 -72.606936) (xy 108.279946 -72.607424) (xy 108.212878 -72.606923) (xy 108.078991 -72.598751)
			(xy 107.945853 -72.582428) (xy 107.813957 -72.558015) (xy 107.683796 -72.525603) (xy 107.555854 -72.485313)
			(xy 107.430608 -72.437295) (xy 107.308524 -72.381727) (xy 107.190056 -72.318816) (xy 107.075645 -72.248797)
			(xy 106.965718 -72.171931) (xy 106.860684 -72.088503) (xy 106.760934 -71.998824) (xy 106.666839 -71.903228)
			(xy 106.57875 -71.802071) (xy 106.496994 -71.69573) (xy 106.45902 -71.640446) (xy 106.451908 -71.630032)
			(xy 106.42981 -71.618094) (xy 106.320082 -71.618094) (xy 106.297984 -71.630032) (xy 106.290872 -71.640446)
			(xy 106.25287 -71.695711) (xy 106.171122 -71.802059) (xy 106.08304 -71.903222) (xy 105.98895 -71.998824)
			(xy 105.889205 -72.088508) (xy 105.784174 -72.171941) (xy 105.674249 -72.248812) (xy 105.55984 -72.318834)
			(xy 105.441373 -72.381747) (xy 105.319289 -72.437317) (xy 105.194042 -72.485335) (xy 105.0661 -72.525625)
			(xy 104.935938 -72.558035) (xy 104.804041 -72.582444) (xy 104.670901 -72.598763) (xy 104.537014 -72.60693)
			(xy 104.469946 -72.607424) (xy 104.403553 -72.606916) (xy 104.27101 -72.598902) (xy 104.139193 -72.5829)
			(xy 104.008582 -72.558969) (xy 103.879654 -72.527195) (xy 103.75288 -72.487696) (xy 103.628722 -72.440614)
			(xy 103.507633 -72.386123) (xy 103.390055 -72.32442) (xy 103.276417 -72.25573) (xy 103.167133 -72.180305)
			(xy 103.062602 -72.09842) (xy 102.963206 -72.010373) (xy 102.869307 -71.916485) (xy 102.781248 -71.817099)
			(xy 102.69935 -71.712578) (xy 102.623912 -71.603304) (xy 102.555209 -71.489673) (xy 102.493492 -71.372103)
			(xy 102.438986 -71.25102) (xy 102.39189 -71.126868) (xy 102.352375 -71.000098) (xy 102.320586 -70.871174)
			(xy 102.296639 -70.740566) (xy 102.280622 -70.608751) (xy 102.272592 -70.476209) (xy 102.272084 -70.409816)
			(xy 102.272569 -70.34359) (xy 102.280552 -70.211379) (xy 102.296484 -70.079888) (xy 102.320308 -69.949596)
			(xy 102.351937 -69.820976) (xy 102.391256 -69.694495) (xy 102.438121 -69.570611) (xy 102.492364 -69.449775)
			(xy 102.553787 -69.332426) (xy 102.587552 -69.275452) (xy 102.593902 -69.265038) (xy 102.59568 -69.241416)
			(xy 102.555548 -69.143372) (xy 102.537768 -69.127878) (xy 102.52583 -69.124576) (xy 102.477308 -69.111506)
			(xy 102.382235 -69.078934) (xy 102.289972 -69.039095) (xy 102.201072 -68.992228) (xy 102.116069 -68.938615)
			(xy 102.035476 -68.878579) (xy 101.959775 -68.81248) (xy 101.889422 -68.740715) (xy 101.82484 -68.663715)
			(xy 101.766417 -68.581944) (xy 101.714505 -68.495893) (xy 101.669414 -68.406079) (xy 101.631417 -68.313042)
			(xy 101.600741 -68.217341) (xy 101.577571 -68.119551) (xy 101.562046 -68.02026) (xy 101.554259 -67.920065)
			(xy 101.553772 -67.869816) (xy 64.146176 -67.869816) (xy 64.14552 -67.929021) (xy 64.134706 -68.046936)
			(xy 64.124586 -68.105274) (xy 64.1223 -68.117212) (xy 64.128904 -68.140072) (xy 64.20104 -68.217796)
			(xy 64.223138 -68.225924) (xy 64.23533 -68.224654) (xy 64.293827 -68.218795) (xy 64.411238 -68.212571)
			(xy 64.470026 -68.212208) (xy 64.537093 -68.212761) (xy 64.670978 -68.220931) (xy 64.804115 -68.237252)
			(xy 64.936009 -68.261662) (xy 65.066169 -68.294071) (xy 65.19411 -68.334358) (xy 65.319355 -68.382374)
			(xy 65.441439 -68.437938) (xy 65.559907 -68.500845) (xy 65.674318 -68.570861) (xy 65.784245 -68.647723)
			(xy 65.88928 -68.731148) (xy 65.989031 -68.820822) (xy 66.083128 -68.916414) (xy 66.171219 -69.017567)
			(xy 66.252976 -69.123904) (xy 66.290952 -69.179186) (xy 66.298064 -69.1896) (xy 66.320162 -69.201538)
			(xy 66.42989 -69.201538) (xy 66.451988 -69.1896) (xy 66.4591 -69.179186) (xy 66.497065 -69.123895)
			(xy 66.578815 -69.017546) (xy 66.666899 -68.916383) (xy 66.760991 -68.820781) (xy 66.860739 -68.731096)
			(xy 66.965772 -68.647664) (xy 67.0757 -68.570794) (xy 67.190111 -68.500773) (xy 67.308581 -68.437862)
			(xy 67.430668 -68.382294) (xy 67.555917 -68.334278) (xy 67.683863 -68.293991) (xy 67.814027 -68.261584)
			(xy 67.945926 -68.237178) (xy 68.079068 -68.220863) (xy 68.212957 -68.2127) (xy 68.280026 -68.212208)
			(xy 68.348503 -68.212702) (xy 68.485191 -68.22123) (xy 68.621084 -68.238252) (xy 68.755653 -68.263701)
			(xy 68.888376 -68.29748) (xy 69.018739 -68.339456) (xy 69.146235 -68.389467) (xy 69.270371 -68.447318)
			(xy 69.390664 -68.512787) (xy 69.448934 -68.548758) (xy 69.458332 -68.5546) (xy 69.480176 -68.557394)
			(xy 69.575426 -68.52793) (xy 69.591682 -68.512944) (xy 69.596254 -68.502784) (xy 69.613781 -68.463304)
			(xy 69.655415 -68.387612) (xy 69.704189 -68.316312) (xy 69.759644 -68.250076) (xy 69.821258 -68.189526)
			(xy 69.88845 -68.135232) (xy 69.960589 -68.087708) (xy 70.036994 -68.047398) (xy 70.116946 -68.014684)
			(xy 70.199693 -67.989873) (xy 70.284454 -67.9732) (xy 70.370433 -67.96482) (xy 70.413626 -67.964304)
			(xy 70.455934 -67.964787) (xy 70.540171 -67.972792) (xy 70.623267 -67.988756) (xy 70.704473 -68.012535)
			(xy 70.783056 -68.043914) (xy 70.858305 -68.08261) (xy 70.894194 -68.10502) (xy 70.902583 -68.109903)
			(xy 70.921626 -68.113574) (xy 70.940669 -68.109903) (xy 70.949058 -68.10502) (xy 70.984929 -68.082579)
			(xy 71.060175 -68.043869) (xy 71.13876 -68.012484) (xy 71.219971 -67.988709) (xy 71.303073 -67.972759)
			(xy 71.387316 -67.964777) (xy 71.429626 -67.964304) (xy 71.471934 -67.964787) (xy 71.556171 -67.972792)
			(xy 71.639267 -67.988756) (xy 71.720473 -68.012535) (xy 71.799056 -68.043914) (xy 71.874305 -68.08261)
			(xy 71.910194 -68.10502) (xy 71.918583 -68.109903) (xy 71.937626 -68.113574) (xy 71.956669 -68.109903)
			(xy 71.965058 -68.10502) (xy 72.000929 -68.082579) (xy 72.076175 -68.043869) (xy 72.15476 -68.012484)
			(xy 72.235971 -67.988709) (xy 72.319073 -67.972759) (xy 72.403316 -67.964777) (xy 72.445626 -67.964304)
			(xy 72.486732 -67.964788) (xy 72.568594 -67.972374) (xy 72.649407 -67.987479) (xy 72.728481 -68.009975)
			(xy 72.805144 -68.03967) (xy 72.87874 -68.076309) (xy 72.948642 -68.119582) (xy 73.014255 -68.169118)
			(xy 73.075018 -68.224496) (xy 73.130414 -68.285243) (xy 73.17997 -68.350841) (xy 73.223263 -68.420731)
			(xy 73.259924 -68.494317) (xy 73.289641 -68.57097) (xy 73.312161 -68.650038) (xy 73.32729 -68.730847)
			(xy 73.3349 -68.812706) (xy 73.335388 -68.853812) (xy 73.334894 -68.896127) (xy 73.326862 -68.980375)
			(xy 73.310862 -69.063479) (xy 73.28704 -69.144687) (xy 73.25561 -69.223265) (xy 73.216858 -69.298501)
			(xy 73.194418 -69.33438) (xy 73.189526 -69.342764) (xy 73.185859 -69.36181) (xy 73.189534 -69.380855)
			(xy 73.194418 -69.389244) (xy 73.216868 -69.425117) (xy 73.255619 -69.500355) (xy 73.287048 -69.578933)
			(xy 73.310873 -69.660142) (xy 73.326876 -69.743246) (xy 73.334913 -69.827495) (xy 73.334912 -69.912126)
			(xy 73.326873 -69.996374) (xy 73.310868 -70.079478) (xy 73.287042 -70.160686) (xy 73.25561 -70.239264)
			(xy 73.216857 -70.314501) (xy 73.194418 -70.35038) (xy 73.189526 -70.358764) (xy 73.185859 -70.37781)
			(xy 73.189534 -70.396855) (xy 73.194418 -70.405244) (xy 73.216868 -70.441117) (xy 73.255619 -70.516355)
			(xy 73.287048 -70.594933) (xy 73.310873 -70.676142) (xy 73.326876 -70.759246) (xy 73.334913 -70.843495)
			(xy 73.334912 -70.928126) (xy 73.326873 -71.012374) (xy 73.310868 -71.095478) (xy 73.287042 -71.176686)
			(xy 73.25561 -71.255264) (xy 73.216857 -71.330501) (xy 73.194418 -71.36638) (xy 73.189526 -71.374764)
			(xy 73.185859 -71.39381) (xy 73.189534 -71.412855) (xy 73.194418 -71.421244) (xy 73.216867 -71.457116)
			(xy 73.25561 -71.532357) (xy 73.287033 -71.610937) (xy 73.310852 -71.692146) (xy 73.326851 -71.77525)
			(xy 73.334887 -71.859497) (xy 73.335388 -71.901812) (xy 73.334959 -71.942923) (xy 73.32737 -72.024795)
			(xy 73.312258 -72.105617) (xy 73.289751 -72.1847) (xy 73.260042 -72.261368) (xy 73.223385 -72.334967)
			(xy 73.180092 -72.404869) (xy 73.130533 -72.470478) (xy 73.075131 -72.531233) (xy 73.014358 -72.586616)
			(xy 72.948733 -72.636154) (xy 72.878817 -72.679424) (xy 72.805206 -72.716058) (xy 72.728529 -72.745742)
			(xy 72.649439 -72.768223) (xy 72.568612 -72.783309) (xy 72.486738 -72.790872) (xy 72.445626 -72.79132)
			(xy 72.403319 -72.790808) (xy 72.319083 -72.782808) (xy 72.235987 -72.766849) (xy 72.154781 -72.743076)
			(xy 72.076198 -72.711702) (xy 72.000948 -72.673011) (xy 71.965058 -72.650604) (xy 71.956669 -72.645721)
			(xy 71.937626 -72.64205) (xy 71.918583 -72.645721) (xy 71.910194 -72.650604) (xy 71.874311 -72.673026)
			(xy 71.799067 -72.711738) (xy 71.720486 -72.743126) (xy 71.639277 -72.766904) (xy 71.556176 -72.782859)
			(xy 71.471936 -72.790845) (xy 71.429626 -72.79132) (xy 71.387319 -72.790808) (xy 71.303083 -72.782808)
			(xy 71.219987 -72.766849) (xy 71.138781 -72.743076) (xy 71.060198 -72.711702) (xy 70.984948 -72.673011)
			(xy 70.949058 -72.650604) (xy 70.940669 -72.645721) (xy 70.921626 -72.64205) (xy 70.902583 -72.645721)
			(xy 70.894194 -72.650604) (xy 70.858311 -72.673026) (xy 70.783067 -72.711738) (xy 70.704486 -72.743126)
			(xy 70.623277 -72.766904) (xy 70.540176 -72.782859) (xy 70.455936 -72.790845) (xy 70.413626 -72.79132)
			(xy 70.372474 -72.790836) (xy 70.290522 -72.783244) (xy 70.209621 -72.768112) (xy 70.130464 -72.745571)
			(xy 70.053729 -72.715814) (xy 69.980071 -72.679093) (xy 69.91012 -72.635725) (xy 69.844476 -72.58608)
			(xy 69.783699 -72.530582) (xy 69.728309 -72.469706) (xy 69.678781 -72.403973) (xy 69.635537 -72.333946)
			(xy 69.616828 -72.29729) (xy 69.611748 -72.287384) (xy 69.595492 -72.273922) (xy 69.501004 -72.24776)
			(xy 69.479922 -72.251062) (xy 69.470778 -72.257158) (xy 69.411715 -72.294571) (xy 69.2896 -72.362684)
			(xy 69.163401 -72.422894) (xy 69.033629 -72.474957) (xy 68.900809 -72.518663) (xy 68.765478 -72.553834)
			(xy 68.628185 -72.580329) (xy 68.489485 -72.59804) (xy 68.349939 -72.606894) (xy 68.280026 -72.607424)
			(xy 68.212958 -72.606939) (xy 68.079071 -72.598766) (xy 67.945932 -72.582442) (xy 67.814036 -72.558028)
			(xy 67.683875 -72.525615) (xy 67.555933 -72.485323) (xy 67.430686 -72.437304) (xy 67.308602 -72.381735)
			(xy 67.190134 -72.318823) (xy 67.075724 -72.248803) (xy 66.965797 -72.171935) (xy 66.860763 -72.088506)
			(xy 66.761013 -71.998827) (xy 66.666918 -71.90323) (xy 66.57883 -71.802072) (xy 66.497074 -71.69573)
			(xy 66.4591 -71.640446) (xy 66.451988 -71.630032) (xy 66.42989 -71.618094) (xy 66.320162 -71.618094)
			(xy 66.298064 -71.630032) (xy 66.290952 -71.640446) (xy 66.252963 -71.695721) (xy 66.171215 -71.802068)
			(xy 66.083131 -71.903231) (xy 65.989041 -71.998833) (xy 65.889294 -72.088517) (xy 65.784262 -72.17195)
			(xy 65.674337 -72.24882) (xy 65.559927 -72.318842) (xy 65.441459 -72.381754) (xy 65.319374 -72.437323)
			(xy 65.194126 -72.485341) (xy 65.066183 -72.525629) (xy 64.93602 -72.558038) (xy 64.804123 -72.582447)
			(xy 64.670982 -72.598765) (xy 64.537094 -72.60693) (xy 64.470026 -72.607424) (xy 64.403633 -72.606935)
			(xy 64.27109 -72.59892) (xy 64.139272 -72.582917) (xy 64.008661 -72.558985) (xy 63.879733 -72.52721)
			(xy 63.752959 -72.48771) (xy 63.628801 -72.440627) (xy 63.507712 -72.386135) (xy 63.390133 -72.32443)
			(xy 63.276495 -72.25574) (xy 63.167211 -72.180314) (xy 63.062681 -72.098428) (xy 62.963285 -72.01038)
			(xy 62.869386 -71.916492) (xy 62.781327 -71.817105) (xy 62.699429 -71.712584) (xy 62.623991 -71.603308)
			(xy 62.555288 -71.489678) (xy 62.493571 -71.372106) (xy 62.439065 -71.251023) (xy 62.391969 -71.12687)
			(xy 62.352455 -71.0001) (xy 62.320666 -70.871176) (xy 62.296719 -70.740567) (xy 62.280702 -70.608751)
			(xy 62.272672 -70.476209) (xy 62.272164 -70.409816) (xy 62.272637 -70.34359) (xy 62.280621 -70.211378)
			(xy 62.296554 -70.079887) (xy 62.320379 -69.949595) (xy 62.352008 -69.820975) (xy 62.391329 -69.694493)
			(xy 62.438196 -69.57061) (xy 62.492441 -69.449774) (xy 62.553866 -69.332426) (xy 62.587632 -69.275452)
			(xy 62.593982 -69.265038) (xy 62.59576 -69.241416) (xy 62.555628 -69.143372) (xy 62.537848 -69.127878)
			(xy 62.52591 -69.124576) (xy 62.477384 -69.111519) (xy 62.382312 -69.078946) (xy 62.290048 -69.039106)
			(xy 62.201148 -68.992238) (xy 62.116146 -68.938624) (xy 62.035553 -68.878586) (xy 61.959852 -68.812486)
			(xy 61.8895 -68.74072) (xy 61.824919 -68.66372) (xy 61.766496 -68.581948) (xy 61.714584 -68.495896)
			(xy 61.669493 -68.406082) (xy 61.631496 -68.313044) (xy 61.60082 -68.217342) (xy 61.577651 -68.119552)
			(xy 61.562126 -68.020261) (xy 61.554339 -67.920065) (xy 61.553852 -67.869816) (xy 12.462296 -67.869816)
			(xy 12.543801 -67.875925) (xy 12.6453 -67.891224) (xy 12.745372 -67.914066) (xy 12.843457 -67.944323)
			(xy 12.939007 -67.981824) (xy 13.031487 -68.026361) (xy 13.12038 -68.077685) (xy 13.205189 -68.135508)
			(xy 13.28544 -68.199507) (xy 13.360685 -68.269324) (xy 13.430501 -68.344569) (xy 13.494499 -68.42482)
			(xy 13.552321 -68.50963) (xy 13.603644 -68.598524) (xy 13.64818 -68.691004) (xy 13.685681 -68.786554)
			(xy 13.715937 -68.88464) (xy 13.738778 -68.984712) (xy 13.754077 -69.086211) (xy 13.761748 -69.188569)
			(xy 13.762228 -69.239892) (xy 13.761691 -69.294799) (xy 13.752937 -69.404262) (xy 13.73546 -69.512676)
			(xy 13.709373 -69.619345) (xy 13.674841 -69.723588) (xy 13.632088 -69.824737) (xy 13.581385 -69.922144)
			(xy 13.523057 -70.015186) (xy 13.490702 -70.05955) (xy 13.484624 -70.068604) (xy 13.480031 -70.089902)
			(xy 13.484626 -70.1112) (xy 13.490702 -70.120256) (xy 13.523049 -70.164626) (xy 13.581374 -70.257669)
			(xy 13.632076 -70.355076) (xy 13.67483 -70.456223) (xy 13.709363 -70.560465) (xy 13.735454 -70.667133)
			(xy 13.752935 -70.775545) (xy 13.761695 -70.885008) (xy 13.762228 -70.939914) (xy 13.761756 -70.99124)
			(xy 13.754085 -71.093606) (xy 13.738787 -71.195112) (xy 13.715947 -71.295192) (xy 13.685693 -71.393285)
			(xy 13.648194 -71.488843) (xy 13.603659 -71.581332) (xy 13.552338 -71.670235) (xy 13.494518 -71.755054)
			(xy 13.430521 -71.835316) (xy 13.360706 -71.910572) (xy 13.285463 -71.9804) (xy 13.205212 -72.044411)
			(xy 13.120403 -72.102247) (xy 13.031509 -72.153584) (xy 12.939028 -72.198135) (xy 12.843477 -72.235652)
			(xy 12.745389 -72.265924) (xy 12.645314 -72.288782) (xy 12.54381 -72.304098) (xy 12.441446 -72.311787)
			(xy 12.39012 -72.312276) (xy 12.339213 -72.311802) (xy 12.23768 -72.304233) (xy 12.136987 -72.28916)
			(xy 12.037688 -72.266667) (xy 11.940329 -72.236876) (xy 11.845446 -72.199952) (xy 11.75356 -72.156098)
			(xy 11.665176 -72.105555) (xy 11.580782 -72.048601) (xy 11.50084 -71.98555) (xy 11.42579 -71.916747)
			(xy 11.356046 -71.842572) (xy 11.291991 -71.763431) (xy 11.233977 -71.679762) (xy 11.20775 -71.636128)
			(xy 11.200892 -71.624444) (xy 11.177524 -71.611236) (xy 11.062716 -71.611236) (xy 11.039348 -71.624444)
			(xy 11.03249 -71.636128) (xy 11.006274 -71.679769) (xy 10.948263 -71.763443) (xy 10.88421 -71.842586)
			(xy 10.814467 -71.916765) (xy 10.739418 -71.98557) (xy 10.659476 -72.048624) (xy 10.57508 -72.105579)
			(xy 10.486695 -72.156122) (xy 10.394806 -72.199975) (xy 10.299921 -72.236897) (xy 10.202559 -72.266684)
			(xy 10.103258 -72.289173) (xy 10.002563 -72.304241) (xy 9.901028 -72.311804) (xy 9.85012 -72.312276)
			(xy 9.798791 -72.311809) (xy 9.696419 -72.304137) (xy 9.594908 -72.288835) (xy 9.494824 -72.265988)
			(xy 9.396727 -72.235726) (xy 9.301167 -72.198216) (xy 9.208677 -72.153669) (xy 9.119776 -72.102335)
			(xy 9.034959 -72.044499) (xy 8.954703 -71.980486) (xy 8.879455 -71.910654) (xy 8.809637 -71.835393)
			(xy 8.745639 -71.755125) (xy 8.687819 -71.670298) (xy 8.636501 -71.581386) (xy 8.591972 -71.488888)
			(xy 8.55448 -71.393321) (xy 8.524235 -71.295219) (xy 8.501408 -71.195131) (xy 8.486124 -71.093616)
			(xy 8.478471 -70.991243) (xy 8.478012 -70.939914) (xy 0.509016 -70.939914) (xy 0.509016 -76.019914)
			(xy 8.478012 -76.019914) (xy 8.478545 -75.965007) (xy 8.487299 -75.855543) (xy 8.504775 -75.747129)
			(xy 8.530863 -75.64046) (xy 8.565395 -75.536217) (xy 8.608149 -75.435068) (xy 8.658854 -75.337662)
			(xy 8.717182 -75.24462) (xy 8.749538 -75.200256) (xy 8.755682 -75.191222) (xy 8.760349 -75.169902)
			(xy 8.755684 -75.148582) (xy 8.749538 -75.13955) (xy 8.717186 -75.095184) (xy 8.65886 -75.002141)
			(xy 8.608158 -74.904733) (xy 8.565404 -74.803585) (xy 8.530872 -74.699343) (xy 8.504782 -74.592674)
			(xy 8.487302 -74.484262) (xy 8.478544 -74.374799) (xy 8.478012 -74.319892) (xy 8.478453 -74.268568)
			(xy 8.486124 -74.166208) (xy 8.501424 -74.064707) (xy 8.524266 -73.964633) (xy 8.554522 -73.866547)
			(xy 8.592024 -73.770995) (xy 8.636562 -73.678513) (xy 8.687887 -73.589618) (xy 8.745711 -73.504808)
			(xy 8.809711 -73.424555) (xy 8.87953 -73.34931) (xy 8.954776 -73.279493) (xy 9.03503 -73.215494)
			(xy 9.119842 -73.157672) (xy 9.208738 -73.106349) (xy 9.301221 -73.061813) (xy 9.396773 -73.024313)
			(xy 9.49486 -72.994058) (xy 9.594935 -72.971218) (xy 9.696436 -72.955921) (xy 9.798796 -72.948252)
			(xy 9.85012 -72.947784) (xy 9.901023 -72.948245) (xy 10.00255 -72.955789) (xy 10.103239 -72.970838)
			(xy 10.202535 -72.993308) (xy 10.299893 -73.023077) (xy 10.394776 -73.05998) (xy 10.486663 -73.103815)
			(xy 10.575047 -73.154339) (xy 10.659444 -73.211276) (xy 10.739389 -73.274313) (xy 10.814441 -73.343101)
			(xy 10.884187 -73.417263) (xy 10.948245 -73.496391) (xy 11.006262 -73.580049) (xy 11.03249 -73.623678)
			(xy 11.039348 -73.635362) (xy 11.062716 -73.64857) (xy 11.177524 -73.64857) (xy 11.200892 -73.635362)
			(xy 11.20775 -73.623678) (xy 11.233971 -73.580045) (xy 11.291989 -73.496388) (xy 11.356048 -73.417261)
			(xy 11.425796 -73.3431) (xy 11.500849 -73.274313) (xy 11.580794 -73.211277) (xy 11.665192 -73.154341)
			(xy 11.753577 -73.103817) (xy 11.845464 -73.059983) (xy 11.940347 -73.02308) (xy 12.037705 -72.993311)
			(xy 12.137001 -72.970841) (xy 12.23769 -72.955792) (xy 12.339217 -72.948247) (xy 12.39012 -72.947784)
			(xy 12.441443 -72.948253) (xy 12.543801 -72.955925) (xy 12.6453 -72.971224) (xy 12.745372 -72.994066)
			(xy 12.843457 -73.024323) (xy 12.939007 -73.061824) (xy 13.031487 -73.106361) (xy 13.12038 -73.157685)
			(xy 13.205189 -73.215508) (xy 13.28544 -73.279507) (xy 13.360685 -73.349324) (xy 13.430501 -73.424569)
			(xy 13.494499 -73.50482) (xy 13.552321 -73.58963) (xy 13.603644 -73.678524) (xy 13.64818 -73.771004)
			(xy 13.685681 -73.866554) (xy 13.715937 -73.96464) (xy 13.738778 -74.064712) (xy 13.754077 -74.166211)
			(xy 13.761748 -74.268569) (xy 13.762228 -74.319892) (xy 13.761691 -74.374799) (xy 13.752937 -74.484262)
			(xy 13.73546 -74.592676) (xy 13.709373 -74.699345) (xy 13.674841 -74.803588) (xy 13.632088 -74.904737)
			(xy 13.581385 -75.002144) (xy 13.523057 -75.095186) (xy 13.490702 -75.13955) (xy 13.484624 -75.148604)
			(xy 13.480031 -75.169902) (xy 13.484626 -75.1912) (xy 13.490702 -75.200256) (xy 13.523049 -75.244626)
			(xy 13.581374 -75.337669) (xy 13.632076 -75.435076) (xy 13.67483 -75.536223) (xy 13.709363 -75.640465)
			(xy 13.735454 -75.747133) (xy 13.752935 -75.855545) (xy 13.761695 -75.965008) (xy 13.762228 -76.019914)
			(xy 13.761756 -76.07124) (xy 13.754085 -76.173606) (xy 13.738787 -76.275112) (xy 13.715947 -76.375192)
			(xy 13.685693 -76.473285) (xy 13.648194 -76.568843) (xy 13.603659 -76.661332) (xy 13.552338 -76.750235)
			(xy 13.494518 -76.835054) (xy 13.430521 -76.915316) (xy 13.360706 -76.990572) (xy 13.285463 -77.0604)
			(xy 13.205212 -77.124411) (xy 13.120403 -77.182247) (xy 13.031509 -77.233584) (xy 12.939028 -77.278135)
			(xy 12.843477 -77.315652) (xy 12.745389 -77.345924) (xy 12.645314 -77.368782) (xy 12.54381 -77.384098)
			(xy 12.441446 -77.391787) (xy 12.39012 -77.392276) (xy 12.339213 -77.391802) (xy 12.23768 -77.384233)
			(xy 12.136987 -77.36916) (xy 12.037688 -77.346667) (xy 11.940329 -77.316876) (xy 11.845446 -77.279952)
			(xy 11.75356 -77.236098) (xy 11.665176 -77.185555) (xy 11.580782 -77.128601) (xy 11.50084 -77.06555)
			(xy 11.42579 -76.996747) (xy 11.356046 -76.922572) (xy 11.291991 -76.843431) (xy 11.233977 -76.759762)
			(xy 11.20775 -76.716128) (xy 11.200892 -76.704444) (xy 11.177524 -76.691236) (xy 11.062716 -76.691236)
			(xy 11.039348 -76.704444) (xy 11.03249 -76.716128) (xy 11.006274 -76.759769) (xy 10.948263 -76.843443)
			(xy 10.88421 -76.922586) (xy 10.814467 -76.996765) (xy 10.739418 -77.06557) (xy 10.659476 -77.128624)
			(xy 10.57508 -77.185579) (xy 10.486695 -77.236122) (xy 10.394806 -77.279975) (xy 10.299921 -77.316897)
			(xy 10.202559 -77.346684) (xy 10.103258 -77.369173) (xy 10.002563 -77.384241) (xy 9.901028 -77.391804)
			(xy 9.85012 -77.392276) (xy 9.798791 -77.391809) (xy 9.696419 -77.384137) (xy 9.594908 -77.368835)
			(xy 9.494824 -77.345988) (xy 9.396727 -77.315726) (xy 9.301167 -77.278216) (xy 9.208677 -77.233669)
			(xy 9.119776 -77.182335) (xy 9.034959 -77.124499) (xy 8.954703 -77.060486) (xy 8.879455 -76.990654)
			(xy 8.809637 -76.915393) (xy 8.745639 -76.835125) (xy 8.687819 -76.750298) (xy 8.636501 -76.661386)
			(xy 8.591972 -76.568888) (xy 8.55448 -76.473321) (xy 8.524235 -76.375219) (xy 8.501408 -76.275131)
			(xy 8.486124 -76.173616) (xy 8.478471 -76.071243) (xy 8.478012 -76.019914) (xy 0.509016 -76.019914)
			(xy 0.509016 -77.760011) (xy 61.960756 -77.760011) (xy 61.960756 -77.675289) (xy 61.968809 -77.590952)
			(xy 61.984843 -77.507762) (xy 62.008711 -77.426472) (xy 62.040199 -77.34782) (xy 62.079021 -77.272517)
			(xy 62.124824 -77.201245) (xy 62.177195 -77.134649) (xy 62.23566 -77.073334) (xy 62.299688 -77.017853)
			(xy 62.3687 -76.96871) (xy 62.44207 -76.92635) (xy 62.519135 -76.891155) (xy 62.599197 -76.863446)
			(xy 62.68153 -76.843472) (xy 62.765389 -76.831415) (xy 62.850014 -76.827384) (xy 62.934639 -76.831415)
			(xy 63.018498 -76.843472) (xy 63.100831 -76.863446) (xy 63.180893 -76.891155) (xy 63.257958 -76.92635)
			(xy 63.331328 -76.96871) (xy 63.40034 -77.017853) (xy 63.464368 -77.073334) (xy 63.522833 -77.134649)
			(xy 63.575204 -77.201245) (xy 63.621007 -77.272517) (xy 63.659829 -77.34782) (xy 63.691317 -77.426472)
			(xy 63.715185 -77.507762) (xy 63.731219 -77.590952) (xy 63.739272 -77.675289) (xy 63.739776 -77.71765)
			(xy 63.739272 -77.760011) (xy 101.960676 -77.760011) (xy 101.960676 -77.675289) (xy 101.968729 -77.590952)
			(xy 101.984763 -77.507762) (xy 102.008631 -77.426472) (xy 102.040119 -77.34782) (xy 102.078941 -77.272517)
			(xy 102.124744 -77.201245) (xy 102.177115 -77.134649) (xy 102.23558 -77.073334) (xy 102.299608 -77.017853)
			(xy 102.36862 -76.96871) (xy 102.44199 -76.92635) (xy 102.519055 -76.891155) (xy 102.599117 -76.863446)
			(xy 102.68145 -76.843472) (xy 102.765309 -76.831415) (xy 102.849934 -76.827384) (xy 102.934559 -76.831415)
			(xy 103.018418 -76.843472) (xy 103.100751 -76.863446) (xy 103.180813 -76.891155) (xy 103.257878 -76.92635)
			(xy 103.331248 -76.96871) (xy 103.40026 -77.017853) (xy 103.464288 -77.073334) (xy 103.522753 -77.134649)
			(xy 103.575124 -77.201245) (xy 103.620927 -77.272517) (xy 103.659749 -77.34782) (xy 103.691237 -77.426472)
			(xy 103.715105 -77.507762) (xy 103.731139 -77.590952) (xy 103.739192 -77.675289) (xy 103.739696 -77.71765)
			(xy 103.739192 -77.760011) (xy 141.96085 -77.760011) (xy 141.96085 -77.675289) (xy 141.968903 -77.590952)
			(xy 141.984937 -77.507762) (xy 142.008805 -77.426472) (xy 142.040293 -77.34782) (xy 142.079115 -77.272517)
			(xy 142.124918 -77.201245) (xy 142.177289 -77.134649) (xy 142.235754 -77.073334) (xy 142.299782 -77.017853)
			(xy 142.368794 -76.96871) (xy 142.442164 -76.92635) (xy 142.519229 -76.891155) (xy 142.599291 -76.863446)
			(xy 142.681624 -76.843472) (xy 142.765483 -76.831415) (xy 142.850108 -76.827384) (xy 142.934733 -76.831415)
			(xy 143.018592 -76.843472) (xy 143.100925 -76.863446) (xy 143.180987 -76.891155) (xy 143.258052 -76.92635)
			(xy 143.331422 -76.96871) (xy 143.400434 -77.017853) (xy 143.464462 -77.073334) (xy 143.522927 -77.134649)
			(xy 143.575298 -77.201245) (xy 143.621101 -77.272517) (xy 143.659923 -77.34782) (xy 143.691411 -77.426472)
			(xy 143.715279 -77.507762) (xy 143.731313 -77.590952) (xy 143.739366 -77.675289) (xy 143.73987 -77.71765)
			(xy 143.739366 -77.760011) (xy 181.961024 -77.760011) (xy 181.961024 -77.675289) (xy 181.969077 -77.590952)
			(xy 181.985111 -77.507762) (xy 182.008979 -77.426472) (xy 182.040467 -77.34782) (xy 182.079289 -77.272517)
			(xy 182.125092 -77.201245) (xy 182.177463 -77.134649) (xy 182.235928 -77.073334) (xy 182.299956 -77.017853)
			(xy 182.368968 -76.96871) (xy 182.442338 -76.92635) (xy 182.519403 -76.891155) (xy 182.599465 -76.863446)
			(xy 182.681798 -76.843472) (xy 182.765657 -76.831415) (xy 182.850282 -76.827384) (xy 182.934907 -76.831415)
			(xy 183.018766 -76.843472) (xy 183.101099 -76.863446) (xy 183.181161 -76.891155) (xy 183.258226 -76.92635)
			(xy 183.331596 -76.96871) (xy 183.400608 -77.017853) (xy 183.464636 -77.073334) (xy 183.523101 -77.134649)
			(xy 183.575472 -77.201245) (xy 183.621275 -77.272517) (xy 183.660097 -77.34782) (xy 183.691585 -77.426472)
			(xy 183.715453 -77.507762) (xy 183.731487 -77.590952) (xy 183.732064 -77.597) (xy 268.350492 -77.597)
			(xy 268.351075 -77.550604) (xy 268.36072 -77.458316) (xy 268.379916 -77.367532) (xy 268.408454 -77.279239)
			(xy 268.426692 -77.236574) (xy 268.430498 -77.226632) (xy 268.430498 -77.205368) (xy 268.426692 -77.195426)
			(xy 268.408447 -77.152764) (xy 268.379903 -77.064471) (xy 268.36071 -76.973686) (xy 268.351077 -76.881396)
			(xy 268.350492 -76.835) (xy 268.351075 -76.788604) (xy 268.36072 -76.696316) (xy 268.379916 -76.605532)
			(xy 268.408454 -76.517239) (xy 268.426692 -76.474574) (xy 268.430498 -76.464632) (xy 268.430498 -76.443368)
			(xy 268.426692 -76.433426) (xy 268.408447 -76.390764) (xy 268.379903 -76.302471) (xy 268.36071 -76.211686)
			(xy 268.351077 -76.119396) (xy 268.350492 -76.073) (xy 268.351075 -76.026604) (xy 268.36072 -75.934316)
			(xy 268.379916 -75.843532) (xy 268.408454 -75.755239) (xy 268.426692 -75.712574) (xy 268.430498 -75.702632)
			(xy 268.430498 -75.681368) (xy 268.426692 -75.671426) (xy 268.408447 -75.628764) (xy 268.379903 -75.540471)
			(xy 268.36071 -75.449686) (xy 268.351077 -75.357396) (xy 268.350492 -75.311) (xy 268.351075 -75.264604)
			(xy 268.36072 -75.172316) (xy 268.379916 -75.081532) (xy 268.408454 -74.993239) (xy 268.426692 -74.950574)
			(xy 268.430498 -74.940632) (xy 268.430498 -74.919368) (xy 268.426692 -74.909426) (xy 268.408447 -74.866764)
			(xy 268.379903 -74.778471) (xy 268.36071 -74.687686) (xy 268.351077 -74.595396) (xy 268.350492 -74.549)
			(xy 268.351075 -74.502604) (xy 268.36072 -74.410316) (xy 268.379916 -74.319532) (xy 268.408454 -74.231239)
			(xy 268.426692 -74.188574) (xy 268.430498 -74.178632) (xy 268.430498 -74.157368) (xy 268.426692 -74.147426)
			(xy 268.408447 -74.104764) (xy 268.379903 -74.016471) (xy 268.36071 -73.925686) (xy 268.351077 -73.833396)
			(xy 268.350492 -73.787) (xy 268.350967 -73.745898) (xy 268.358552 -73.664043) (xy 268.373657 -73.583238)
			(xy 268.396153 -73.504171) (xy 268.425849 -73.427517) (xy 268.462491 -73.35393) (xy 268.505766 -73.284038)
			(xy 268.555306 -73.218437) (xy 268.610687 -73.157687) (xy 268.671437 -73.102306) (xy 268.737038 -73.052766)
			(xy 268.80693 -73.009491) (xy 268.880517 -72.972849) (xy 268.957171 -72.943153) (xy 269.036238 -72.920657)
			(xy 269.117043 -72.905552) (xy 269.198898 -72.897967) (xy 269.24 -72.897492) (xy 269.286396 -72.898075)
			(xy 269.378684 -72.90772) (xy 269.469468 -72.926916) (xy 269.557761 -72.955454) (xy 269.600426 -72.973692)
			(xy 269.610368 -72.977498) (xy 269.631632 -72.977498) (xy 269.641574 -72.973692) (xy 269.684236 -72.955447)
			(xy 269.772529 -72.926903) (xy 269.863314 -72.90771) (xy 269.955604 -72.898077) (xy 270.002 -72.897492)
			(xy 270.048396 -72.898075) (xy 270.140684 -72.90772) (xy 270.231468 -72.926916) (xy 270.319761 -72.955454)
			(xy 270.362426 -72.973692) (xy 270.372368 -72.977498) (xy 270.393632 -72.977498) (xy 270.403574 -72.973692)
			(xy 270.446236 -72.955447) (xy 270.534529 -72.926903) (xy 270.625314 -72.90771) (xy 270.717604 -72.898077)
			(xy 270.764 -72.897492) (xy 270.810396 -72.898075) (xy 270.902684 -72.90772) (xy 270.993468 -72.926916)
			(xy 271.081761 -72.955454) (xy 271.124426 -72.973692) (xy 271.134368 -72.977498) (xy 271.155632 -72.977498)
			(xy 271.165574 -72.973692) (xy 271.208236 -72.955447) (xy 271.296529 -72.926903) (xy 271.387314 -72.90771)
			(xy 271.479604 -72.898077) (xy 271.526 -72.897492) (xy 271.572396 -72.898075) (xy 271.664684 -72.90772)
			(xy 271.755468 -72.926916) (xy 271.843761 -72.955454) (xy 271.886426 -72.973692) (xy 271.896368 -72.977498)
			(xy 271.917632 -72.977498) (xy 271.927574 -72.973692) (xy 271.970236 -72.955447) (xy 272.058529 -72.926903)
			(xy 272.149314 -72.90771) (xy 272.241604 -72.898077) (xy 272.288 -72.897492) (xy 272.329102 -72.897967)
			(xy 272.410957 -72.905552) (xy 272.491762 -72.920657) (xy 272.570829 -72.943153) (xy 272.647483 -72.972849)
			(xy 272.72107 -73.009491) (xy 272.790962 -73.052766) (xy 272.856563 -73.102306) (xy 272.917313 -73.157687)
			(xy 272.972694 -73.218437) (xy 273.022234 -73.284038) (xy 273.065509 -73.35393) (xy 273.102151 -73.427517)
			(xy 273.131847 -73.504171) (xy 273.154343 -73.583238) (xy 273.169448 -73.664043) (xy 273.177033 -73.745898)
			(xy 273.177508 -73.787) (xy 273.176925 -73.833396) (xy 273.16728 -73.925684) (xy 273.148084 -74.016468)
			(xy 273.119546 -74.104761) (xy 273.101308 -74.147426) (xy 273.097502 -74.157368) (xy 273.097502 -74.178632)
			(xy 273.101308 -74.188574) (xy 273.119553 -74.231236) (xy 273.148097 -74.319529) (xy 273.16729 -74.410314)
			(xy 273.176923 -74.502604) (xy 273.177508 -74.549) (xy 273.177033 -74.590102) (xy 273.169448 -74.671957)
			(xy 273.154343 -74.752762) (xy 273.131847 -74.831829) (xy 273.102151 -74.908483) (xy 273.065509 -74.98207)
			(xy 273.022234 -75.051962) (xy 272.972694 -75.117563) (xy 272.917313 -75.178313) (xy 272.856563 -75.233694)
			(xy 272.790962 -75.283234) (xy 272.72107 -75.326509) (xy 272.647483 -75.363151) (xy 272.570829 -75.392847)
			(xy 272.491762 -75.415343) (xy 272.410957 -75.430448) (xy 272.329102 -75.438033) (xy 272.288 -75.438508)
			(xy 272.241604 -75.437925) (xy 272.149316 -75.42828) (xy 272.058532 -75.409084) (xy 271.970239 -75.380546)
			(xy 271.927574 -75.362308) (xy 271.917632 -75.358502) (xy 271.896368 -75.358502) (xy 271.886426 -75.362308)
			(xy 271.853507 -75.376537) (xy 271.785822 -75.400257) (xy 271.716442 -75.418437) (xy 271.681194 -75.425046)
			(xy 271.67107 -75.427344) (xy 271.653749 -75.438749) (xy 271.642344 -75.45607) (xy 271.640046 -75.466194)
			(xy 271.633416 -75.501437) (xy 271.61522 -75.57081) (xy 271.591513 -75.638498) (xy 271.577308 -75.671426)
			(xy 271.573502 -75.681368) (xy 271.573502 -75.702632) (xy 271.577308 -75.712574) (xy 271.591537 -75.745493)
			(xy 271.615257 -75.813178) (xy 271.633437 -75.882558) (xy 271.640046 -75.917806) (xy 271.642344 -75.92793)
			(xy 271.653749 -75.945251) (xy 271.67107 -75.956656) (xy 271.681194 -75.958954) (xy 271.716437 -75.965584)
			(xy 271.78581 -75.98378) (xy 271.853498 -76.007487) (xy 271.886426 -76.021692) (xy 271.896368 -76.025498)
			(xy 271.917632 -76.025498) (xy 271.927574 -76.021692) (xy 271.970236 -76.003447) (xy 272.058529 -75.974903)
			(xy 272.149314 -75.95571) (xy 272.241604 -75.946077) (xy 272.288 -75.945492) (xy 272.329102 -75.945967)
			(xy 272.410957 -75.953552) (xy 272.491762 -75.968657) (xy 272.570829 -75.991153) (xy 272.647483 -76.020849)
			(xy 272.72107 -76.057491) (xy 272.790962 -76.100766) (xy 272.856563 -76.150306) (xy 272.917313 -76.205687)
			(xy 272.972694 -76.266437) (xy 273.022234 -76.332038) (xy 273.065509 -76.40193) (xy 273.102151 -76.475517)
			(xy 273.131847 -76.552171) (xy 273.154343 -76.631238) (xy 273.169448 -76.712043) (xy 273.177033 -76.793898)
			(xy 273.177508 -76.835) (xy 273.176925 -76.881396) (xy 273.16728 -76.973684) (xy 273.148084 -77.064468)
			(xy 273.119546 -77.152761) (xy 273.101308 -77.195426) (xy 273.097502 -77.205368) (xy 273.097502 -77.226632)
			(xy 273.101308 -77.236574) (xy 273.119553 -77.279236) (xy 273.148097 -77.367529) (xy 273.16729 -77.458314)
			(xy 273.176923 -77.550604) (xy 273.177508 -77.597) (xy 273.177033 -77.638102) (xy 273.169448 -77.719957)
			(xy 273.154343 -77.800762) (xy 273.131847 -77.879829) (xy 273.102151 -77.956483) (xy 273.065509 -78.03007)
			(xy 273.022234 -78.099962) (xy 272.972694 -78.165563) (xy 272.917313 -78.226313) (xy 272.856563 -78.281694)
			(xy 272.790962 -78.331234) (xy 272.72107 -78.374509) (xy 272.647483 -78.411151) (xy 272.570829 -78.440847)
			(xy 272.491762 -78.463343) (xy 272.410957 -78.478448) (xy 272.329102 -78.486033) (xy 272.288 -78.486508)
			(xy 272.241604 -78.485925) (xy 272.149316 -78.47628) (xy 272.058532 -78.457084) (xy 271.970239 -78.428546)
			(xy 271.927574 -78.410308) (xy 271.917632 -78.406502) (xy 271.896368 -78.406502) (xy 271.886426 -78.410308)
			(xy 271.843764 -78.428553) (xy 271.755471 -78.457097) (xy 271.664686 -78.47629) (xy 271.572396 -78.485923)
			(xy 271.526 -78.486508) (xy 271.479604 -78.485925) (xy 271.387316 -78.47628) (xy 271.296532 -78.457084)
			(xy 271.208239 -78.428546) (xy 271.165574 -78.410308) (xy 271.155632 -78.406502) (xy 271.134368 -78.406502)
			(xy 271.124426 -78.410308) (xy 271.081764 -78.428553) (xy 270.993471 -78.457097) (xy 270.902686 -78.47629)
			(xy 270.810396 -78.485923) (xy 270.764 -78.486508) (xy 270.717604 -78.485925) (xy 270.625316 -78.47628)
			(xy 270.534532 -78.457084) (xy 270.446239 -78.428546) (xy 270.403574 -78.410308) (xy 270.393632 -78.406502)
			(xy 270.372368 -78.406502) (xy 270.362426 -78.410308) (xy 270.319764 -78.428553) (xy 270.231471 -78.457097)
			(xy 270.140686 -78.47629) (xy 270.048396 -78.485923) (xy 270.002 -78.486508) (xy 269.955604 -78.485925)
			(xy 269.863316 -78.47628) (xy 269.772532 -78.457084) (xy 269.684239 -78.428546) (xy 269.641574 -78.410308)
			(xy 269.631632 -78.406502) (xy 269.610368 -78.406502) (xy 269.600426 -78.410308) (xy 269.557764 -78.428553)
			(xy 269.469471 -78.457097) (xy 269.378686 -78.47629) (xy 269.286396 -78.485923) (xy 269.24 -78.486508)
			(xy 269.198898 -78.486033) (xy 269.117043 -78.478448) (xy 269.036238 -78.463343) (xy 268.957171 -78.440847)
			(xy 268.880517 -78.411151) (xy 268.80693 -78.374509) (xy 268.737038 -78.331234) (xy 268.671437 -78.281694)
			(xy 268.610687 -78.226313) (xy 268.555306 -78.165563) (xy 268.505766 -78.099962) (xy 268.462491 -78.03007)
			(xy 268.425849 -77.956483) (xy 268.396153 -77.879829) (xy 268.373657 -77.800762) (xy 268.358552 -77.719957)
			(xy 268.350967 -77.638102) (xy 268.350492 -77.597) (xy 183.732064 -77.597) (xy 183.73954 -77.675289)
			(xy 183.740044 -77.71765) (xy 183.73954 -77.760011) (xy 183.731487 -77.844348) (xy 183.715453 -77.927538)
			(xy 183.691585 -78.008828) (xy 183.660097 -78.08748) (xy 183.621275 -78.162783) (xy 183.575472 -78.234055)
			(xy 183.523101 -78.300651) (xy 183.464636 -78.361966) (xy 183.400608 -78.417447) (xy 183.331596 -78.46659)
			(xy 183.258226 -78.50895) (xy 183.181161 -78.544145) (xy 183.101099 -78.571854) (xy 183.018766 -78.591828)
			(xy 182.934907 -78.603885) (xy 182.850282 -78.607917) (xy 182.765657 -78.603885) (xy 182.681798 -78.591828)
			(xy 182.599465 -78.571854) (xy 182.519403 -78.544145) (xy 182.442338 -78.50895) (xy 182.368968 -78.46659)
			(xy 182.299956 -78.417447) (xy 182.235928 -78.361966) (xy 182.177463 -78.300651) (xy 182.125092 -78.234055)
			(xy 182.079289 -78.162783) (xy 182.040467 -78.08748) (xy 182.008979 -78.008828) (xy 181.985111 -77.927538)
			(xy 181.969077 -77.844348) (xy 181.961024 -77.760011) (xy 143.739366 -77.760011) (xy 143.731313 -77.844348)
			(xy 143.715279 -77.927538) (xy 143.691411 -78.008828) (xy 143.659923 -78.08748) (xy 143.621101 -78.162783)
			(xy 143.575298 -78.234055) (xy 143.522927 -78.300651) (xy 143.464462 -78.361966) (xy 143.400434 -78.417447)
			(xy 143.331422 -78.46659) (xy 143.258052 -78.50895) (xy 143.180987 -78.544145) (xy 143.100925 -78.571854)
			(xy 143.018592 -78.591828) (xy 142.934733 -78.603885) (xy 142.850108 -78.607917) (xy 142.765483 -78.603885)
			(xy 142.681624 -78.591828) (xy 142.599291 -78.571854) (xy 142.519229 -78.544145) (xy 142.442164 -78.50895)
			(xy 142.368794 -78.46659) (xy 142.299782 -78.417447) (xy 142.235754 -78.361966) (xy 142.177289 -78.300651)
			(xy 142.124918 -78.234055) (xy 142.079115 -78.162783) (xy 142.040293 -78.08748) (xy 142.008805 -78.008828)
			(xy 141.984937 -77.927538) (xy 141.968903 -77.844348) (xy 141.96085 -77.760011) (xy 103.739192 -77.760011)
			(xy 103.731139 -77.844348) (xy 103.715105 -77.927538) (xy 103.691237 -78.008828) (xy 103.659749 -78.08748)
			(xy 103.620927 -78.162783) (xy 103.575124 -78.234055) (xy 103.522753 -78.300651) (xy 103.464288 -78.361966)
			(xy 103.40026 -78.417447) (xy 103.331248 -78.46659) (xy 103.257878 -78.50895) (xy 103.180813 -78.544145)
			(xy 103.100751 -78.571854) (xy 103.018418 -78.591828) (xy 102.934559 -78.603885) (xy 102.849934 -78.607917)
			(xy 102.765309 -78.603885) (xy 102.68145 -78.591828) (xy 102.599117 -78.571854) (xy 102.519055 -78.544145)
			(xy 102.44199 -78.50895) (xy 102.36862 -78.46659) (xy 102.299608 -78.417447) (xy 102.23558 -78.361966)
			(xy 102.177115 -78.300651) (xy 102.124744 -78.234055) (xy 102.078941 -78.162783) (xy 102.040119 -78.08748)
			(xy 102.008631 -78.008828) (xy 101.984763 -77.927538) (xy 101.968729 -77.844348) (xy 101.960676 -77.760011)
			(xy 63.739272 -77.760011) (xy 63.731219 -77.844348) (xy 63.715185 -77.927538) (xy 63.691317 -78.008828)
			(xy 63.659829 -78.08748) (xy 63.621007 -78.162783) (xy 63.575204 -78.234055) (xy 63.522833 -78.300651)
			(xy 63.464368 -78.361966) (xy 63.40034 -78.417447) (xy 63.331328 -78.46659) (xy 63.257958 -78.50895)
			(xy 63.180893 -78.544145) (xy 63.100831 -78.571854) (xy 63.018498 -78.591828) (xy 62.934639 -78.603885)
			(xy 62.850014 -78.607917) (xy 62.765389 -78.603885) (xy 62.68153 -78.591828) (xy 62.599197 -78.571854)
			(xy 62.519135 -78.544145) (xy 62.44207 -78.50895) (xy 62.3687 -78.46659) (xy 62.299688 -78.417447)
			(xy 62.23566 -78.361966) (xy 62.177195 -78.300651) (xy 62.124824 -78.234055) (xy 62.079021 -78.162783)
			(xy 62.040199 -78.08748) (xy 62.008711 -78.008828) (xy 61.984843 -77.927538) (xy 61.968809 -77.844348)
			(xy 61.960756 -77.760011) (xy 0.509016 -77.760011) (xy 0.509016 -80.799629) (xy 270.301208 -80.799629)
			(xy 270.301208 -80.714907) (xy 270.309261 -80.63057) (xy 270.325295 -80.54738) (xy 270.349163 -80.46609)
			(xy 270.380651 -80.387438) (xy 270.419473 -80.312135) (xy 270.465276 -80.240863) (xy 270.517647 -80.174267)
			(xy 270.576112 -80.112952) (xy 270.64014 -80.057471) (xy 270.709152 -80.008328) (xy 270.782522 -79.965968)
			(xy 270.859587 -79.930773) (xy 270.939649 -79.903064) (xy 271.021982 -79.88309) (xy 271.105841 -79.871033)
			(xy 271.190466 -79.867002) (xy 271.275091 -79.871033) (xy 271.35895 -79.88309) (xy 271.441283 -79.903064)
			(xy 271.521345 -79.930773) (xy 271.59841 -79.965968) (xy 271.67178 -80.008328) (xy 271.740792 -80.057471)
			(xy 271.80482 -80.112952) (xy 271.863285 -80.174267) (xy 271.915656 -80.240863) (xy 271.961459 -80.312135)
			(xy 272.000281 -80.387438) (xy 272.031769 -80.46609) (xy 272.055637 -80.54738) (xy 272.071671 -80.63057)
			(xy 272.079724 -80.714907) (xy 272.080228 -80.757268) (xy 272.079724 -80.799629) (xy 272.071671 -80.883966)
			(xy 272.055637 -80.967156) (xy 272.031769 -81.048446) (xy 272.000281 -81.127098) (xy 271.961459 -81.202401)
			(xy 271.915656 -81.273673) (xy 271.863285 -81.340269) (xy 271.80482 -81.401584) (xy 271.740792 -81.457065)
			(xy 271.67178 -81.506208) (xy 271.59841 -81.548568) (xy 271.521345 -81.583763) (xy 271.441283 -81.611472)
			(xy 271.35895 -81.631446) (xy 271.275091 -81.643503) (xy 271.190466 -81.647535) (xy 271.105841 -81.643503)
			(xy 271.021982 -81.631446) (xy 270.939649 -81.611472) (xy 270.859587 -81.583763) (xy 270.782522 -81.548568)
			(xy 270.709152 -81.506208) (xy 270.64014 -81.457065) (xy 270.576112 -81.401584) (xy 270.517647 -81.340269)
			(xy 270.465276 -81.273673) (xy 270.419473 -81.202401) (xy 270.380651 -81.127098) (xy 270.349163 -81.048446)
			(xy 270.325295 -80.967156) (xy 270.309261 -80.883966) (xy 270.301208 -80.799629) (xy 0.509016 -80.799629)
			(xy 0.509016 -82.272829) (xy 268.757142 -82.272829) (xy 268.757142 -82.188107) (xy 268.765195 -82.10377)
			(xy 268.781229 -82.02058) (xy 268.805097 -81.93929) (xy 268.836585 -81.860638) (xy 268.875407 -81.785335)
			(xy 268.92121 -81.714063) (xy 268.973581 -81.647467) (xy 269.032046 -81.586152) (xy 269.096074 -81.530671)
			(xy 269.165086 -81.481528) (xy 269.238456 -81.439168) (xy 269.315521 -81.403973) (xy 269.395583 -81.376264)
			(xy 269.477916 -81.35629) (xy 269.561775 -81.344233) (xy 269.6464 -81.340202) (xy 269.731025 -81.344233)
			(xy 269.814884 -81.35629) (xy 269.897217 -81.376264) (xy 269.977279 -81.403973) (xy 270.054344 -81.439168)
			(xy 270.127714 -81.481528) (xy 270.196726 -81.530671) (xy 270.260754 -81.586152) (xy 270.319219 -81.647467)
			(xy 270.37159 -81.714063) (xy 270.417393 -81.785335) (xy 270.456215 -81.860638) (xy 270.487703 -81.93929)
			(xy 270.511571 -82.02058) (xy 270.527605 -82.10377) (xy 270.535658 -82.188107) (xy 270.536162 -82.230468)
			(xy 270.535658 -82.272829) (xy 270.527605 -82.357166) (xy 270.511571 -82.440356) (xy 270.487703 -82.521646)
			(xy 270.456215 -82.600298) (xy 270.417393 -82.675601) (xy 270.37159 -82.746873) (xy 270.319219 -82.813469)
			(xy 270.260754 -82.874784) (xy 270.196726 -82.930265) (xy 270.127714 -82.979408) (xy 270.054344 -83.021768)
			(xy 269.977279 -83.056963) (xy 269.897217 -83.084672) (xy 269.814884 -83.104646) (xy 269.731025 -83.116703)
			(xy 269.6464 -83.120735) (xy 269.561775 -83.116703) (xy 269.477916 -83.104646) (xy 269.395583 -83.084672)
			(xy 269.315521 -83.056963) (xy 269.238456 -83.021768) (xy 269.165086 -82.979408) (xy 269.096074 -82.930265)
			(xy 269.032046 -82.874784) (xy 268.973581 -82.813469) (xy 268.92121 -82.746873) (xy 268.875407 -82.675601)
			(xy 268.836585 -82.600298) (xy 268.805097 -82.521646) (xy 268.781229 -82.440356) (xy 268.765195 -82.357166)
			(xy 268.757142 -82.272829) (xy 0.509016 -82.272829) (xy 0.509016 -89.662) (xy 268.350492 -89.662)
			(xy 268.351075 -89.615604) (xy 268.36072 -89.523316) (xy 268.379916 -89.432532) (xy 268.408454 -89.344239)
			(xy 268.426692 -89.301574) (xy 268.430498 -89.291632) (xy 268.430498 -89.270368) (xy 268.426692 -89.260426)
			(xy 268.408447 -89.217764) (xy 268.379903 -89.129471) (xy 268.36071 -89.038686) (xy 268.351077 -88.946396)
			(xy 268.350492 -88.9) (xy 268.351075 -88.853604) (xy 268.36072 -88.761316) (xy 268.379916 -88.670532)
			(xy 268.408454 -88.582239) (xy 268.426692 -88.539574) (xy 268.430498 -88.529632) (xy 268.430498 -88.508368)
			(xy 268.426692 -88.498426) (xy 268.408447 -88.455764) (xy 268.379903 -88.367471) (xy 268.36071 -88.276686)
			(xy 268.351077 -88.184396) (xy 268.350492 -88.138) (xy 268.351075 -88.091604) (xy 268.36072 -87.999316)
			(xy 268.379916 -87.908532) (xy 268.408454 -87.820239) (xy 268.426692 -87.777574) (xy 268.430498 -87.767632)
			(xy 268.430498 -87.746368) (xy 268.426692 -87.736426) (xy 268.408447 -87.693764) (xy 268.379903 -87.605471)
			(xy 268.36071 -87.514686) (xy 268.351077 -87.422396) (xy 268.350492 -87.376) (xy 268.351075 -87.329604)
			(xy 268.36072 -87.237316) (xy 268.379916 -87.146532) (xy 268.408454 -87.058239) (xy 268.426692 -87.015574)
			(xy 268.430498 -87.005632) (xy 268.430498 -86.984368) (xy 268.426692 -86.974426) (xy 268.408447 -86.931764)
			(xy 268.379903 -86.843471) (xy 268.36071 -86.752686) (xy 268.351077 -86.660396) (xy 268.350492 -86.614)
			(xy 268.351075 -86.567604) (xy 268.36072 -86.475316) (xy 268.379916 -86.384532) (xy 268.408454 -86.296239)
			(xy 268.426692 -86.253574) (xy 268.430498 -86.243632) (xy 268.430498 -86.222368) (xy 268.426692 -86.212426)
			(xy 268.408447 -86.169764) (xy 268.379903 -86.081471) (xy 268.36071 -85.990686) (xy 268.351077 -85.898396)
			(xy 268.350492 -85.852) (xy 268.350967 -85.810898) (xy 268.358552 -85.729043) (xy 268.373657 -85.648238)
			(xy 268.396153 -85.569171) (xy 268.425849 -85.492517) (xy 268.462491 -85.41893) (xy 268.505766 -85.349038)
			(xy 268.555306 -85.283437) (xy 268.610687 -85.222687) (xy 268.671437 -85.167306) (xy 268.737038 -85.117766)
			(xy 268.80693 -85.074491) (xy 268.880517 -85.037849) (xy 268.957171 -85.008153) (xy 269.036238 -84.985657)
			(xy 269.117043 -84.970552) (xy 269.198898 -84.962967) (xy 269.24 -84.962492) (xy 269.286396 -84.963075)
			(xy 269.378684 -84.97272) (xy 269.469468 -84.991916) (xy 269.557761 -85.020454) (xy 269.600426 -85.038692)
			(xy 269.610368 -85.042498) (xy 269.631632 -85.042498) (xy 269.641574 -85.038692) (xy 269.684236 -85.020447)
			(xy 269.772529 -84.991903) (xy 269.863314 -84.97271) (xy 269.955604 -84.963077) (xy 270.002 -84.962492)
			(xy 270.048396 -84.963075) (xy 270.140684 -84.97272) (xy 270.231468 -84.991916) (xy 270.319761 -85.020454)
			(xy 270.362426 -85.038692) (xy 270.372368 -85.042498) (xy 270.393632 -85.042498) (xy 270.403574 -85.038692)
			(xy 270.446236 -85.020447) (xy 270.534529 -84.991903) (xy 270.625314 -84.97271) (xy 270.717604 -84.963077)
			(xy 270.764 -84.962492) (xy 270.810396 -84.963075) (xy 270.902684 -84.97272) (xy 270.993468 -84.991916)
			(xy 271.081761 -85.020454) (xy 271.124426 -85.038692) (xy 271.134368 -85.042498) (xy 271.155632 -85.042498)
			(xy 271.165574 -85.038692) (xy 271.208236 -85.020447) (xy 271.296529 -84.991903) (xy 271.387314 -84.97271)
			(xy 271.479604 -84.963077) (xy 271.526 -84.962492) (xy 271.572396 -84.963075) (xy 271.664684 -84.97272)
			(xy 271.755468 -84.991916) (xy 271.843761 -85.020454) (xy 271.886426 -85.038692) (xy 271.896368 -85.042498)
			(xy 271.917632 -85.042498) (xy 271.927574 -85.038692) (xy 271.970236 -85.020447) (xy 272.058529 -84.991903)
			(xy 272.149314 -84.97271) (xy 272.241604 -84.963077) (xy 272.288 -84.962492) (xy 272.329102 -84.962967)
			(xy 272.410957 -84.970552) (xy 272.491762 -84.985657) (xy 272.570829 -85.008153) (xy 272.647483 -85.037849)
			(xy 272.72107 -85.074491) (xy 272.790962 -85.117766) (xy 272.856563 -85.167306) (xy 272.917313 -85.222687)
			(xy 272.972694 -85.283437) (xy 273.022234 -85.349038) (xy 273.065509 -85.41893) (xy 273.102151 -85.492517)
			(xy 273.131847 -85.569171) (xy 273.154343 -85.648238) (xy 273.169448 -85.729043) (xy 273.177033 -85.810898)
			(xy 273.177508 -85.852) (xy 273.176925 -85.898396) (xy 273.16728 -85.990684) (xy 273.148084 -86.081468)
			(xy 273.119546 -86.169761) (xy 273.101308 -86.212426) (xy 273.097502 -86.222368) (xy 273.097502 -86.243632)
			(xy 273.101308 -86.253574) (xy 273.119553 -86.296236) (xy 273.148097 -86.384529) (xy 273.16729 -86.475314)
			(xy 273.176923 -86.567604) (xy 273.177508 -86.614) (xy 273.177033 -86.655102) (xy 273.169448 -86.736957)
			(xy 273.154343 -86.817762) (xy 273.131847 -86.896829) (xy 273.102151 -86.973483) (xy 273.065509 -87.04707)
			(xy 273.022234 -87.116962) (xy 272.972694 -87.182563) (xy 272.917313 -87.243313) (xy 272.856563 -87.298694)
			(xy 272.790962 -87.348234) (xy 272.72107 -87.391509) (xy 272.647483 -87.428151) (xy 272.570829 -87.457847)
			(xy 272.491762 -87.480343) (xy 272.410957 -87.495448) (xy 272.329102 -87.503033) (xy 272.288 -87.503508)
			(xy 272.241604 -87.502925) (xy 272.149316 -87.49328) (xy 272.058532 -87.474084) (xy 271.970239 -87.445546)
			(xy 271.927574 -87.427308) (xy 271.917632 -87.423502) (xy 271.896368 -87.423502) (xy 271.886426 -87.427308)
			(xy 271.853507 -87.441537) (xy 271.785822 -87.465257) (xy 271.716442 -87.483437) (xy 271.681194 -87.490046)
			(xy 271.67107 -87.492344) (xy 271.653749 -87.503749) (xy 271.642344 -87.52107) (xy 271.640046 -87.531194)
			(xy 271.633416 -87.566437) (xy 271.61522 -87.63581) (xy 271.591513 -87.703498) (xy 271.577308 -87.736426)
			(xy 271.573502 -87.746368) (xy 271.573502 -87.767632) (xy 271.577308 -87.777574) (xy 271.591537 -87.810493)
			(xy 271.615257 -87.878178) (xy 271.633437 -87.947558) (xy 271.640046 -87.982806) (xy 271.642344 -87.99293)
			(xy 271.653749 -88.010251) (xy 271.67107 -88.021656) (xy 271.681194 -88.023954) (xy 271.716437 -88.030584)
			(xy 271.78581 -88.04878) (xy 271.853498 -88.072487) (xy 271.886426 -88.086692) (xy 271.896368 -88.090498)
			(xy 271.917632 -88.090498) (xy 271.927574 -88.086692) (xy 271.970236 -88.068447) (xy 272.058529 -88.039903)
			(xy 272.149314 -88.02071) (xy 272.241604 -88.011077) (xy 272.288 -88.010492) (xy 272.329102 -88.010967)
			(xy 272.410957 -88.018552) (xy 272.491762 -88.033657) (xy 272.570829 -88.056153) (xy 272.647483 -88.085849)
			(xy 272.72107 -88.122491) (xy 272.790962 -88.165766) (xy 272.856563 -88.215306) (xy 272.917313 -88.270687)
			(xy 272.972694 -88.331437) (xy 273.022234 -88.397038) (xy 273.065509 -88.46693) (xy 273.102151 -88.540517)
			(xy 273.131847 -88.617171) (xy 273.154343 -88.696238) (xy 273.169448 -88.777043) (xy 273.177033 -88.858898)
			(xy 273.177508 -88.9) (xy 273.176925 -88.946396) (xy 273.16728 -89.038684) (xy 273.148084 -89.129468)
			(xy 273.119546 -89.217761) (xy 273.101308 -89.260426) (xy 273.097502 -89.270368) (xy 273.097502 -89.291632)
			(xy 273.101308 -89.301574) (xy 273.119553 -89.344236) (xy 273.148097 -89.432529) (xy 273.16729 -89.523314)
			(xy 273.176923 -89.615604) (xy 273.177508 -89.662) (xy 273.177033 -89.703102) (xy 273.169448 -89.784957)
			(xy 273.154343 -89.865762) (xy 273.131847 -89.944829) (xy 273.102151 -90.021483) (xy 273.065509 -90.09507)
			(xy 273.022234 -90.164962) (xy 272.972694 -90.230563) (xy 272.917313 -90.291313) (xy 272.856563 -90.346694)
			(xy 272.790962 -90.396234) (xy 272.72107 -90.439509) (xy 272.667144 -90.466361) (xy 275.081742 -90.466361)
			(xy 275.081742 -90.381639) (xy 275.089795 -90.297302) (xy 275.105829 -90.214112) (xy 275.129697 -90.132822)
			(xy 275.161185 -90.05417) (xy 275.200007 -89.978867) (xy 275.24581 -89.907595) (xy 275.298181 -89.840999)
			(xy 275.356646 -89.779684) (xy 275.420674 -89.724203) (xy 275.489686 -89.67506) (xy 275.563056 -89.6327)
			(xy 275.640121 -89.597505) (xy 275.720183 -89.569796) (xy 275.802516 -89.549822) (xy 275.886375 -89.537765)
			(xy 275.971 -89.533734) (xy 276.055625 -89.537765) (xy 276.139484 -89.549822) (xy 276.221817 -89.569796)
			(xy 276.301879 -89.597505) (xy 276.378944 -89.6327) (xy 276.452314 -89.67506) (xy 276.521326 -89.724203)
			(xy 276.585354 -89.779684) (xy 276.643819 -89.840999) (xy 276.69619 -89.907595) (xy 276.741993 -89.978867)
			(xy 276.780815 -90.05417) (xy 276.812303 -90.132822) (xy 276.836171 -90.214112) (xy 276.852205 -90.297302)
			(xy 276.860258 -90.381639) (xy 276.860762 -90.424) (xy 276.860258 -90.466361) (xy 276.852205 -90.550698)
			(xy 276.836171 -90.633888) (xy 276.812303 -90.715178) (xy 276.780815 -90.79383) (xy 276.741993 -90.869133)
			(xy 276.69619 -90.940405) (xy 276.643819 -91.007001) (xy 276.585354 -91.068316) (xy 276.521326 -91.123797)
			(xy 276.452314 -91.17294) (xy 276.378944 -91.2153) (xy 276.301879 -91.250495) (xy 276.221817 -91.278204)
			(xy 276.139484 -91.298178) (xy 276.055625 -91.310235) (xy 275.971 -91.314267) (xy 275.886375 -91.310235)
			(xy 275.802516 -91.298178) (xy 275.720183 -91.278204) (xy 275.640121 -91.250495) (xy 275.563056 -91.2153)
			(xy 275.489686 -91.17294) (xy 275.420674 -91.123797) (xy 275.356646 -91.068316) (xy 275.298181 -91.007001)
			(xy 275.24581 -90.940405) (xy 275.200007 -90.869133) (xy 275.161185 -90.79383) (xy 275.129697 -90.715178)
			(xy 275.105829 -90.633888) (xy 275.089795 -90.550698) (xy 275.081742 -90.466361) (xy 272.667144 -90.466361)
			(xy 272.647483 -90.476151) (xy 272.570829 -90.505847) (xy 272.491762 -90.528343) (xy 272.410957 -90.543448)
			(xy 272.329102 -90.551033) (xy 272.288 -90.551508) (xy 272.241604 -90.550925) (xy 272.149316 -90.54128)
			(xy 272.058532 -90.522084) (xy 271.970239 -90.493546) (xy 271.927574 -90.475308) (xy 271.917632 -90.471502)
			(xy 271.896368 -90.471502) (xy 271.886426 -90.475308) (xy 271.843764 -90.493553) (xy 271.755471 -90.522097)
			(xy 271.664686 -90.54129) (xy 271.572396 -90.550923) (xy 271.526 -90.551508) (xy 271.479604 -90.550925)
			(xy 271.387316 -90.54128) (xy 271.296532 -90.522084) (xy 271.208239 -90.493546) (xy 271.165574 -90.475308)
			(xy 271.155632 -90.471502) (xy 271.134368 -90.471502) (xy 271.124426 -90.475308) (xy 271.081764 -90.493553)
			(xy 270.993471 -90.522097) (xy 270.902686 -90.54129) (xy 270.810396 -90.550923) (xy 270.764 -90.551508)
			(xy 270.717604 -90.550925) (xy 270.625316 -90.54128) (xy 270.534532 -90.522084) (xy 270.446239 -90.493546)
			(xy 270.403574 -90.475308) (xy 270.393632 -90.471502) (xy 270.372368 -90.471502) (xy 270.362426 -90.475308)
			(xy 270.340242 -90.484956) (xy 270.295004 -90.502108) (xy 270.272002 -90.509598) (xy 270.258794 -90.513916)
			(xy 270.24076 -90.533982) (xy 270.21663 -90.64752) (xy 270.225266 -90.673428) (xy 270.23568 -90.682572)
			(xy 270.266746 -90.710632) (xy 270.323976 -90.771738) (xy 270.375209 -90.837953) (xy 270.419991 -90.90869)
			(xy 270.457926 -90.983323) (xy 270.488678 -91.061192) (xy 270.511974 -91.141606) (xy 270.527609 -91.223854)
			(xy 270.535444 -91.307207) (xy 270.535908 -91.349068) (xy 270.535404 -91.391416) (xy 270.527353 -91.47573)
			(xy 270.511324 -91.558896) (xy 270.487463 -91.640163) (xy 270.455984 -91.718793) (xy 270.417173 -91.794074)
			(xy 270.371383 -91.865326) (xy 270.319027 -91.931902) (xy 270.260579 -91.9932) (xy 270.196569 -92.048665)
			(xy 270.127577 -92.097794) (xy 270.054227 -92.140143) (xy 269.977184 -92.175327) (xy 269.897145 -92.203029)
			(xy 269.814836 -92.222997) (xy 269.731001 -92.23505) (xy 269.6464 -92.239081) (xy 269.561799 -92.23505)
			(xy 269.477964 -92.222997) (xy 269.395655 -92.203029) (xy 269.315616 -92.175327) (xy 269.238573 -92.140143)
			(xy 269.165223 -92.097794) (xy 269.096231 -92.048665) (xy 269.032221 -91.9932) (xy 268.973773 -91.931902)
			(xy 268.921417 -91.865326) (xy 268.875627 -91.794074) (xy 268.836816 -91.718793) (xy 268.805337 -91.640163)
			(xy 268.781476 -91.558896) (xy 268.765447 -91.47573) (xy 268.757396 -91.391416) (xy 268.756892 -91.349068)
			(xy 268.757344 -91.308052) (xy 268.764906 -91.226369) (xy 268.779953 -91.145729) (xy 268.802357 -91.066816)
			(xy 268.831929 -90.990299) (xy 268.868417 -90.916829) (xy 268.911512 -90.847029) (xy 268.960847 -90.781491)
			(xy 269.016005 -90.720771) (xy 269.045944 -90.692732) (xy 269.056104 -90.683334) (xy 269.064232 -90.656918)
			(xy 269.0368 -90.54338) (xy 269.01775 -90.523568) (xy 269.004288 -90.519758) (xy 268.964497 -90.508355)
			(xy 268.88706 -90.47909) (xy 268.812678 -90.442758) (xy 268.741992 -90.399673) (xy 268.675615 -90.350208)
			(xy 268.61412 -90.29479) (xy 268.55804 -90.233898) (xy 268.507859 -90.16806) (xy 268.464012 -90.097845)
			(xy 268.426877 -90.02386) (xy 268.396777 -89.946745) (xy 268.373971 -89.867167) (xy 268.358656 -89.785814)
			(xy 268.350965 -89.703391) (xy 268.350492 -89.662) (xy 0.509016 -89.662) (xy 0.509016 -93.399864)
			(xy 3.446023 -93.399864) (xy 3.450044 -93.286002) (xy 3.462086 -93.172708) (xy 3.482091 -93.060546)
			(xy 3.509957 -92.950074) (xy 3.545546 -92.841842) (xy 3.588681 -92.736391) (xy 3.639147 -92.634245)
			(xy 3.696693 -92.535914) (xy 3.761032 -92.441886) (xy 3.831843 -92.352631) (xy 3.908773 -92.268594)
			(xy 3.99144 -92.190192) (xy 4.079431 -92.117817) (xy 4.172308 -92.051829) (xy 4.269609 -91.992557)
			(xy 4.370848 -91.940296) (xy 4.475522 -91.895306) (xy 4.583108 -91.857812) (xy 4.693071 -91.828001)
			(xy 4.804864 -91.80602) (xy 4.917928 -91.79198) (xy 5.0317 -91.78595) (xy 5.145615 -91.787961) (xy 5.259104 -91.798002)
			(xy 5.371603 -91.816024) (xy 5.482549 -91.841936) (xy 5.591392 -91.87561) (xy 5.697588 -91.916877)
			(xy 5.800608 -91.965533) (xy 5.89994 -92.021334) (xy 5.995089 -92.084003) (xy 6.085579 -92.153228)
			(xy 6.170961 -92.228663) (xy 6.25081 -92.309934) (xy 6.324727 -92.396634) (xy 6.392343 -92.488332)
			(xy 6.453324 -92.584571) (xy 6.507363 -92.684873) (xy 6.554193 -92.788736) (xy 6.582153 -92.864629)
			(xy 270.30832 -92.864629) (xy 270.30832 -92.779907) (xy 270.316373 -92.69557) (xy 270.332407 -92.61238)
			(xy 270.356275 -92.53109) (xy 270.387763 -92.452438) (xy 270.426585 -92.377135) (xy 270.472388 -92.305863)
			(xy 270.524759 -92.239267) (xy 270.583224 -92.177952) (xy 270.647252 -92.122471) (xy 270.716264 -92.073328)
			(xy 270.789634 -92.030968) (xy 270.866699 -91.995773) (xy 270.946761 -91.968064) (xy 271.029094 -91.94809)
			(xy 271.112953 -91.936033) (xy 271.197578 -91.932002) (xy 271.282203 -91.936033) (xy 271.366062 -91.94809)
			(xy 271.448395 -91.968064) (xy 271.528457 -91.995773) (xy 271.605522 -92.030968) (xy 271.678892 -92.073328)
			(xy 271.747904 -92.122471) (xy 271.811932 -92.177952) (xy 271.870397 -92.239267) (xy 271.922768 -92.305863)
			(xy 271.968571 -92.377135) (xy 272.007393 -92.452438) (xy 272.038881 -92.53109) (xy 272.062749 -92.61238)
			(xy 272.078783 -92.69557) (xy 272.086836 -92.779907) (xy 272.08734 -92.822268) (xy 272.086836 -92.864629)
			(xy 272.078783 -92.948966) (xy 272.062749 -93.032156) (xy 272.038881 -93.113446) (xy 272.007393 -93.192098)
			(xy 271.968571 -93.267401) (xy 271.922768 -93.338673) (xy 271.870397 -93.405269) (xy 271.811932 -93.466584)
			(xy 271.747904 -93.522065) (xy 271.678892 -93.571208) (xy 271.605522 -93.613568) (xy 271.528457 -93.648763)
			(xy 271.448395 -93.676472) (xy 271.366062 -93.696446) (xy 271.282203 -93.708503) (xy 271.197578 -93.712535)
			(xy 271.112953 -93.708503) (xy 271.029094 -93.696446) (xy 270.946761 -93.676472) (xy 270.866699 -93.648763)
			(xy 270.789634 -93.613568) (xy 270.716264 -93.571208) (xy 270.647252 -93.522065) (xy 270.583224 -93.466584)
			(xy 270.524759 -93.405269) (xy 270.472388 -93.338673) (xy 270.426585 -93.267401) (xy 270.387763 -93.192098)
			(xy 270.356275 -93.113446) (xy 270.332407 -93.032156) (xy 270.316373 -92.948966) (xy 270.30832 -92.864629)
			(xy 6.582153 -92.864629) (xy 6.59358 -92.895644) (xy 6.625327 -93.005064) (xy 6.649277 -93.11645)
			(xy 6.665311 -93.229249) (xy 6.673347 -93.342898) (xy 6.67385 -93.399864) (xy 6.673347 -93.45683)
			(xy 6.665311 -93.570479) (xy 6.649277 -93.683278) (xy 6.625327 -93.794664) (xy 6.59358 -93.904084)
			(xy 6.554193 -94.010992) (xy 6.507363 -94.114855) (xy 6.453324 -94.215157) (xy 6.392343 -94.311396)
			(xy 6.324727 -94.403094) (xy 6.25081 -94.489794) (xy 6.170961 -94.571065) (xy 6.085579 -94.6465)
			(xy 5.995089 -94.715725) (xy 5.89994 -94.778394) (xy 5.800608 -94.834195) (xy 5.697588 -94.882851)
			(xy 5.591392 -94.924118) (xy 5.550527 -94.936761) (xy 273.536914 -94.936761) (xy 273.536914 -94.852039)
			(xy 273.544967 -94.767702) (xy 273.561001 -94.684512) (xy 273.584869 -94.603222) (xy 273.616357 -94.52457)
			(xy 273.655179 -94.449267) (xy 273.700982 -94.377995) (xy 273.753353 -94.311399) (xy 273.811818 -94.250084)
			(xy 273.875846 -94.194603) (xy 273.944858 -94.14546) (xy 274.018228 -94.1031) (xy 274.095293 -94.067905)
			(xy 274.175355 -94.040196) (xy 274.257688 -94.020222) (xy 274.341547 -94.008165) (xy 274.426172 -94.004134)
			(xy 274.510797 -94.008165) (xy 274.594656 -94.020222) (xy 274.676989 -94.040196) (xy 274.757051 -94.067905)
			(xy 274.834116 -94.1031) (xy 274.907486 -94.14546) (xy 274.976498 -94.194603) (xy 275.040526 -94.250084)
			(xy 275.098991 -94.311399) (xy 275.151362 -94.377995) (xy 275.197165 -94.449267) (xy 275.235987 -94.52457)
			(xy 275.267475 -94.603222) (xy 275.291343 -94.684512) (xy 275.307377 -94.767702) (xy 275.31543 -94.852039)
			(xy 275.315934 -94.8944) (xy 275.31543 -94.936761) (xy 275.307377 -95.021098) (xy 275.291343 -95.104288)
			(xy 275.267475 -95.185578) (xy 275.235987 -95.26423) (xy 275.197165 -95.339533) (xy 275.151362 -95.410805)
			(xy 275.098991 -95.477401) (xy 275.040526 -95.538716) (xy 274.976498 -95.594197) (xy 274.907486 -95.64334)
			(xy 274.834116 -95.6857) (xy 274.757051 -95.720895) (xy 274.676989 -95.748604) (xy 274.594656 -95.768578)
			(xy 274.510797 -95.780635) (xy 274.426172 -95.784667) (xy 274.341547 -95.780635) (xy 274.257688 -95.768578)
			(xy 274.175355 -95.748604) (xy 274.095293 -95.720895) (xy 274.018228 -95.6857) (xy 273.944858 -95.64334)
			(xy 273.875846 -95.594197) (xy 273.811818 -95.538716) (xy 273.753353 -95.477401) (xy 273.700982 -95.410805)
			(xy 273.655179 -95.339533) (xy 273.616357 -95.26423) (xy 273.584869 -95.185578) (xy 273.561001 -95.104288)
			(xy 273.544967 -95.021098) (xy 273.536914 -94.936761) (xy 5.550527 -94.936761) (xy 5.482549 -94.957792)
			(xy 5.371603 -94.983704) (xy 5.259104 -95.001726) (xy 5.145615 -95.011767) (xy 5.0317 -95.013778)
			(xy 4.917928 -95.007748) (xy 4.804864 -94.993708) (xy 4.693071 -94.971727) (xy 4.583108 -94.941916)
			(xy 4.475522 -94.904422) (xy 4.370848 -94.859432) (xy 4.269609 -94.807171) (xy 4.172308 -94.747899)
			(xy 4.079431 -94.681911) (xy 3.99144 -94.609536) (xy 3.908773 -94.531134) (xy 3.831843 -94.447097)
			(xy 3.761032 -94.357842) (xy 3.696693 -94.263814) (xy 3.639147 -94.165483) (xy 3.588681 -94.063337)
			(xy 3.545546 -93.957886) (xy 3.509957 -93.849654) (xy 3.482091 -93.739182) (xy 3.462086 -93.62702)
			(xy 3.450044 -93.513726) (xy 3.446023 -93.399864) (xy 0.509016 -93.399864) (xy 0.509016 -98.013)
			(xy 214.347099 -98.013) (xy 214.351129 -97.928402) (xy 214.363182 -97.844571) (xy 214.383149 -97.762265)
			(xy 214.410848 -97.682229) (xy 214.44603 -97.605189) (xy 214.488376 -97.531842) (xy 214.537502 -97.462852)
			(xy 214.592963 -97.398843) (xy 214.654257 -97.340397) (xy 214.720829 -97.288041) (xy 214.792077 -97.24225)
			(xy 214.867354 -97.203439) (xy 214.94598 -97.171959) (xy 215.027241 -97.148095) (xy 215.110404 -97.132064)
			(xy 215.194713 -97.124009) (xy 215.23706 -97.123504) (xy 215.283455 -97.1241) (xy 215.375743 -97.133741)
			(xy 215.466527 -97.152933) (xy 215.554821 -97.181468) (xy 215.597486 -97.199704) (xy 215.607428 -97.20351)
			(xy 215.628692 -97.20351) (xy 215.638634 -97.199704) (xy 215.681302 -97.181473) (xy 215.769592 -97.152925)
			(xy 215.860375 -97.133728) (xy 215.952664 -97.124091) (xy 215.99906 -97.123504) (xy 216.041067 -97.12399)
			(xy 216.124708 -97.131906) (xy 216.207231 -97.14767) (xy 216.2879 -97.171143) (xy 216.365997 -97.202116)
			(xy 216.440827 -97.240312) (xy 216.511723 -97.285392) (xy 216.578055 -97.336953) (xy 216.639231 -97.394538)
			(xy 216.667334 -97.425764) (xy 216.6747 -97.434146) (xy 216.694512 -97.443036) (xy 216.79281 -97.443036)
			(xy 216.812622 -97.434146) (xy 216.819988 -97.425764) (xy 216.848079 -97.394524) (xy 216.909243 -97.33692)
			(xy 216.975568 -97.285342) (xy 217.046463 -97.240252) (xy 217.121295 -97.202051) (xy 217.199398 -97.171081)
			(xy 217.280074 -97.147616) (xy 217.362604 -97.131868) (xy 217.446252 -97.123975) (xy 217.488262 -97.123504)
			(xy 217.534657 -97.124099) (xy 217.626945 -97.133741) (xy 217.717729 -97.152933) (xy 217.806023 -97.181468)
			(xy 217.848688 -97.199704) (xy 217.85863 -97.20351) (xy 217.879894 -97.20351) (xy 217.889836 -97.199704)
			(xy 217.932504 -97.181473) (xy 218.020794 -97.152925) (xy 218.111577 -97.133728) (xy 218.203866 -97.124091)
			(xy 218.250262 -97.123504) (xy 218.291199 -97.124004) (xy 218.372725 -97.13153) (xy 218.453216 -97.146514)
			(xy 218.531989 -97.168828) (xy 218.60838 -97.198285) (xy 218.681742 -97.234633) (xy 218.751455 -97.277567)
			(xy 218.81693 -97.326724) (xy 218.877611 -97.381687) (xy 218.932988 -97.441992) (xy 218.95816 -97.474278)
			(xy 218.965526 -97.48393) (xy 218.987116 -97.494344) (xy 219.093542 -97.492566) (xy 219.114878 -97.48139)
			(xy 219.12199 -97.471484) (xy 219.146898 -97.437102) (xy 219.202355 -97.372809) (xy 219.263686 -97.314092)
			(xy 219.330332 -97.261485) (xy 219.401687 -97.215468) (xy 219.477102 -97.176458) (xy 219.55589 -97.144811)
			(xy 219.637335 -97.120815) (xy 219.720696 -97.104688) (xy 219.805215 -97.096576) (xy 219.847668 -97.096072)
			(xy 219.894071 -97.096675) (xy 219.986369 -97.106372) (xy 220.077154 -97.125633) (xy 220.165439 -97.154247)
			(xy 220.208094 -97.172526) (xy 220.218036 -97.176332) (xy 220.2393 -97.176332) (xy 220.249242 -97.172526)
			(xy 220.291907 -97.154274) (xy 220.380194 -97.125678) (xy 220.470975 -97.106418) (xy 220.563267 -97.096703)
			(xy 220.609668 -97.096072) (xy 220.651684 -97.096525) (xy 220.73534 -97.104457) (xy 220.817875 -97.120244)
			(xy 220.898554 -97.143744) (xy 220.976656 -97.174749) (xy 221.051486 -97.212982) (xy 221.122376 -97.258102)
			(xy 221.188695 -97.309707) (xy 221.249851 -97.367337) (xy 221.277942 -97.398586) (xy 221.285308 -97.406968)
			(xy 221.30512 -97.415858) (xy 221.403418 -97.415858) (xy 221.42323 -97.406968) (xy 221.430596 -97.398586)
			(xy 221.458694 -97.367348) (xy 221.519864 -97.309741) (xy 221.586191 -97.258156) (xy 221.657084 -97.213051)
			(xy 221.731912 -97.174827) (xy 221.81001 -97.143825) (xy 221.890681 -97.120321) (xy 221.973209 -97.104524)
			(xy 222.056857 -97.096575) (xy 222.09887 -97.096072) (xy 222.145273 -97.096675) (xy 222.237571 -97.106372)
			(xy 222.328356 -97.125632) (xy 222.416641 -97.154247) (xy 222.459296 -97.172526) (xy 222.469238 -97.176332)
			(xy 222.490502 -97.176332) (xy 222.500444 -97.172526) (xy 222.543109 -97.154273) (xy 222.631395 -97.125678)
			(xy 222.722177 -97.106418) (xy 222.814469 -97.096703) (xy 222.86087 -97.096072) (xy 222.903898 -97.096585)
			(xy 222.989549 -97.104908) (xy 223.073998 -97.12146) (xy 223.156454 -97.146086) (xy 223.236148 -97.178557)
			(xy 223.312336 -97.218569) (xy 223.384305 -97.265748) (xy 223.451385 -97.319654) (xy 223.512948 -97.379783)
			(xy 223.568419 -97.445574) (xy 223.61728 -97.516413) (xy 223.638618 -97.55378) (xy 223.643347 -97.561498)
			(xy 223.657067 -97.573284) (xy 223.674025 -97.579573) (xy 223.683068 -97.579942) (xy 223.771714 -97.579942)
			(xy 223.78076 -97.579567) (xy 223.797731 -97.573298) (xy 223.811459 -97.561515) (xy 223.816164 -97.55378)
			(xy 223.837459 -97.516385) (xy 223.88631 -97.445532) (xy 223.941777 -97.379729) (xy 224.003339 -97.319589)
			(xy 224.070421 -97.265677) (xy 224.142397 -97.218495) (xy 224.218592 -97.178485) (xy 224.298296 -97.146021)
			(xy 224.380763 -97.121407) (xy 224.465221 -97.104872) (xy 224.550881 -97.096571) (xy 224.593912 -97.096072)
			(xy 224.640314 -97.096695) (xy 224.732612 -97.106386) (xy 224.823397 -97.125641) (xy 224.911682 -97.15425)
			(xy 224.954338 -97.172526) (xy 224.96428 -97.176332) (xy 224.985544 -97.176332) (xy 224.995486 -97.172526)
			(xy 225.038145 -97.154259) (xy 225.126434 -97.125668) (xy 225.217217 -97.106412) (xy 225.309511 -97.0967)
			(xy 225.355912 -97.096072) (xy 225.397927 -97.096565) (xy 225.481582 -97.104491) (xy 225.564116 -97.120273)
			(xy 225.644794 -97.143768) (xy 225.722896 -97.174768) (xy 225.797726 -97.212997) (xy 225.868618 -97.258112)
			(xy 225.934937 -97.309713) (xy 225.996095 -97.367339) (xy 226.024186 -97.398586) (xy 226.031552 -97.406968)
			(xy 226.051364 -97.415858) (xy 226.149662 -97.415858) (xy 226.169474 -97.406968) (xy 226.17684 -97.398586)
			(xy 226.204915 -97.367326) (xy 226.266088 -97.309721) (xy 226.332418 -97.258137) (xy 226.403314 -97.213033)
			(xy 226.478146 -97.174812) (xy 226.556246 -97.143813) (xy 226.63692 -97.120312) (xy 226.71945 -97.104518)
			(xy 226.8031 -97.096573) (xy 226.845114 -97.096072) (xy 226.891516 -97.096694) (xy 226.983814 -97.106386)
			(xy 227.074599 -97.125641) (xy 227.162884 -97.15425) (xy 227.20554 -97.172526) (xy 227.215482 -97.176332)
			(xy 227.236746 -97.176332) (xy 227.246688 -97.172526) (xy 227.289347 -97.154259) (xy 227.377636 -97.125667)
			(xy 227.468419 -97.106411) (xy 227.560713 -97.0967) (xy 227.607114 -97.096072) (xy 227.649476 -97.096509)
			(xy 227.733816 -97.104563) (xy 227.817008 -97.120598) (xy 227.898299 -97.144469) (xy 227.976953 -97.175958)
			(xy 228.052258 -97.214782) (xy 228.123532 -97.260588) (xy 228.190129 -97.312961) (xy 228.251445 -97.371427)
			(xy 228.306927 -97.435457) (xy 228.356071 -97.504471) (xy 228.398433 -97.577844) (xy 228.433628 -97.654912)
			(xy 228.461338 -97.734976) (xy 228.481312 -97.817311) (xy 228.493369 -97.901172) (xy 228.497401 -97.9858)
			(xy 228.496115 -98.0128) (xy 228.639776 -98.0128) (xy 228.643808 -97.928166) (xy 228.655866 -97.844299)
			(xy 228.675843 -97.761958) (xy 228.703556 -97.681889) (xy 228.738755 -97.604817) (xy 228.781121 -97.53144)
			(xy 228.830271 -97.462422) (xy 228.885758 -97.398389) (xy 228.947082 -97.339921) (xy 229.013685 -97.287547)
			(xy 229.084966 -97.241741) (xy 229.160278 -97.202918) (xy 229.238939 -97.171431) (xy 229.320238 -97.147563)
			(xy 229.403437 -97.131532) (xy 229.487783 -97.123482) (xy 229.530148 -97.122996) (xy 229.576551 -97.123604)
			(xy 229.668849 -97.133299) (xy 229.759634 -97.152558) (xy 229.847919 -97.181172) (xy 229.890574 -97.19945)
			(xy 229.900516 -97.203256) (xy 229.92178 -97.203256) (xy 229.931722 -97.19945) (xy 229.974377 -97.181173)
			(xy 230.062667 -97.152584) (xy 230.153452 -97.13333) (xy 230.245746 -97.123623) (xy 230.292148 -97.122996)
			(xy 230.334163 -97.123489) (xy 230.417817 -97.131418) (xy 230.50035 -97.147202) (xy 230.581028 -97.170698)
			(xy 230.659129 -97.201699) (xy 230.733959 -97.239927) (xy 230.80485 -97.285041) (xy 230.871171 -97.336641)
			(xy 230.93233 -97.394264) (xy 230.960422 -97.42551) (xy 230.967788 -97.433892) (xy 230.9876 -97.442782)
			(xy 231.085898 -97.442782) (xy 231.10571 -97.433892) (xy 231.113076 -97.42551) (xy 231.14119 -97.394286)
			(xy 231.202357 -97.336679) (xy 231.268682 -97.285092) (xy 231.339573 -97.239985) (xy 231.414399 -97.201759)
			(xy 231.492495 -97.170756) (xy 231.573164 -97.14725) (xy 231.65569 -97.131451) (xy 231.739338 -97.123499)
			(xy 231.78135 -97.122996) (xy 231.827753 -97.123604) (xy 231.920051 -97.133299) (xy 232.010836 -97.152558)
			(xy 232.099121 -97.181171) (xy 232.141776 -97.19945) (xy 232.151718 -97.203256) (xy 232.172982 -97.203256)
			(xy 232.182924 -97.19945) (xy 232.225592 -97.181205) (xy 232.313877 -97.152607) (xy 232.404658 -97.133345)
			(xy 232.49695 -97.123628) (xy 232.54335 -97.122996) (xy 232.586931 -97.123531) (xy 232.673673 -97.132067)
			(xy 232.759165 -97.149043) (xy 232.842588 -97.174296) (xy 232.923142 -97.207584) (xy 233.000056 -97.248588)
			(xy 233.072592 -97.296916) (xy 233.140056 -97.352103) (xy 233.201801 -97.413622) (xy 233.257236 -97.480883)
			(xy 233.30583 -97.553242) (xy 233.32694 -97.591372) (xy 233.333798 -97.604072) (xy 233.357928 -97.618296)
			(xy 233.477054 -97.616518) (xy 233.50093 -97.601532) (xy 233.50728 -97.588578) (xy 233.526 -97.552008)
			(xy 233.569301 -97.482183) (xy 233.618856 -97.416648) (xy 233.674243 -97.355962) (xy 233.734989 -97.300641)
			(xy 233.800577 -97.251157) (xy 233.870449 -97.207932) (xy 233.944009 -97.171333) (xy 234.02063 -97.141673)
			(xy 234.099659 -97.119205) (xy 234.180424 -97.104119) (xy 234.262235 -97.096545) (xy 234.303316 -97.096072)
			(xy 234.349718 -97.096694) (xy 234.442016 -97.106385) (xy 234.532801 -97.12564) (xy 234.621086 -97.15425)
			(xy 234.663742 -97.172526) (xy 234.673684 -97.176332) (xy 234.694948 -97.176332) (xy 234.70489 -97.172526)
			(xy 234.747548 -97.154258) (xy 234.835837 -97.125667) (xy 234.926621 -97.106411) (xy 235.018915 -97.0967)
			(xy 235.065316 -97.096072) (xy 235.107331 -97.096562) (xy 235.190986 -97.104489) (xy 235.27352 -97.120271)
			(xy 235.354198 -97.143767) (xy 235.4323 -97.174767) (xy 235.507131 -97.212996) (xy 235.578022 -97.258112)
			(xy 235.644341 -97.309713) (xy 235.705499 -97.367339) (xy 235.73359 -97.398586) (xy 235.740956 -97.406968)
			(xy 235.760768 -97.415858) (xy 235.859066 -97.415858) (xy 235.878878 -97.406968) (xy 235.886244 -97.398586)
			(xy 235.914369 -97.367373) (xy 235.975536 -97.309766) (xy 236.041859 -97.258179) (xy 236.112748 -97.213071)
			(xy 236.187573 -97.174845) (xy 236.265667 -97.14384) (xy 236.346335 -97.120332) (xy 236.42886 -97.104531)
			(xy 236.512506 -97.096577) (xy 236.554518 -97.096072) (xy 236.60092 -97.096693) (xy 236.693218 -97.106385)
			(xy 236.784003 -97.12564) (xy 236.872288 -97.154249) (xy 236.914944 -97.172526) (xy 236.924886 -97.176332)
			(xy 236.94615 -97.176332) (xy 236.956092 -97.172526) (xy 236.99875 -97.154257) (xy 237.087039 -97.125666)
			(xy 237.177823 -97.106411) (xy 237.270117 -97.0967) (xy 237.316518 -97.096072) (xy 237.357615 -97.096505)
			(xy 237.439458 -97.104088) (xy 237.520253 -97.119186) (xy 237.599312 -97.141671) (xy 237.675959 -97.171353)
			(xy 237.749543 -97.207976) (xy 237.819435 -97.251231) (xy 237.88504 -97.300747) (xy 237.945798 -97.356102)
			(xy 238.001192 -97.416825) (xy 238.05075 -97.482399) (xy 238.094048 -97.552263) (xy 238.112808 -97.588832)
			(xy 238.119158 -97.601786) (xy 238.143034 -97.616772) (xy 238.261906 -97.61855) (xy 238.28629 -97.604326)
			(xy 238.293148 -97.591626) (xy 238.314222 -97.553465) (xy 238.362786 -97.481062) (xy 238.4182 -97.413758)
			(xy 238.479934 -97.352199) (xy 238.547395 -97.296976) (xy 238.619936 -97.248619) (xy 238.69686 -97.207592)
			(xy 238.77743 -97.174288) (xy 238.860871 -97.149028) (xy 238.946384 -97.132052) (xy 239.033147 -97.123526)
			(xy 239.076738 -97.122996) (xy 239.123141 -97.123608) (xy 239.215438 -97.133302) (xy 239.306224 -97.15256)
			(xy 239.394509 -97.181172) (xy 239.437164 -97.19945) (xy 239.447106 -97.203256) (xy 239.46837 -97.203256)
			(xy 239.478312 -97.19945) (xy 239.520968 -97.181176) (xy 239.609258 -97.152586) (xy 239.700042 -97.133332)
			(xy 239.792337 -97.123623) (xy 239.838738 -97.122996) (xy 239.880752 -97.123496) (xy 239.964406 -97.131425)
			(xy 240.04694 -97.147207) (xy 240.127617 -97.170703) (xy 240.205719 -97.201702) (xy 240.280549 -97.239929)
			(xy 240.35144 -97.285043) (xy 240.417761 -97.336642) (xy 240.47892 -97.394265) (xy 240.507012 -97.42551)
			(xy 240.514378 -97.433892) (xy 240.53419 -97.442782) (xy 240.632488 -97.442782) (xy 240.6523 -97.433892)
			(xy 240.659666 -97.42551) (xy 240.687785 -97.394291) (xy 240.748952 -97.336683) (xy 240.815276 -97.285096)
			(xy 240.886166 -97.239989) (xy 240.960991 -97.201763) (xy 241.039086 -97.170759) (xy 241.119755 -97.147252)
			(xy 241.202281 -97.131452) (xy 241.285928 -97.1235) (xy 241.32794 -97.122996) (xy 241.374343 -97.123607)
			(xy 241.46664 -97.133301) (xy 241.557426 -97.15256) (xy 241.645711 -97.181172) (xy 241.688366 -97.19945)
			(xy 241.698308 -97.203256) (xy 241.719572 -97.203256) (xy 241.729514 -97.19945) (xy 241.77217 -97.181176)
			(xy 241.86046 -97.152585) (xy 241.951244 -97.133332) (xy 242.043539 -97.123623) (xy 242.08994 -97.122996)
			(xy 242.132297 -97.123586) (xy 242.216628 -97.131642) (xy 242.299811 -97.147678) (xy 242.381094 -97.171547)
			(xy 242.459739 -97.203035) (xy 242.535035 -97.241856) (xy 242.606301 -97.287659) (xy 242.67289 -97.340028)
			(xy 242.734199 -97.398489) (xy 242.789674 -97.462513) (xy 242.838812 -97.531521) (xy 242.881169 -97.604886)
			(xy 242.916359 -97.681946) (xy 242.944066 -97.762002) (xy 242.964038 -97.844329) (xy 242.976094 -97.928181)
			(xy 242.980125 -98.0128) (xy 242.976094 -98.097419) (xy 242.964038 -98.181271) (xy 242.944066 -98.263598)
			(xy 242.916359 -98.343654) (xy 242.881169 -98.420714) (xy 242.838812 -98.494079) (xy 242.789674 -98.563087)
			(xy 242.734199 -98.627111) (xy 242.67289 -98.685572) (xy 242.606301 -98.737941) (xy 242.535035 -98.783744)
			(xy 242.459739 -98.822565) (xy 242.381094 -98.854053) (xy 242.299811 -98.877922) (xy 242.216628 -98.893958)
			(xy 242.132297 -98.902014) (xy 242.08994 -98.90252) (xy 242.043537 -98.901915) (xy 241.951239 -98.892218)
			(xy 241.860454 -98.872958) (xy 241.772169 -98.844345) (xy 241.729514 -98.826066) (xy 241.719572 -98.82226)
			(xy 241.698308 -98.82226) (xy 241.688366 -98.826066) (xy 241.6457 -98.844315) (xy 241.557414 -98.872912)
			(xy 241.466632 -98.892172) (xy 241.374341 -98.901889) (xy 241.32794 -98.90252) (xy 241.285924 -98.902064)
			(xy 241.202268 -98.894132) (xy 241.119733 -98.878347) (xy 241.039054 -98.854846) (xy 240.960952 -98.823842)
			(xy 240.886122 -98.785609) (xy 240.815232 -98.740489) (xy 240.748913 -98.688884) (xy 240.687757 -98.631255)
			(xy 240.659666 -98.600006) (xy 240.6523 -98.591624) (xy 240.632488 -98.582734) (xy 240.53419 -98.582734)
			(xy 240.514378 -98.591624) (xy 240.507012 -98.600006) (xy 240.478908 -98.631239) (xy 240.417739 -98.688846)
			(xy 240.351413 -98.740432) (xy 240.280521 -98.785537) (xy 240.205693 -98.823762) (xy 240.127596 -98.854764)
			(xy 240.046926 -98.878269) (xy 239.964399 -98.894067) (xy 239.88075 -98.902017) (xy 239.838738 -98.90252)
			(xy 239.792335 -98.901915) (xy 239.700037 -98.892219) (xy 239.609252 -98.872959) (xy 239.520967 -98.844345)
			(xy 239.478312 -98.826066) (xy 239.46837 -98.82226) (xy 239.447106 -98.82226) (xy 239.437164 -98.826066)
			(xy 239.394498 -98.844316) (xy 239.306212 -98.872912) (xy 239.215431 -98.892173) (xy 239.123139 -98.901889)
			(xy 239.076738 -98.90252) (xy 239.035642 -98.902044) (xy 238.9538 -98.894466) (xy 238.873006 -98.879373)
			(xy 238.793948 -98.856892) (xy 238.7173 -98.827215) (xy 238.643717 -98.790595) (xy 238.573825 -98.747345)
			(xy 238.508219 -98.697833) (xy 238.44746 -98.64248) (xy 238.392066 -98.58176) (xy 238.342507 -98.516189)
			(xy 238.299208 -98.446327) (xy 238.280448 -98.40976) (xy 238.274098 -98.396806) (xy 238.250222 -98.38182)
			(xy 238.13135 -98.380042) (xy 238.106966 -98.394266) (xy 238.100108 -98.406966) (xy 238.079063 -98.445144)
			(xy 238.030497 -98.517548) (xy 237.97508 -98.584852) (xy 237.913343 -98.64641) (xy 237.845879 -98.701633)
			(xy 237.773335 -98.749989) (xy 237.696408 -98.791014) (xy 237.615835 -98.824316) (xy 237.532391 -98.849574)
			(xy 237.446875 -98.866545) (xy 237.36011 -98.875068) (xy 237.316518 -98.875596) (xy 237.270115 -98.875)
			(xy 237.177817 -98.865302) (xy 237.087031 -98.846039) (xy 236.998747 -98.817422) (xy 236.956092 -98.799142)
			(xy 236.94615 -98.795336) (xy 236.924886 -98.795336) (xy 236.914944 -98.799142) (xy 236.87228 -98.817397)
			(xy 236.783993 -98.845992) (xy 236.693211 -98.865251) (xy 236.600919 -98.874966) (xy 236.554518 -98.875596)
			(xy 236.512503 -98.875129) (xy 236.428848 -98.867197) (xy 236.346313 -98.85141) (xy 236.265636 -98.827911)
			(xy 236.187534 -98.796907) (xy 236.112704 -98.758676) (xy 236.041813 -98.713558) (xy 235.975493 -98.661956)
			(xy 235.914336 -98.604329) (xy 235.886244 -98.573082) (xy 235.878878 -98.5647) (xy 235.859066 -98.55581)
			(xy 235.760768 -98.55581) (xy 235.740956 -98.5647) (xy 235.73359 -98.573082) (xy 235.705492 -98.604321)
			(xy 235.644323 -98.661928) (xy 235.577996 -98.713514) (xy 235.507103 -98.75862) (xy 235.432275 -98.796844)
			(xy 235.354177 -98.827845) (xy 235.273506 -98.851349) (xy 235.190978 -98.867146) (xy 235.107329 -98.875094)
			(xy 235.065316 -98.875596) (xy 235.018913 -98.875001) (xy 234.926615 -98.865302) (xy 234.835829 -98.846039)
			(xy 234.747545 -98.817422) (xy 234.70489 -98.799142) (xy 234.694948 -98.795336) (xy 234.673684 -98.795336)
			(xy 234.663742 -98.799142) (xy 234.621078 -98.817397) (xy 234.532791 -98.845993) (xy 234.442009 -98.865252)
			(xy 234.349717 -98.874966) (xy 234.303316 -98.875596) (xy 234.259735 -98.875093) (xy 234.172991 -98.866554)
			(xy 234.087498 -98.849575) (xy 234.004075 -98.824318) (xy 233.92352 -98.791027) (xy 233.846606 -98.750019)
			(xy 233.77407 -98.701689) (xy 233.706607 -98.646498) (xy 233.644862 -98.584976) (xy 233.589428 -98.517712)
			(xy 233.540836 -98.445351) (xy 233.519726 -98.40722) (xy 233.512868 -98.39452) (xy 233.488738 -98.380296)
			(xy 233.369612 -98.382074) (xy 233.345736 -98.39706) (xy 233.339386 -98.410014) (xy 233.320611 -98.446555)
			(xy 233.277315 -98.516379) (xy 233.227765 -98.581914) (xy 233.172384 -98.6426) (xy 233.111643 -98.697922)
			(xy 233.04606 -98.747408) (xy 232.976193 -98.790636) (xy 232.902638 -98.827237) (xy 232.826022 -98.856901)
			(xy 232.746997 -98.879374) (xy 232.666237 -98.894464) (xy 232.584429 -98.902044) (xy 232.54335 -98.90252)
			(xy 232.496947 -98.901911) (xy 232.40465 -98.892216) (xy 232.313864 -98.872957) (xy 232.225579 -98.844344)
			(xy 232.182924 -98.826066) (xy 232.172982 -98.82226) (xy 232.151718 -98.82226) (xy 232.141776 -98.826066)
			(xy 232.099108 -98.844312) (xy 232.010823 -98.872909) (xy 231.920042 -98.892171) (xy 231.82775 -98.901888)
			(xy 231.78135 -98.90252) (xy 231.739335 -98.902057) (xy 231.655679 -98.894126) (xy 231.573143 -98.878341)
			(xy 231.492465 -98.854842) (xy 231.414363 -98.823839) (xy 231.339533 -98.785607) (xy 231.268642 -98.740488)
			(xy 231.202323 -98.688883) (xy 231.141167 -98.631254) (xy 231.113076 -98.600006) (xy 231.10571 -98.591624)
			(xy 231.085898 -98.582734) (xy 230.9876 -98.582734) (xy 230.967788 -98.591624) (xy 230.960422 -98.600006)
			(xy 230.932313 -98.631234) (xy 230.871144 -98.688841) (xy 230.804819 -98.740427) (xy 230.733927 -98.785534)
			(xy 230.659101 -98.823758) (xy 230.581005 -98.854761) (xy 230.500334 -98.878267) (xy 230.417808 -98.894066)
			(xy 230.33416 -98.902017) (xy 230.292148 -98.90252) (xy 230.245745 -98.901912) (xy 230.153448 -98.892216)
			(xy 230.062662 -98.872957) (xy 229.974377 -98.844344) (xy 229.931722 -98.826066) (xy 229.92178 -98.82226)
			(xy 229.900516 -98.82226) (xy 229.890574 -98.826066) (xy 229.847907 -98.844312) (xy 229.759621 -98.87291)
			(xy 229.66884 -98.892171) (xy 229.576548 -98.901889) (xy 229.530148 -98.90252) (xy 229.487783 -98.902118)
			(xy 229.403437 -98.894068) (xy 229.320238 -98.878037) (xy 229.238939 -98.854169) (xy 229.160278 -98.822682)
			(xy 229.084966 -98.783859) (xy 229.013685 -98.738053) (xy 228.947082 -98.685679) (xy 228.885758 -98.627211)
			(xy 228.830271 -98.563178) (xy 228.781121 -98.49416) (xy 228.738755 -98.420783) (xy 228.703556 -98.343711)
			(xy 228.675843 -98.263642) (xy 228.655866 -98.181301) (xy 228.643808 -98.097434) (xy 228.639776 -98.0128)
			(xy 228.496115 -98.0128) (xy 228.493369 -98.070428) (xy 228.481312 -98.154289) (xy 228.461338 -98.236624)
			(xy 228.433628 -98.316688) (xy 228.398433 -98.393756) (xy 228.356071 -98.467129) (xy 228.306927 -98.536143)
			(xy 228.251445 -98.600173) (xy 228.190129 -98.658639) (xy 228.123532 -98.711012) (xy 228.052258 -98.756818)
			(xy 227.976953 -98.795642) (xy 227.898299 -98.827131) (xy 227.817008 -98.851002) (xy 227.733816 -98.867037)
			(xy 227.649476 -98.875091) (xy 227.607114 -98.875596) (xy 227.560711 -98.875002) (xy 227.468413 -98.865303)
			(xy 227.377627 -98.84604) (xy 227.289343 -98.817422) (xy 227.246688 -98.799142) (xy 227.236746 -98.795336)
			(xy 227.215482 -98.795336) (xy 227.20554 -98.799142) (xy 227.162877 -98.817398) (xy 227.07459 -98.845993)
			(xy 226.983807 -98.865252) (xy 226.891515 -98.874966) (xy 226.845114 -98.875596) (xy 226.803099 -98.875132)
			(xy 226.719443 -98.867199) (xy 226.636909 -98.851412) (xy 226.556231 -98.827912) (xy 226.47813 -98.796908)
			(xy 226.4033 -98.758677) (xy 226.332409 -98.713559) (xy 226.266089 -98.661956) (xy 226.204932 -98.604329)
			(xy 226.17684 -98.573082) (xy 226.169474 -98.5647) (xy 226.149662 -98.55581) (xy 226.051364 -98.55581)
			(xy 226.031552 -98.5647) (xy 226.024186 -98.573082) (xy 225.996091 -98.604322) (xy 225.93492 -98.66193)
			(xy 225.868594 -98.713516) (xy 225.7977 -98.758621) (xy 225.722872 -98.796845) (xy 225.644774 -98.827847)
			(xy 225.564102 -98.85135) (xy 225.481574 -98.867146) (xy 225.397925 -98.875094) (xy 225.355912 -98.875596)
			(xy 225.309509 -98.875003) (xy 225.217211 -98.865303) (xy 225.126425 -98.84604) (xy 225.038141 -98.817423)
			(xy 224.995486 -98.799142) (xy 224.985544 -98.795336) (xy 224.96428 -98.795336) (xy 224.954338 -98.799142)
			(xy 224.911675 -98.817399) (xy 224.823388 -98.845994) (xy 224.732606 -98.865252) (xy 224.640313 -98.874966)
			(xy 224.593912 -98.875596) (xy 224.550884 -98.875115) (xy 224.46523 -98.866789) (xy 224.380781 -98.850235)
			(xy 224.298323 -98.825606) (xy 224.218628 -98.793132) (xy 224.14244 -98.753118) (xy 224.070471 -98.705935)
			(xy 224.003392 -98.652026) (xy 223.94183 -98.591893) (xy 223.88636 -98.526099) (xy 223.837501 -98.455257)
			(xy 223.816164 -98.417888) (xy 223.811456 -98.410156) (xy 223.797725 -98.398375) (xy 223.78076 -98.392092)
			(xy 223.771714 -98.391726) (xy 223.683068 -98.391726) (xy 223.674022 -98.392104) (xy 223.657053 -98.398374)
			(xy 223.643325 -98.410155) (xy 223.638618 -98.417888) (xy 223.61725 -98.45524) (xy 223.568406 -98.526093)
			(xy 223.512948 -98.591898) (xy 223.451394 -98.652039) (xy 223.38432 -98.705954) (xy 223.312352 -98.753139)
			(xy 223.236163 -98.793153) (xy 223.156466 -98.825623) (xy 223.074006 -98.850243) (xy 222.989554 -98.866785)
			(xy 222.903899 -98.875093) (xy 222.86087 -98.875596) (xy 222.814467 -98.874982) (xy 222.72217 -98.865289)
			(xy 222.631384 -98.846031) (xy 222.5431 -98.81742) (xy 222.500444 -98.799142) (xy 222.490502 -98.795336)
			(xy 222.469238 -98.795336) (xy 222.459296 -98.799142) (xy 222.416639 -98.817413) (xy 222.328349 -98.846004)
			(xy 222.237565 -98.865259) (xy 222.145271 -98.874969) (xy 222.09887 -98.875596) (xy 222.056856 -98.875093)
			(xy 221.973202 -98.867165) (xy 221.890668 -98.851383) (xy 221.809991 -98.827888) (xy 221.731889 -98.796889)
			(xy 221.657059 -98.758662) (xy 221.586168 -98.713549) (xy 221.519847 -98.66195) (xy 221.458688 -98.604327)
			(xy 221.430596 -98.573082) (xy 221.42323 -98.5647) (xy 221.403418 -98.55581) (xy 221.30512 -98.55581)
			(xy 221.285308 -98.5647) (xy 221.277942 -98.573082) (xy 221.249817 -98.604295) (xy 221.188651 -98.661904)
			(xy 221.122328 -98.713491) (xy 221.051439 -98.758599) (xy 220.976614 -98.796826) (xy 220.89852 -98.827831)
			(xy 220.817851 -98.851338) (xy 220.735326 -98.867139) (xy 220.65168 -98.875092) (xy 220.609668 -98.875596)
			(xy 220.563265 -98.874983) (xy 220.470968 -98.865289) (xy 220.380182 -98.846032) (xy 220.291898 -98.81742)
			(xy 220.249242 -98.799142) (xy 220.2393 -98.795336) (xy 220.218036 -98.795336) (xy 220.208094 -98.799142)
			(xy 220.165437 -98.817413) (xy 220.077147 -98.846004) (xy 219.986363 -98.865259) (xy 219.894069 -98.874969)
			(xy 219.847668 -98.875596) (xy 219.806723 -98.875148) (xy 219.725182 -98.867601) (xy 219.644679 -98.852594)
			(xy 219.565896 -98.830252) (xy 219.489499 -98.800765) (xy 219.416135 -98.764383) (xy 219.346425 -98.721413)
			(xy 219.280958 -98.672219) (xy 219.220289 -98.617217) (xy 219.164931 -98.556873) (xy 219.13977 -98.524568)
			(xy 219.132404 -98.514916) (xy 219.110814 -98.504502) (xy 219.004388 -98.50628) (xy 218.983052 -98.517456)
			(xy 218.97594 -98.527362) (xy 218.950986 -98.561702) (xy 218.895528 -98.625977) (xy 218.834198 -98.684675)
			(xy 218.767553 -98.737261) (xy 218.6962 -98.783257) (xy 218.620789 -98.822245) (xy 218.542006 -98.853868)
			(xy 218.460568 -98.87784) (xy 218.377216 -98.893943) (xy 218.292709 -98.902029) (xy 218.250262 -98.90252)
			(xy 218.203867 -98.901914) (xy 218.111579 -98.892276) (xy 218.020796 -98.873086) (xy 217.932501 -98.844555)
			(xy 217.889836 -98.82632) (xy 217.879894 -98.822514) (xy 217.85863 -98.822514) (xy 217.848688 -98.82632)
			(xy 217.806031 -98.844578) (xy 217.717737 -98.873118) (xy 217.62695 -98.892308) (xy 217.534659 -98.901937)
			(xy 217.488262 -98.90252) (xy 217.446255 -98.90201) (xy 217.362615 -98.894097) (xy 217.280094 -98.878335)
			(xy 217.199425 -98.854865) (xy 217.121328 -98.823895) (xy 217.046498 -98.785702) (xy 216.975601 -98.740625)
			(xy 216.909269 -98.689066) (xy 216.848092 -98.631484) (xy 216.819988 -98.60026) (xy 216.812622 -98.591878)
			(xy 216.79281 -98.582988) (xy 216.694512 -98.582988) (xy 216.6747 -98.591878) (xy 216.667334 -98.60026)
			(xy 216.639237 -98.631494) (xy 216.578074 -98.689098) (xy 216.511749 -98.740675) (xy 216.440855 -98.785766)
			(xy 216.366023 -98.823967) (xy 216.287921 -98.854938) (xy 216.207246 -98.878404) (xy 216.124717 -98.894154)
			(xy 216.04107 -98.902048) (xy 215.99906 -98.90252) (xy 215.952665 -98.901915) (xy 215.860377 -98.892276)
			(xy 215.769594 -98.873087) (xy 215.681299 -98.844555) (xy 215.638634 -98.82632) (xy 215.628692 -98.822514)
			(xy 215.607428 -98.822514) (xy 215.597486 -98.82632) (xy 215.55483 -98.844579) (xy 215.466535 -98.873119)
			(xy 215.375748 -98.892308) (xy 215.283457 -98.901937) (xy 215.23706 -98.90252) (xy 215.194713 -98.901991)
			(xy 215.110404 -98.893936) (xy 215.027241 -98.877905) (xy 214.94598 -98.854041) (xy 214.867354 -98.822561)
			(xy 214.792077 -98.78375) (xy 214.720829 -98.737959) (xy 214.654257 -98.685603) (xy 214.592963 -98.627157)
			(xy 214.537502 -98.563148) (xy 214.488376 -98.494158) (xy 214.44603 -98.420811) (xy 214.410848 -98.343771)
			(xy 214.383149 -98.263735) (xy 214.363182 -98.181429) (xy 214.351129 -98.097598) (xy 214.347099 -98.013)
			(xy 0.509016 -98.013) (xy 0.509016 -101.388361) (xy 214.756742 -101.388361) (xy 214.756742 -101.303639)
			(xy 214.764795 -101.219302) (xy 214.780829 -101.136112) (xy 214.804697 -101.054822) (xy 214.836185 -100.97617)
			(xy 214.875007 -100.900867) (xy 214.92081 -100.829595) (xy 214.973181 -100.762999) (xy 215.031646 -100.701684)
			(xy 215.095674 -100.646203) (xy 215.164686 -100.59706) (xy 215.238056 -100.5547) (xy 215.315121 -100.519505)
			(xy 215.395183 -100.491796) (xy 215.477516 -100.471822) (xy 215.561375 -100.459765) (xy 215.646 -100.455734)
			(xy 215.730625 -100.459765) (xy 215.814484 -100.471822) (xy 215.896817 -100.491796) (xy 215.976879 -100.519505)
			(xy 216.053944 -100.5547) (xy 216.127314 -100.59706) (xy 216.196326 -100.646203) (xy 216.260354 -100.701684)
			(xy 216.318819 -100.762999) (xy 216.37119 -100.829595) (xy 216.416993 -100.900867) (xy 216.455815 -100.97617)
			(xy 216.487303 -101.054822) (xy 216.511171 -101.136112) (xy 216.527205 -101.219302) (xy 216.535258 -101.303639)
			(xy 216.535762 -101.346) (xy 216.535258 -101.388361) (xy 216.527205 -101.472698) (xy 216.511171 -101.555888)
			(xy 216.487303 -101.637178) (xy 216.455815 -101.71583) (xy 216.450056 -101.727) (xy 268.350492 -101.727)
			(xy 268.351075 -101.680604) (xy 268.36072 -101.588316) (xy 268.379916 -101.497532) (xy 268.408454 -101.409239)
			(xy 268.426692 -101.366574) (xy 268.430498 -101.356632) (xy 268.430498 -101.335368) (xy 268.426692 -101.325426)
			(xy 268.408447 -101.282764) (xy 268.379903 -101.194471) (xy 268.36071 -101.103686) (xy 268.351077 -101.011396)
			(xy 268.350492 -100.965) (xy 268.351075 -100.918604) (xy 268.36072 -100.826316) (xy 268.379916 -100.735532)
			(xy 268.408454 -100.647239) (xy 268.426692 -100.604574) (xy 268.430498 -100.594632) (xy 268.430498 -100.573368)
			(xy 268.426692 -100.563426) (xy 268.408447 -100.520764) (xy 268.379903 -100.432471) (xy 268.36071 -100.341686)
			(xy 268.351077 -100.249396) (xy 268.350492 -100.203) (xy 268.351075 -100.156604) (xy 268.36072 -100.064316)
			(xy 268.379916 -99.973532) (xy 268.408454 -99.885239) (xy 268.426692 -99.842574) (xy 268.430498 -99.832632)
			(xy 268.430498 -99.811368) (xy 268.426692 -99.801426) (xy 268.408447 -99.758764) (xy 268.379903 -99.670471)
			(xy 268.36071 -99.579686) (xy 268.351077 -99.487396) (xy 268.350492 -99.441) (xy 268.351075 -99.394604)
			(xy 268.36072 -99.302316) (xy 268.379916 -99.211532) (xy 268.408454 -99.123239) (xy 268.426692 -99.080574)
			(xy 268.430498 -99.070632) (xy 268.430498 -99.049368) (xy 268.426692 -99.039426) (xy 268.408447 -98.996764)
			(xy 268.379903 -98.908471) (xy 268.36071 -98.817686) (xy 268.351077 -98.725396) (xy 268.350492 -98.679)
			(xy 268.351075 -98.632604) (xy 268.36072 -98.540316) (xy 268.379916 -98.449532) (xy 268.408454 -98.361239)
			(xy 268.426692 -98.318574) (xy 268.430498 -98.308632) (xy 268.430498 -98.287368) (xy 268.426692 -98.277426)
			(xy 268.408447 -98.234764) (xy 268.379903 -98.146471) (xy 268.36071 -98.055686) (xy 268.351077 -97.963396)
			(xy 268.350492 -97.917) (xy 268.350967 -97.875898) (xy 268.358552 -97.794043) (xy 268.373657 -97.713238)
			(xy 268.396153 -97.634171) (xy 268.425849 -97.557517) (xy 268.462491 -97.48393) (xy 268.505766 -97.414038)
			(xy 268.555306 -97.348437) (xy 268.610687 -97.287687) (xy 268.671437 -97.232306) (xy 268.737038 -97.182766)
			(xy 268.80693 -97.139491) (xy 268.880517 -97.102849) (xy 268.957171 -97.073153) (xy 269.036238 -97.050657)
			(xy 269.117043 -97.035552) (xy 269.198898 -97.027967) (xy 269.24 -97.027492) (xy 269.286396 -97.028075)
			(xy 269.378684 -97.03772) (xy 269.469468 -97.056916) (xy 269.557761 -97.085454) (xy 269.600426 -97.103692)
			(xy 269.610368 -97.107498) (xy 269.631632 -97.107498) (xy 269.641574 -97.103692) (xy 269.684236 -97.085447)
			(xy 269.772529 -97.056903) (xy 269.863314 -97.03771) (xy 269.955604 -97.028077) (xy 270.002 -97.027492)
			(xy 270.048396 -97.028075) (xy 270.140684 -97.03772) (xy 270.231468 -97.056916) (xy 270.319761 -97.085454)
			(xy 270.362426 -97.103692) (xy 270.372368 -97.107498) (xy 270.393632 -97.107498) (xy 270.403574 -97.103692)
			(xy 270.446236 -97.085447) (xy 270.534529 -97.056903) (xy 270.625314 -97.03771) (xy 270.717604 -97.028077)
			(xy 270.764 -97.027492) (xy 270.810396 -97.028075) (xy 270.902684 -97.03772) (xy 270.993468 -97.056916)
			(xy 271.081761 -97.085454) (xy 271.124426 -97.103692) (xy 271.134368 -97.107498) (xy 271.155632 -97.107498)
			(xy 271.165574 -97.103692) (xy 271.208236 -97.085447) (xy 271.296529 -97.056903) (xy 271.387314 -97.03771)
			(xy 271.479604 -97.028077) (xy 271.526 -97.027492) (xy 271.572396 -97.028075) (xy 271.664684 -97.03772)
			(xy 271.755468 -97.056916) (xy 271.843761 -97.085454) (xy 271.886426 -97.103692) (xy 271.896368 -97.107498)
			(xy 271.917632 -97.107498) (xy 271.927574 -97.103692) (xy 271.970236 -97.085447) (xy 272.058529 -97.056903)
			(xy 272.149314 -97.03771) (xy 272.241604 -97.028077) (xy 272.288 -97.027492) (xy 272.329102 -97.027967)
			(xy 272.410957 -97.035552) (xy 272.491762 -97.050657) (xy 272.570829 -97.073153) (xy 272.647483 -97.102849)
			(xy 272.72107 -97.139491) (xy 272.790962 -97.182766) (xy 272.856563 -97.232306) (xy 272.917313 -97.287687)
			(xy 272.972694 -97.348437) (xy 273.022234 -97.414038) (xy 273.065509 -97.48393) (xy 273.102151 -97.557517)
			(xy 273.131847 -97.634171) (xy 273.154343 -97.713238) (xy 273.169448 -97.794043) (xy 273.177033 -97.875898)
			(xy 273.177508 -97.917) (xy 273.176925 -97.963396) (xy 273.16728 -98.055684) (xy 273.148084 -98.146468)
			(xy 273.119546 -98.234761) (xy 273.101308 -98.277426) (xy 273.097502 -98.287368) (xy 273.097502 -98.308632)
			(xy 273.101308 -98.318574) (xy 273.119553 -98.361236) (xy 273.148097 -98.449529) (xy 273.16729 -98.540314)
			(xy 273.176923 -98.632604) (xy 273.177508 -98.679) (xy 273.177033 -98.720102) (xy 273.169448 -98.801957)
			(xy 273.154343 -98.882762) (xy 273.131847 -98.961829) (xy 273.102151 -99.038483) (xy 273.065509 -99.11207)
			(xy 273.022234 -99.181962) (xy 272.972694 -99.247563) (xy 272.917313 -99.308313) (xy 272.856563 -99.363694)
			(xy 272.790962 -99.413234) (xy 272.72107 -99.456509) (xy 272.647483 -99.493151) (xy 272.570829 -99.522847)
			(xy 272.491762 -99.545343) (xy 272.410957 -99.560448) (xy 272.329102 -99.568033) (xy 272.288 -99.568508)
			(xy 272.241604 -99.567925) (xy 272.149316 -99.55828) (xy 272.058532 -99.539084) (xy 271.970239 -99.510546)
			(xy 271.927574 -99.492308) (xy 271.917632 -99.488502) (xy 271.896368 -99.488502) (xy 271.886426 -99.492308)
			(xy 271.853507 -99.506537) (xy 271.785822 -99.530257) (xy 271.716442 -99.548437) (xy 271.681194 -99.555046)
			(xy 271.67107 -99.557344) (xy 271.653749 -99.568749) (xy 271.642344 -99.58607) (xy 271.640046 -99.596194)
			(xy 271.633416 -99.631437) (xy 271.61522 -99.70081) (xy 271.591513 -99.768498) (xy 271.577308 -99.801426)
			(xy 271.573502 -99.811368) (xy 271.573502 -99.832632) (xy 271.577308 -99.842574) (xy 271.591537 -99.875493)
			(xy 271.615257 -99.943178) (xy 271.633437 -100.012558) (xy 271.640046 -100.047806) (xy 271.642344 -100.05793)
			(xy 271.653749 -100.075251) (xy 271.67107 -100.086656) (xy 271.681194 -100.088954) (xy 271.716437 -100.095584)
			(xy 271.78581 -100.11378) (xy 271.853498 -100.137487) (xy 271.886426 -100.151692) (xy 271.896368 -100.155498)
			(xy 271.917632 -100.155498) (xy 271.927574 -100.151692) (xy 271.970236 -100.133447) (xy 272.058529 -100.104903)
			(xy 272.149314 -100.08571) (xy 272.241604 -100.076077) (xy 272.288 -100.075492) (xy 272.329102 -100.075967)
			(xy 272.410957 -100.083552) (xy 272.491762 -100.098657) (xy 272.570829 -100.121153) (xy 272.647483 -100.150849)
			(xy 272.72107 -100.187491) (xy 272.790962 -100.230766) (xy 272.856563 -100.280306) (xy 272.917313 -100.335687)
			(xy 272.972694 -100.396437) (xy 273.022234 -100.462038) (xy 273.065509 -100.53193) (xy 273.102151 -100.605517)
			(xy 273.131847 -100.682171) (xy 273.154343 -100.761238) (xy 273.169448 -100.842043) (xy 273.177033 -100.923898)
			(xy 273.177508 -100.965) (xy 273.176925 -101.011396) (xy 273.16728 -101.103684) (xy 273.148084 -101.194468)
			(xy 273.119546 -101.282761) (xy 273.101308 -101.325426) (xy 273.097502 -101.335368) (xy 273.097502 -101.356632)
			(xy 273.101308 -101.366574) (xy 273.119553 -101.409236) (xy 273.148097 -101.497529) (xy 273.16729 -101.588314)
			(xy 273.176923 -101.680604) (xy 273.177508 -101.727) (xy 273.177087 -101.76701) (xy 273.169907 -101.846708)
			(xy 273.155596 -101.925439) (xy 273.134269 -102.002565) (xy 273.106099 -102.077463) (xy 273.071314 -102.149528)
			(xy 273.030196 -102.218176) (xy 272.983076 -102.282852) (xy 272.957036 -102.313232) (xy 272.947892 -102.3239)
			(xy 272.942812 -102.350824) (xy 272.982436 -102.460806) (xy 273.003518 -102.478332) (xy 273.017488 -102.480618)
			(xy 273.058748 -102.487682) (xy 273.139783 -102.5087) (xy 273.202283 -102.531361) (xy 275.081742 -102.531361)
			(xy 275.081742 -102.446639) (xy 275.089795 -102.362302) (xy 275.105829 -102.279112) (xy 275.129697 -102.197822)
			(xy 275.161185 -102.11917) (xy 275.200007 -102.043867) (xy 275.24581 -101.972595) (xy 275.298181 -101.905999)
			(xy 275.356646 -101.844684) (xy 275.420674 -101.789203) (xy 275.489686 -101.74006) (xy 275.563056 -101.6977)
			(xy 275.640121 -101.662505) (xy 275.720183 -101.634796) (xy 275.802516 -101.614822) (xy 275.886375 -101.602765)
			(xy 275.971 -101.598734) (xy 276.055625 -101.602765) (xy 276.139484 -101.614822) (xy 276.221817 -101.634796)
			(xy 276.301879 -101.662505) (xy 276.378944 -101.6977) (xy 276.452314 -101.74006) (xy 276.521326 -101.789203)
			(xy 276.585354 -101.844684) (xy 276.643819 -101.905999) (xy 276.69619 -101.972595) (xy 276.741993 -102.043867)
			(xy 276.780815 -102.11917) (xy 276.812303 -102.197822) (xy 276.836171 -102.279112) (xy 276.852205 -102.362302)
			(xy 276.860258 -102.446639) (xy 276.860762 -102.489) (xy 276.860258 -102.531361) (xy 276.852205 -102.615698)
			(xy 276.836171 -102.698888) (xy 276.812303 -102.780178) (xy 276.780815 -102.85883) (xy 276.741993 -102.934133)
			(xy 276.69619 -103.005405) (xy 276.643819 -103.072001) (xy 276.585354 -103.133316) (xy 276.521326 -103.188797)
			(xy 276.452314 -103.23794) (xy 276.378944 -103.2803) (xy 276.301879 -103.315495) (xy 276.221817 -103.343204)
			(xy 276.139484 -103.363178) (xy 276.055625 -103.375235) (xy 275.971 -103.379267) (xy 275.886375 -103.375235)
			(xy 275.802516 -103.363178) (xy 275.720183 -103.343204) (xy 275.640121 -103.315495) (xy 275.563056 -103.2803)
			(xy 275.489686 -103.23794) (xy 275.420674 -103.188797) (xy 275.356646 -103.133316) (xy 275.298181 -103.072001)
			(xy 275.24581 -103.005405) (xy 275.200007 -102.934133) (xy 275.161185 -102.85883) (xy 275.129697 -102.780178)
			(xy 275.105829 -102.698888) (xy 275.089795 -102.615698) (xy 275.081742 -102.531361) (xy 273.202283 -102.531361)
			(xy 273.218486 -102.537236) (xy 273.29416 -102.573039) (xy 273.366137 -102.615792) (xy 273.43378 -102.665117)
			(xy 273.49649 -102.720577) (xy 273.553714 -102.781682) (xy 273.604945 -102.847892) (xy 273.649731 -102.918622)
			(xy 273.687675 -102.993246) (xy 273.718442 -103.071104) (xy 273.741759 -103.151508) (xy 273.757421 -103.233746)
			(xy 273.76529 -103.317092) (xy 273.765772 -103.35895) (xy 273.765268 -103.401298) (xy 273.757217 -103.485612)
			(xy 273.741188 -103.568778) (xy 273.717327 -103.650045) (xy 273.685848 -103.728675) (xy 273.647037 -103.803956)
			(xy 273.601247 -103.875208) (xy 273.548891 -103.941784) (xy 273.490443 -104.003082) (xy 273.426433 -104.058547)
			(xy 273.357441 -104.107676) (xy 273.284091 -104.150025) (xy 273.207048 -104.185209) (xy 273.127009 -104.212911)
			(xy 273.0447 -104.232879) (xy 272.960865 -104.244932) (xy 272.876264 -104.248963) (xy 272.791663 -104.244932)
			(xy 272.707828 -104.232879) (xy 272.625519 -104.212911) (xy 272.54548 -104.185209) (xy 272.468437 -104.150025)
			(xy 272.395087 -104.107676) (xy 272.326095 -104.058547) (xy 272.262085 -104.003082) (xy 272.203637 -103.941784)
			(xy 272.151281 -103.875208) (xy 272.105491 -103.803956) (xy 272.06668 -103.728675) (xy 272.035201 -103.650045)
			(xy 272.01134 -103.568778) (xy 271.995311 -103.485612) (xy 271.98726 -103.401298) (xy 271.986756 -103.35895)
			(xy 271.987216 -103.318941) (xy 271.994392 -103.239244) (xy 272.008698 -103.160515) (xy 272.03002 -103.083389)
			(xy 272.058184 -103.008491) (xy 272.092963 -102.936426) (xy 272.134076 -102.867777) (xy 272.181191 -102.803099)
			(xy 272.207228 -102.772718) (xy 272.216372 -102.76205) (xy 272.221452 -102.735126) (xy 272.181828 -102.625144)
			(xy 272.160746 -102.607618) (xy 272.146776 -102.605332) (xy 272.109108 -102.598853) (xy 272.034963 -102.580278)
			(xy 271.962681 -102.555417) (xy 271.927574 -102.540308) (xy 271.917632 -102.536502) (xy 271.896368 -102.536502)
			(xy 271.886426 -102.540308) (xy 271.843764 -102.558553) (xy 271.755471 -102.587097) (xy 271.664686 -102.60629)
			(xy 271.572396 -102.615923) (xy 271.526 -102.616508) (xy 271.479604 -102.615925) (xy 271.387316 -102.60628)
			(xy 271.296532 -102.587084) (xy 271.208239 -102.558546) (xy 271.165574 -102.540308) (xy 271.155632 -102.536502)
			(xy 271.134368 -102.536502) (xy 271.124426 -102.540308) (xy 271.081764 -102.558553) (xy 270.993471 -102.587097)
			(xy 270.902686 -102.60629) (xy 270.810396 -102.615923) (xy 270.764 -102.616508) (xy 270.717604 -102.615925)
			(xy 270.625316 -102.60628) (xy 270.534532 -102.587084) (xy 270.446239 -102.558546) (xy 270.403574 -102.540308)
			(xy 270.393632 -102.536502) (xy 270.372368 -102.536502) (xy 270.362426 -102.540308) (xy 270.319764 -102.558553)
			(xy 270.231471 -102.587097) (xy 270.140686 -102.60629) (xy 270.048396 -102.615923) (xy 270.002 -102.616508)
			(xy 269.955604 -102.615925) (xy 269.863316 -102.60628) (xy 269.772532 -102.587084) (xy 269.684239 -102.558546)
			(xy 269.641574 -102.540308) (xy 269.631632 -102.536502) (xy 269.610368 -102.536502) (xy 269.600426 -102.540308)
			(xy 269.557764 -102.558553) (xy 269.469471 -102.587097) (xy 269.378686 -102.60629) (xy 269.286396 -102.615923)
			(xy 269.24 -102.616508) (xy 269.198898 -102.616033) (xy 269.117043 -102.608448) (xy 269.036238 -102.593343)
			(xy 268.957171 -102.570847) (xy 268.880517 -102.541151) (xy 268.80693 -102.504509) (xy 268.737038 -102.461234)
			(xy 268.671437 -102.411694) (xy 268.610687 -102.356313) (xy 268.555306 -102.295563) (xy 268.505766 -102.229962)
			(xy 268.462491 -102.16007) (xy 268.425849 -102.086483) (xy 268.396153 -102.009829) (xy 268.373657 -101.930762)
			(xy 268.358552 -101.849957) (xy 268.350967 -101.768102) (xy 268.350492 -101.727) (xy 216.450056 -101.727)
			(xy 216.416993 -101.791133) (xy 216.37119 -101.862405) (xy 216.318819 -101.929001) (xy 216.260354 -101.990316)
			(xy 216.196326 -102.045797) (xy 216.127314 -102.09494) (xy 216.053944 -102.1373) (xy 215.976879 -102.172495)
			(xy 215.896817 -102.200204) (xy 215.814484 -102.220178) (xy 215.730625 -102.232235) (xy 215.646 -102.236267)
			(xy 215.561375 -102.232235) (xy 215.477516 -102.220178) (xy 215.395183 -102.200204) (xy 215.315121 -102.172495)
			(xy 215.238056 -102.1373) (xy 215.164686 -102.09494) (xy 215.095674 -102.045797) (xy 215.031646 -101.990316)
			(xy 214.973181 -101.929001) (xy 214.92081 -101.862405) (xy 214.875007 -101.791133) (xy 214.836185 -101.71583)
			(xy 214.804697 -101.637178) (xy 214.780829 -101.555888) (xy 214.764795 -101.472698) (xy 214.756742 -101.388361)
			(xy 0.509016 -101.388361) (xy 0.509016 -108.3818) (xy 28.498292 -108.3818) (xy 28.498875 -108.335404)
			(xy 28.50852 -108.243116) (xy 28.527716 -108.152332) (xy 28.556254 -108.064039) (xy 28.574492 -108.021374)
			(xy 28.578397 -108.011452) (xy 28.578397 -107.990148) (xy 28.574492 -107.980226) (xy 28.556247 -107.937564)
			(xy 28.527703 -107.849271) (xy 28.50851 -107.758486) (xy 28.498877 -107.666196) (xy 28.498292 -107.6198)
			(xy 28.498723 -107.581372) (xy 28.505365 -107.504803) (xy 28.518591 -107.429093) (xy 28.538303 -107.354808)
			(xy 28.564353 -107.282501) (xy 28.58008 -107.247436) (xy 28.584223 -107.237163) (xy 28.584223 -107.215037)
			(xy 28.58008 -107.204764) (xy 28.564356 -107.169698) (xy 28.53831 -107.097389) (xy 28.518597 -107.023104)
			(xy 28.505365 -106.947396) (xy 28.498711 -106.870828) (xy 28.498292 -106.8324) (xy 28.498875 -106.786004)
			(xy 28.50852 -106.693716) (xy 28.527716 -106.602932) (xy 28.556254 -106.514639) (xy 28.574492 -106.471974)
			(xy 28.578397 -106.462052) (xy 28.578397 -106.440748) (xy 28.574492 -106.430826) (xy 28.556247 -106.388164)
			(xy 28.527703 -106.299871) (xy 28.50851 -106.209086) (xy 28.498877 -106.116796) (xy 28.498292 -106.0704)
			(xy 28.498875 -106.024004) (xy 28.50852 -105.931716) (xy 28.527716 -105.840932) (xy 28.556254 -105.752639)
			(xy 28.574492 -105.709974) (xy 28.578397 -105.700052) (xy 28.578397 -105.678748) (xy 28.574492 -105.668826)
			(xy 28.556247 -105.626164) (xy 28.527703 -105.537871) (xy 28.50851 -105.447086) (xy 28.498877 -105.354796)
			(xy 28.498292 -105.3084) (xy 28.498875 -105.262004) (xy 28.50852 -105.169716) (xy 28.527716 -105.078932)
			(xy 28.556254 -104.990639) (xy 28.574492 -104.947974) (xy 28.578397 -104.938052) (xy 28.578397 -104.916748)
			(xy 28.574492 -104.906826) (xy 28.556247 -104.864164) (xy 28.527703 -104.775871) (xy 28.50851 -104.685086)
			(xy 28.498877 -104.592796) (xy 28.498292 -104.5464) (xy 28.498875 -104.500004) (xy 28.50852 -104.407716)
			(xy 28.527716 -104.316932) (xy 28.556254 -104.228639) (xy 28.574492 -104.185974) (xy 28.578397 -104.176052)
			(xy 28.578397 -104.154748) (xy 28.574492 -104.144826) (xy 28.556247 -104.102164) (xy 28.527703 -104.013871)
			(xy 28.50851 -103.923086) (xy 28.498877 -103.830796) (xy 28.498292 -103.7844) (xy 28.498767 -103.743298)
			(xy 28.506352 -103.661443) (xy 28.521457 -103.580638) (xy 28.543953 -103.501571) (xy 28.573649 -103.424917)
			(xy 28.610291 -103.35133) (xy 28.653566 -103.281438) (xy 28.703106 -103.215837) (xy 28.758487 -103.155087)
			(xy 28.819237 -103.099706) (xy 28.884838 -103.050166) (xy 28.95473 -103.006891) (xy 29.028317 -102.970249)
			(xy 29.104971 -102.940553) (xy 29.184038 -102.918057) (xy 29.264843 -102.902952) (xy 29.346698 -102.895367)
			(xy 29.3878 -102.894892) (xy 29.433417 -102.895466) (xy 29.524172 -102.904799) (xy 29.613497 -102.923367)
			(xy 29.700453 -102.950974) (xy 29.78413 -102.987332) (xy 29.824172 -103.009192) (xy 29.832335 -103.013339)
			(xy 29.8504 -103.0162) (xy 29.86831 -103.012491) (xy 29.876242 -103.007922) (xy 29.911906 -102.985856)
			(xy 29.986639 -102.947783) (xy 30.064625 -102.916916) (xy 30.145171 -102.89353) (xy 30.227561 -102.877832)
			(xy 30.311064 -102.869963) (xy 30.353 -102.869492) (xy 30.39679 -102.86998) (xy 30.483949 -102.878545)
			(xy 30.569843 -102.89564) (xy 30.65364 -102.921101) (xy 30.734526 -102.95468) (xy 30.77337 -102.974902)
			(xy 30.784836 -102.98032) (xy 30.810164 -102.98032) (xy 30.82163 -102.974902) (xy 30.860471 -102.954677)
			(xy 30.941366 -102.921126) (xy 31.025164 -102.89568) (xy 31.111056 -102.878584) (xy 31.198212 -102.870005)
			(xy 31.242 -102.869492) (xy 31.283102 -102.869967) (xy 31.364957 -102.877552) (xy 31.445762 -102.892657)
			(xy 31.524829 -102.915153) (xy 31.601483 -102.944849) (xy 31.67507 -102.981491) (xy 31.744962 -103.024766)
			(xy 31.810563 -103.074306) (xy 31.871313 -103.129687) (xy 31.926694 -103.190437) (xy 31.976234 -103.256038)
			(xy 32.019509 -103.32593) (xy 32.056151 -103.399517) (xy 32.085847 -103.476171) (xy 32.108343 -103.555238)
			(xy 32.123448 -103.636043) (xy 32.131033 -103.717898) (xy 32.131508 -103.759) (xy 32.130925 -103.805396)
			(xy 32.12128 -103.897684) (xy 32.102084 -103.988468) (xy 32.073546 -104.076761) (xy 32.055308 -104.119426)
			(xy 32.051502 -104.129368) (xy 32.051502 -104.150632) (xy 32.055308 -104.160574) (xy 32.073553 -104.203236)
			(xy 32.102097 -104.291529) (xy 32.12129 -104.382314) (xy 32.130923 -104.474604) (xy 32.131508 -104.521)
			(xy 32.130925 -104.567396) (xy 32.12128 -104.659684) (xy 32.102084 -104.750468) (xy 32.073546 -104.838761)
			(xy 32.055308 -104.881426) (xy 32.051502 -104.891368) (xy 32.051502 -104.912632) (xy 32.055308 -104.922574)
			(xy 32.073553 -104.965236) (xy 32.102097 -105.053529) (xy 32.12129 -105.144314) (xy 32.130923 -105.236604)
			(xy 32.131508 -105.283) (xy 32.130925 -105.329396) (xy 32.12128 -105.421684) (xy 32.102084 -105.512468)
			(xy 32.073546 -105.600761) (xy 32.055308 -105.643426) (xy 32.051502 -105.653368) (xy 32.051502 -105.674632)
			(xy 32.055308 -105.684574) (xy 32.073553 -105.727236) (xy 32.102097 -105.815529) (xy 32.12129 -105.906314)
			(xy 32.130923 -105.998604) (xy 32.131508 -106.045) (xy 32.130925 -106.091396) (xy 32.12128 -106.183684)
			(xy 32.102084 -106.274468) (xy 32.073546 -106.362761) (xy 32.055308 -106.405426) (xy 32.051502 -106.415368)
			(xy 32.051502 -106.436632) (xy 32.055308 -106.446574) (xy 32.073553 -106.489236) (xy 32.102097 -106.577529)
			(xy 32.12129 -106.668314) (xy 32.130923 -106.760604) (xy 32.131508 -106.807) (xy 32.131149 -106.845449)
			(xy 32.124566 -106.922065) (xy 32.111388 -106.997826) (xy 32.091715 -107.072165) (xy 32.065692 -107.144526)
			(xy 32.049974 -107.179618) (xy 32.045874 -107.189831) (xy 32.045885 -107.211818) (xy 32.049974 -107.222036)
			(xy 32.065681 -107.257103) (xy 32.091668 -107.329421) (xy 32.111325 -107.40371) (xy 32.124505 -107.479417)
			(xy 32.131112 -107.555977) (xy 32.131508 -107.5944) (xy 32.130925 -107.640796) (xy 32.12128 -107.733084)
			(xy 32.102084 -107.823868) (xy 32.073546 -107.912161) (xy 32.055308 -107.954826) (xy 32.051403 -107.964748)
			(xy 32.051403 -107.986052) (xy 32.055308 -107.995974) (xy 32.073553 -108.038636) (xy 32.102097 -108.126929)
			(xy 32.12129 -108.217714) (xy 32.130923 -108.310004) (xy 32.131508 -108.3564) (xy 38.937692 -108.3564)
			(xy 38.938275 -108.310004) (xy 38.94792 -108.217716) (xy 38.967116 -108.126932) (xy 38.995654 -108.038639)
			(xy 39.013892 -107.995974) (xy 39.017797 -107.986052) (xy 39.017797 -107.964748) (xy 39.013892 -107.954826)
			(xy 38.995647 -107.912164) (xy 38.967103 -107.823871) (xy 38.94791 -107.733086) (xy 38.938277 -107.640796)
			(xy 38.937692 -107.5944) (xy 38.938251 -107.550173) (xy 38.947033 -107.462156) (xy 38.964509 -107.375446)
			(xy 38.990508 -107.2909) (xy 39.024773 -107.209352) (xy 39.045388 -107.17022) (xy 39.050228 -107.160228)
			(xy 39.051661 -107.138093) (xy 39.048182 -107.127548) (xy 39.033858 -107.089132) (xy 39.011486 -107.010251)
			(xy 38.996473 -106.929644) (xy 38.988949 -106.847997) (xy 38.988492 -106.807) (xy 38.989075 -106.760604)
			(xy 38.99872 -106.668316) (xy 39.017916 -106.577532) (xy 39.046454 -106.489239) (xy 39.064692 -106.446574)
			(xy 39.068498 -106.436632) (xy 39.068498 -106.415368) (xy 39.064692 -106.405426) (xy 39.046447 -106.362764)
			(xy 39.017903 -106.274471) (xy 38.99871 -106.183686) (xy 38.989077 -106.091396) (xy 38.988492 -106.045)
			(xy 38.989075 -105.998604) (xy 38.99872 -105.906316) (xy 39.017916 -105.815532) (xy 39.046454 -105.727239)
			(xy 39.064692 -105.684574) (xy 39.068498 -105.674632) (xy 39.068498 -105.653368) (xy 39.064692 -105.643426)
			(xy 39.046447 -105.600764) (xy 39.017903 -105.512471) (xy 38.99871 -105.421686) (xy 38.989077 -105.329396)
			(xy 38.988492 -105.283) (xy 38.989075 -105.236604) (xy 38.99872 -105.144316) (xy 39.017916 -105.053532)
			(xy 39.046454 -104.965239) (xy 39.064692 -104.922574) (xy 39.068498 -104.912632) (xy 39.068498 -104.891368)
			(xy 39.064692 -104.881426) (xy 39.046447 -104.838764) (xy 39.017903 -104.750471) (xy 38.99871 -104.659686)
			(xy 38.989077 -104.567396) (xy 38.988492 -104.521) (xy 38.989075 -104.474604) (xy 38.99872 -104.382316)
			(xy 39.017916 -104.291532) (xy 39.046454 -104.203239) (xy 39.064692 -104.160574) (xy 39.068498 -104.150632)
			(xy 39.068498 -104.129368) (xy 39.064692 -104.119426) (xy 39.046447 -104.076764) (xy 39.017903 -103.988471)
			(xy 38.99871 -103.897686) (xy 38.989077 -103.805396) (xy 38.988492 -103.759) (xy 38.988967 -103.717898)
			(xy 38.996552 -103.636043) (xy 39.011657 -103.555238) (xy 39.034153 -103.476171) (xy 39.063849 -103.399517)
			(xy 39.100491 -103.32593) (xy 39.143766 -103.256038) (xy 39.193306 -103.190437) (xy 39.248687 -103.129687)
			(xy 39.309437 -103.074306) (xy 39.375038 -103.024766) (xy 39.44493 -102.981491) (xy 39.518517 -102.944849)
			(xy 39.595171 -102.915153) (xy 39.674238 -102.892657) (xy 39.755043 -102.877552) (xy 39.836898 -102.869967)
			(xy 39.878 -102.869492) (xy 39.92179 -102.86998) (xy 40.008949 -102.878545) (xy 40.094843 -102.89564)
			(xy 40.17864 -102.921101) (xy 40.259526 -102.95468) (xy 40.29837 -102.974902) (xy 40.309836 -102.98032)
			(xy 40.335164 -102.98032) (xy 40.34663 -102.974902) (xy 40.385471 -102.954677) (xy 40.466366 -102.921126)
			(xy 40.550164 -102.89568) (xy 40.636056 -102.878584) (xy 40.723212 -102.870005) (xy 40.767 -102.869492)
			(xy 40.813379 -102.870097) (xy 40.905633 -102.879747) (xy 40.996382 -102.898942) (xy 41.084642 -102.927473)
			(xy 41.169455 -102.965032) (xy 41.209976 -102.987602) (xy 41.221253 -102.993254) (xy 41.246432 -102.993937)
			(xy 41.257982 -102.988872) (xy 41.295102 -102.970822) (xy 41.372033 -102.940898) (xy 41.451405 -102.918227)
			(xy 41.532535 -102.903004) (xy 41.614727 -102.89536) (xy 41.656 -102.894892) (xy 41.697102 -102.895367)
			(xy 41.778957 -102.902952) (xy 41.859762 -102.918057) (xy 41.938829 -102.940553) (xy 42.015483 -102.970249)
			(xy 42.08907 -103.006891) (xy 42.158962 -103.050166) (xy 42.224563 -103.099706) (xy 42.285313 -103.155087)
			(xy 42.340694 -103.215837) (xy 42.390234 -103.281438) (xy 42.433509 -103.35133) (xy 42.470151 -103.424917)
			(xy 42.499847 -103.501571) (xy 42.522343 -103.580638) (xy 42.537448 -103.661443) (xy 42.545033 -103.743298)
			(xy 42.545508 -103.7844) (xy 42.544925 -103.830796) (xy 42.53528 -103.923084) (xy 42.516084 -104.013868)
			(xy 42.487546 -104.102161) (xy 42.469308 -104.144826) (xy 42.465403 -104.154748) (xy 42.465403 -104.176052)
			(xy 42.469308 -104.185974) (xy 42.487553 -104.228636) (xy 42.516097 -104.316929) (xy 42.53529 -104.407714)
			(xy 42.544923 -104.500004) (xy 42.545508 -104.5464) (xy 42.544925 -104.592796) (xy 42.53528 -104.685084)
			(xy 42.516084 -104.775868) (xy 42.487546 -104.864161) (xy 42.469308 -104.906826) (xy 42.465403 -104.916748)
			(xy 42.465403 -104.938052) (xy 42.469308 -104.947974) (xy 42.487553 -104.990636) (xy 42.516097 -105.078929)
			(xy 42.53529 -105.169714) (xy 42.544923 -105.262004) (xy 42.545508 -105.3084) (xy 42.544925 -105.354796)
			(xy 42.53528 -105.447084) (xy 42.516084 -105.537868) (xy 42.487546 -105.626161) (xy 42.469308 -105.668826)
			(xy 42.465403 -105.678748) (xy 42.465403 -105.700052) (xy 42.469308 -105.709974) (xy 42.487553 -105.752636)
			(xy 42.516097 -105.840929) (xy 42.525034 -105.883202) (xy 201.446892 -105.883202) (xy 201.447476 -105.836806)
			(xy 201.45712 -105.744518) (xy 201.476316 -105.653734) (xy 201.504854 -105.565441) (xy 201.523092 -105.522776)
			(xy 201.526896 -105.512833) (xy 201.526897 -105.49157) (xy 201.523092 -105.481628) (xy 201.504848 -105.438966)
			(xy 201.476304 -105.350673) (xy 201.45711 -105.259888) (xy 201.447477 -105.167598) (xy 201.446892 -105.121202)
			(xy 201.447364 -105.078635) (xy 201.455472 -104.993887) (xy 201.471642 -104.910303) (xy 201.495727 -104.828647)
			(xy 201.511154 -104.78897) (xy 201.514396 -104.779715) (xy 201.514403 -104.760122) (xy 201.511154 -104.75087)
			(xy 201.495726 -104.711195) (xy 201.47165 -104.629536) (xy 201.455485 -104.545952) (xy 201.447378 -104.461205)
			(xy 201.446892 -104.418638) (xy 201.447488 -104.372243) (xy 201.457129 -104.279955) (xy 201.476321 -104.189171)
			(xy 201.504856 -104.100877) (xy 201.523092 -104.058212) (xy 201.526875 -104.048263) (xy 201.526889 -104.027006)
			(xy 201.523092 -104.017064) (xy 201.50486 -103.974397) (xy 201.476312 -103.886106) (xy 201.457116 -103.795323)
			(xy 201.447479 -103.703034) (xy 201.446892 -103.656638) (xy 201.447488 -103.610243) (xy 201.457129 -103.517955)
			(xy 201.476321 -103.427171) (xy 201.504856 -103.338877) (xy 201.523092 -103.296212) (xy 201.526875 -103.286263)
			(xy 201.526889 -103.265006) (xy 201.523092 -103.255064) (xy 201.50486 -103.212397) (xy 201.476312 -103.124106)
			(xy 201.457116 -103.033323) (xy 201.447479 -102.941034) (xy 201.446892 -102.894638) (xy 201.447449 -102.853533)
			(xy 201.455029 -102.771674) (xy 201.470129 -102.690863) (xy 201.492619 -102.61179) (xy 201.522308 -102.535128)
			(xy 201.558942 -102.461532) (xy 201.60221 -102.39163) (xy 201.651741 -102.326017) (xy 201.707115 -102.265254)
			(xy 201.767857 -102.209858) (xy 201.833451 -102.160301) (xy 201.903337 -102.117007) (xy 201.976919 -102.080345)
			(xy 202.053569 -102.050627) (xy 202.132634 -102.028106) (xy 202.213439 -102.012976) (xy 202.295295 -102.005364)
			(xy 202.3364 -102.004876) (xy 202.38045 -102.00545) (xy 202.468114 -102.014227) (xy 202.554483 -102.031616)
			(xy 202.638713 -102.057447) (xy 202.679554 -102.073964) (xy 202.688564 -102.077299) (xy 202.707756 -102.077697)
			(xy 202.716892 -102.074726) (xy 202.754276 -102.061238) (xy 202.83092 -102.040197) (xy 202.909137 -102.026086)
			(xy 202.988302 -102.019017) (xy 203.028042 -102.018592) (xy 203.074437 -102.019195) (xy 203.166725 -102.028834)
			(xy 203.257509 -102.048024) (xy 203.345803 -102.076557) (xy 203.388468 -102.094792) (xy 203.39841 -102.098598)
			(xy 203.419674 -102.098598) (xy 203.429616 -102.094792) (xy 203.472273 -102.076533) (xy 203.560567 -102.047993)
			(xy 203.651354 -102.028804) (xy 203.743645 -102.019175) (xy 203.790042 -102.018592) (xy 203.836437 -102.019195)
			(xy 203.928725 -102.028834) (xy 204.019509 -102.048024) (xy 204.107803 -102.076557) (xy 204.150468 -102.094792)
			(xy 204.16041 -102.098598) (xy 204.181674 -102.098598) (xy 204.191616 -102.094792) (xy 204.234273 -102.076533)
			(xy 204.322567 -102.047993) (xy 204.413354 -102.028804) (xy 204.505645 -102.019175) (xy 204.552042 -102.018592)
			(xy 204.598437 -102.019195) (xy 204.690725 -102.028834) (xy 204.781509 -102.048024) (xy 204.869803 -102.076557)
			(xy 204.912468 -102.094792) (xy 204.92241 -102.098598) (xy 204.943674 -102.098598) (xy 204.953616 -102.094792)
			(xy 204.996273 -102.076533) (xy 205.084567 -102.047993) (xy 205.175354 -102.028804) (xy 205.267645 -102.019175)
			(xy 205.314042 -102.018592) (xy 205.360437 -102.019195) (xy 205.452725 -102.028834) (xy 205.543509 -102.048024)
			(xy 205.631803 -102.076557) (xy 205.674468 -102.094792) (xy 205.68441 -102.098598) (xy 205.705674 -102.098598)
			(xy 205.715616 -102.094792) (xy 205.758273 -102.076533) (xy 205.846567 -102.047993) (xy 205.937354 -102.028804)
			(xy 206.029645 -102.019175) (xy 206.076042 -102.018592) (xy 206.122437 -102.019195) (xy 206.214725 -102.028834)
			(xy 206.305509 -102.048024) (xy 206.393803 -102.076557) (xy 206.436468 -102.094792) (xy 206.44641 -102.098598)
			(xy 206.467674 -102.098598) (xy 206.477616 -102.094792) (xy 206.520273 -102.076533) (xy 206.608567 -102.047993)
			(xy 206.699354 -102.028804) (xy 206.791645 -102.019175) (xy 206.838042 -102.018592) (xy 206.879551 -102.019069)
			(xy 206.962209 -102.026787) (xy 207.043788 -102.042181) (xy 207.123575 -102.065115) (xy 207.1624 -102.079806)
			(xy 207.171897 -102.08298) (xy 207.191897 -102.082587) (xy 207.201262 -102.079044) (xy 207.243424 -102.061305)
			(xy 207.330583 -102.033534) (xy 207.420131 -102.014855) (xy 207.511124 -102.005463) (xy 207.556862 -102.004876)
			(xy 207.597969 -102.005349) (xy 207.679833 -102.01293) (xy 207.760649 -102.028032) (xy 207.839727 -102.050525)
			(xy 207.916392 -102.080217) (xy 207.989991 -102.116856) (xy 208.059896 -102.160128) (xy 208.125511 -102.209665)
			(xy 208.186276 -102.265044) (xy 208.241672 -102.325793) (xy 208.291228 -102.391394) (xy 208.334521 -102.461287)
			(xy 208.37118 -102.534875) (xy 208.400895 -102.611532) (xy 208.42341 -102.690604) (xy 208.438535 -102.771415)
			(xy 208.446139 -102.853277) (xy 208.446624 -102.894384) (xy 208.446027 -102.940787) (xy 208.436328 -103.033085)
			(xy 208.417066 -103.12387) (xy 208.38845 -103.212155) (xy 208.37017 -103.25481) (xy 208.366371 -103.264755)
			(xy 208.366365 -103.286016) (xy 208.37017 -103.295958) (xy 208.388427 -103.338621) (xy 208.417021 -103.426908)
			(xy 208.43628 -103.51769) (xy 208.445994 -103.609983) (xy 208.446624 -103.656384) (xy 208.446027 -103.702787)
			(xy 208.436328 -103.795085) (xy 208.417066 -103.88587) (xy 208.38845 -103.974155) (xy 208.37017 -104.01681)
			(xy 208.366371 -104.026755) (xy 208.366365 -104.048016) (xy 208.37017 -104.057958) (xy 208.388427 -104.100621)
			(xy 208.417021 -104.188908) (xy 208.43628 -104.27969) (xy 208.445994 -104.371983) (xy 208.446624 -104.418384)
			(xy 208.446109 -104.460957) (xy 208.437948 -104.545711) (xy 208.421718 -104.629296) (xy 208.397568 -104.710946)
			(xy 208.382108 -104.750616) (xy 208.378875 -104.759874) (xy 208.378863 -104.779464) (xy 208.382108 -104.788716)
			(xy 208.39754 -104.828395) (xy 208.421676 -104.910046) (xy 208.43791 -104.993628) (xy 208.446096 -105.078377)
			(xy 208.446624 -105.120948) (xy 208.446014 -105.167351) (xy 208.436319 -105.259648) (xy 208.417061 -105.350434)
			(xy 208.388448 -105.438718) (xy 208.37017 -105.481374) (xy 208.366333 -105.491307) (xy 208.366351 -105.51258)
			(xy 208.37017 -105.522522) (xy 208.388448 -105.565176) (xy 208.417037 -105.653467) (xy 208.43629 -105.744252)
			(xy 208.445997 -105.836546) (xy 208.446624 -105.882948) (xy 208.446621 -105.883202) (xy 215.929464 -105.883202)
			(xy 215.930093 -105.8368) (xy 215.939782 -105.744503) (xy 215.959035 -105.653717) (xy 215.987643 -105.565432)
			(xy 216.005918 -105.522776) (xy 216.009721 -105.512833) (xy 216.009721 -105.49157) (xy 216.005918 -105.481628)
			(xy 215.987656 -105.438967) (xy 215.959063 -105.350679) (xy 215.939806 -105.259896) (xy 215.930093 -105.167603)
			(xy 215.929464 -105.121202) (xy 215.929976 -105.078629) (xy 215.938138 -104.993875) (xy 215.954369 -104.910289)
			(xy 215.978519 -104.82864) (xy 215.99398 -104.78897) (xy 215.997221 -104.779714) (xy 215.997228 -104.760122)
			(xy 215.99398 -104.75087) (xy 215.978542 -104.711193) (xy 215.954408 -104.629541) (xy 215.938175 -104.545959)
			(xy 215.929991 -104.461209) (xy 215.929464 -104.418638) (xy 215.93007 -104.372235) (xy 215.939766 -104.279937)
			(xy 215.959026 -104.189152) (xy 215.98764 -104.100867) (xy 216.005918 -104.058212) (xy 216.0097 -104.048263)
			(xy 216.009714 -104.027006) (xy 216.005918 -104.017064) (xy 215.987667 -103.974398) (xy 215.959071 -103.886112)
			(xy 215.939811 -103.795331) (xy 215.930095 -103.703039) (xy 215.929464 -103.656638) (xy 215.93007 -103.610235)
			(xy 215.939766 -103.517937) (xy 215.959026 -103.427152) (xy 215.98764 -103.338867) (xy 216.005918 -103.296212)
			(xy 216.0097 -103.286263) (xy 216.009714 -103.265006) (xy 216.005918 -103.255064) (xy 215.987667 -103.212398)
			(xy 215.959071 -103.124112) (xy 215.939811 -103.033331) (xy 215.930095 -102.941039) (xy 215.929464 -102.894638)
			(xy 215.929935 -102.853523) (xy 215.937519 -102.771643) (xy 215.952626 -102.690813) (xy 215.975127 -102.611721)
			(xy 216.00483 -102.535043) (xy 216.041481 -102.461433) (xy 216.084768 -102.391519) (xy 216.134322 -102.325897)
			(xy 216.18972 -102.265128) (xy 216.250488 -102.20973) (xy 216.316109 -102.160175) (xy 216.386023 -102.116887)
			(xy 216.459632 -102.080234) (xy 216.53631 -102.050531) (xy 216.615401 -102.028029) (xy 216.696232 -102.01292)
			(xy 216.778111 -102.005335) (xy 216.819226 -102.004876) (xy 216.863277 -102.005441) (xy 216.950941 -102.014221)
			(xy 217.03731 -102.031612) (xy 217.12154 -102.057446) (xy 217.16238 -102.073964) (xy 217.171386 -102.077313)
			(xy 217.190582 -102.077702) (xy 217.199718 -102.074726) (xy 217.237099 -102.061231) (xy 217.313744 -102.040192)
			(xy 217.391962 -102.026083) (xy 217.471128 -102.019016) (xy 217.510868 -102.018592) (xy 217.557263 -102.019186)
			(xy 217.649551 -102.028828) (xy 217.740335 -102.048021) (xy 217.828629 -102.076556) (xy 217.871294 -102.094792)
			(xy 217.881236 -102.098598) (xy 217.9025 -102.098598) (xy 217.912442 -102.094792) (xy 217.955109 -102.076558)
			(xy 218.043399 -102.048011) (xy 218.134183 -102.028815) (xy 218.226472 -102.019179) (xy 218.272868 -102.018592)
			(xy 218.319263 -102.019186) (xy 218.411551 -102.028828) (xy 218.502335 -102.048021) (xy 218.590629 -102.076556)
			(xy 218.633294 -102.094792) (xy 218.643236 -102.098598) (xy 218.6645 -102.098598) (xy 218.674442 -102.094792)
			(xy 218.717109 -102.076558) (xy 218.805399 -102.048011) (xy 218.896183 -102.028815) (xy 218.988472 -102.019179)
			(xy 219.034868 -102.018592) (xy 219.081263 -102.019186) (xy 219.173551 -102.028828) (xy 219.264335 -102.048021)
			(xy 219.352629 -102.076556) (xy 219.395294 -102.094792) (xy 219.405236 -102.098598) (xy 219.4265 -102.098598)
			(xy 219.436442 -102.094792) (xy 219.479109 -102.076558) (xy 219.567399 -102.048011) (xy 219.658183 -102.028815)
			(xy 219.750472 -102.019179) (xy 219.796868 -102.018592) (xy 219.843263 -102.019186) (xy 219.935551 -102.028828)
			(xy 220.026335 -102.048021) (xy 220.114629 -102.076556) (xy 220.157294 -102.094792) (xy 220.167236 -102.098598)
			(xy 220.1885 -102.098598) (xy 220.198442 -102.094792) (xy 220.241109 -102.076558) (xy 220.329399 -102.048011)
			(xy 220.420183 -102.028815) (xy 220.512472 -102.019179) (xy 220.558868 -102.018592) (xy 220.605263 -102.019186)
			(xy 220.697551 -102.028828) (xy 220.788335 -102.048021) (xy 220.876629 -102.076556) (xy 220.919294 -102.094792)
			(xy 220.929236 -102.098598) (xy 220.9505 -102.098598) (xy 220.960442 -102.094792) (xy 221.003109 -102.076558)
			(xy 221.091399 -102.048011) (xy 221.182183 -102.028815) (xy 221.274472 -102.019179) (xy 221.320868 -102.018592)
			(xy 221.362377 -102.01906) (xy 221.445036 -102.026781) (xy 221.526614 -102.042177) (xy 221.606401 -102.065114)
			(xy 221.645226 -102.079806) (xy 221.654719 -102.082995) (xy 221.674723 -102.082593) (xy 221.684088 -102.079044)
			(xy 221.726247 -102.061296) (xy 221.813407 -102.033528) (xy 221.902956 -102.014851) (xy 221.99395 -102.005462)
			(xy 222.039688 -102.004876) (xy 222.08079 -102.005378) (xy 222.162643 -102.012962) (xy 222.243447 -102.028065)
			(xy 222.322513 -102.05056) (xy 222.399166 -102.080255) (xy 222.472752 -102.116895) (xy 222.542644 -102.160169)
			(xy 222.608245 -102.209706) (xy 222.668995 -102.265086) (xy 222.724376 -102.325834) (xy 222.773916 -102.391433)
			(xy 222.817191 -102.461323) (xy 222.853834 -102.534908) (xy 222.883531 -102.61156) (xy 222.906028 -102.690626)
			(xy 222.921134 -102.771429) (xy 222.928721 -102.853282) (xy 222.929196 -102.894384) (xy 222.928609 -102.940779)
			(xy 222.918965 -103.033068) (xy 222.89977 -103.123852) (xy 222.871233 -103.212145) (xy 222.852996 -103.25481)
			(xy 222.849201 -103.264755) (xy 222.849195 -103.286016) (xy 222.852996 -103.295958) (xy 222.871235 -103.338623)
			(xy 222.899781 -103.426914) (xy 222.918975 -103.517698) (xy 222.92861 -103.609988) (xy 222.929196 -103.656384)
			(xy 222.928609 -103.702779) (xy 222.918965 -103.795068) (xy 222.89977 -103.885852) (xy 222.871233 -103.974145)
			(xy 222.852996 -104.01681) (xy 222.849201 -104.026755) (xy 222.849195 -104.048016) (xy 222.852996 -104.057958)
			(xy 222.871235 -104.100623) (xy 222.899781 -104.188914) (xy 222.918975 -104.279698) (xy 222.92861 -104.371988)
			(xy 222.929196 -104.418384) (xy 222.928713 -104.460951) (xy 222.920608 -104.545698) (xy 222.90444 -104.629282)
			(xy 222.880359 -104.710939) (xy 222.864934 -104.750616) (xy 222.8617 -104.759874) (xy 222.861688 -104.779464)
			(xy 222.864934 -104.788716) (xy 222.880357 -104.828393) (xy 222.904434 -104.910051) (xy 222.908221 -104.929629)
			(xy 270.263616 -104.929629) (xy 270.263616 -104.844907) (xy 270.271669 -104.76057) (xy 270.287703 -104.67738)
			(xy 270.311571 -104.59609) (xy 270.343059 -104.517438) (xy 270.381881 -104.442135) (xy 270.427684 -104.370863)
			(xy 270.480055 -104.304267) (xy 270.53852 -104.242952) (xy 270.602548 -104.187471) (xy 270.67156 -104.138328)
			(xy 270.74493 -104.095968) (xy 270.821995 -104.060773) (xy 270.902057 -104.033064) (xy 270.98439 -104.01309)
			(xy 271.068249 -104.001033) (xy 271.152874 -103.997002) (xy 271.237499 -104.001033) (xy 271.321358 -104.01309)
			(xy 271.403691 -104.033064) (xy 271.483753 -104.060773) (xy 271.560818 -104.095968) (xy 271.634188 -104.138328)
			(xy 271.7032 -104.187471) (xy 271.767228 -104.242952) (xy 271.825693 -104.304267) (xy 271.878064 -104.370863)
			(xy 271.923867 -104.442135) (xy 271.962689 -104.517438) (xy 271.994177 -104.59609) (xy 272.018045 -104.67738)
			(xy 272.034079 -104.76057) (xy 272.042132 -104.844907) (xy 272.042636 -104.887268) (xy 272.042132 -104.929629)
			(xy 272.034079 -105.013966) (xy 272.018045 -105.097156) (xy 271.994177 -105.178446) (xy 271.962689 -105.257098)
			(xy 271.923867 -105.332401) (xy 271.878064 -105.403673) (xy 271.825693 -105.470269) (xy 271.767228 -105.531584)
			(xy 271.7032 -105.587065) (xy 271.634188 -105.636208) (xy 271.560818 -105.678568) (xy 271.483753 -105.713763)
			(xy 271.403691 -105.741472) (xy 271.321358 -105.761446) (xy 271.237499 -105.773503) (xy 271.152874 -105.777535)
			(xy 271.068249 -105.773503) (xy 270.98439 -105.761446) (xy 270.902057 -105.741472) (xy 270.821995 -105.713763)
			(xy 270.74493 -105.678568) (xy 270.67156 -105.636208) (xy 270.602548 -105.587065) (xy 270.53852 -105.531584)
			(xy 270.480055 -105.470269) (xy 270.427684 -105.403673) (xy 270.381881 -105.332401) (xy 270.343059 -105.257098)
			(xy 270.311571 -105.178446) (xy 270.287703 -105.097156) (xy 270.271669 -105.013966) (xy 270.263616 -104.929629)
			(xy 222.908221 -104.929629) (xy 222.920601 -104.993635) (xy 222.92871 -105.078381) (xy 222.929196 -105.120948)
			(xy 222.928596 -105.167343) (xy 222.918956 -105.259631) (xy 222.899765 -105.350415) (xy 222.871232 -105.438709)
			(xy 222.852996 -105.481374) (xy 222.849163 -105.491308) (xy 222.849181 -105.512579) (xy 222.852996 -105.522522)
			(xy 222.871223 -105.565192) (xy 222.899772 -105.653481) (xy 222.91897 -105.744264) (xy 222.928608 -105.836553)
			(xy 222.929196 -105.882948) (xy 222.928779 -105.924052) (xy 222.92119 -106.005908) (xy 222.90608 -106.086715)
			(xy 222.883579 -106.165783) (xy 222.853879 -106.242437) (xy 222.817233 -106.316025) (xy 222.773954 -106.385917)
			(xy 222.761182 -106.402829) (xy 268.600678 -106.402829) (xy 268.600678 -106.318107) (xy 268.608731 -106.23377)
			(xy 268.624765 -106.15058) (xy 268.648633 -106.06929) (xy 268.680121 -105.990638) (xy 268.718943 -105.915335)
			(xy 268.764746 -105.844063) (xy 268.817117 -105.777467) (xy 268.875582 -105.716152) (xy 268.93961 -105.660671)
			(xy 269.008622 -105.611528) (xy 269.081992 -105.569168) (xy 269.159057 -105.533973) (xy 269.239119 -105.506264)
			(xy 269.321452 -105.48629) (xy 269.405311 -105.474233) (xy 269.489936 -105.470202) (xy 269.574561 -105.474233)
			(xy 269.65842 -105.48629) (xy 269.740753 -105.506264) (xy 269.820815 -105.533973) (xy 269.89788 -105.569168)
			(xy 269.97125 -105.611528) (xy 270.040262 -105.660671) (xy 270.10429 -105.716152) (xy 270.162755 -105.777467)
			(xy 270.215126 -105.844063) (xy 270.260929 -105.915335) (xy 270.299751 -105.990638) (xy 270.331239 -106.06929)
			(xy 270.355107 -106.15058) (xy 270.371141 -106.23377) (xy 270.379194 -106.318107) (xy 270.379698 -106.360468)
			(xy 270.379194 -106.402829) (xy 270.371141 -106.487166) (xy 270.355107 -106.570356) (xy 270.331239 -106.651646)
			(xy 270.299751 -106.730298) (xy 270.260929 -106.805601) (xy 270.215126 -106.876873) (xy 270.162755 -106.943469)
			(xy 270.10429 -107.004784) (xy 270.040262 -107.060265) (xy 269.97125 -107.109408) (xy 269.89788 -107.151768)
			(xy 269.820815 -107.186963) (xy 269.740753 -107.214672) (xy 269.65842 -107.234646) (xy 269.574561 -107.246703)
			(xy 269.489936 -107.250735) (xy 269.405311 -107.246703) (xy 269.321452 -107.234646) (xy 269.239119 -107.214672)
			(xy 269.159057 -107.186963) (xy 269.081992 -107.151768) (xy 269.008622 -107.109408) (xy 268.93961 -107.060265)
			(xy 268.875582 -107.004784) (xy 268.817117 -106.943469) (xy 268.764746 -106.876873) (xy 268.718943 -106.805601)
			(xy 268.680121 -106.730298) (xy 268.648633 -106.651646) (xy 268.624765 -106.570356) (xy 268.608731 -106.487166)
			(xy 268.600678 -106.402829) (xy 222.761182 -106.402829) (xy 222.724411 -106.451518) (xy 222.669026 -106.512268)
			(xy 222.608272 -106.567649) (xy 222.542668 -106.617188) (xy 222.472772 -106.660463) (xy 222.399183 -106.697104)
			(xy 222.322526 -106.726799) (xy 222.243456 -106.749294) (xy 222.162648 -106.764398) (xy 222.080792 -106.771982)
			(xy 222.039688 -106.772456) (xy 221.998179 -106.771973) (xy 221.915521 -106.764257) (xy 221.833943 -106.748865)
			(xy 221.754155 -106.725932) (xy 221.71533 -106.711242) (xy 221.705829 -106.708082) (xy 221.685833 -106.708464)
			(xy 221.676468 -106.712004) (xy 221.634314 -106.729763) (xy 221.547152 -106.757529) (xy 221.457601 -106.776203)
			(xy 221.366607 -106.785588) (xy 221.320868 -106.786172) (xy 221.274473 -106.785568) (xy 221.182185 -106.77593)
			(xy 221.091401 -106.75674) (xy 221.003107 -106.728207) (xy 220.960442 -106.709972) (xy 220.9505 -106.706166)
			(xy 220.929236 -106.706166) (xy 220.919294 -106.709972) (xy 220.876635 -106.728225) (xy 220.788342 -106.756768)
			(xy 220.697556 -106.775958) (xy 220.605264 -106.785589) (xy 220.558868 -106.786172) (xy 220.512473 -106.785568)
			(xy 220.420185 -106.77593) (xy 220.329401 -106.75674) (xy 220.241107 -106.728207) (xy 220.198442 -106.709972)
			(xy 220.1885 -106.706166) (xy 220.167236 -106.706166) (xy 220.157294 -106.709972) (xy 220.114635 -106.728225)
			(xy 220.026342 -106.756768) (xy 219.935556 -106.775958) (xy 219.843264 -106.785589) (xy 219.796868 -106.786172)
			(xy 219.750473 -106.785568) (xy 219.658185 -106.77593) (xy 219.567401 -106.75674) (xy 219.479107 -106.728207)
			(xy 219.436442 -106.709972) (xy 219.4265 -106.706166) (xy 219.405236 -106.706166) (xy 219.395294 -106.709972)
			(xy 219.352635 -106.728225) (xy 219.264342 -106.756768) (xy 219.173556 -106.775958) (xy 219.081264 -106.785589)
			(xy 219.034868 -106.786172) (xy 218.988473 -106.785568) (xy 218.896185 -106.77593) (xy 218.805401 -106.75674)
			(xy 218.717107 -106.728207) (xy 218.674442 -106.709972) (xy 218.6645 -106.706166) (xy 218.643236 -106.706166)
			(xy 218.633294 -106.709972) (xy 218.590635 -106.728225) (xy 218.502342 -106.756768) (xy 218.411556 -106.775958)
			(xy 218.319264 -106.785589) (xy 218.272868 -106.786172) (xy 218.226473 -106.785568) (xy 218.134185 -106.77593)
			(xy 218.043401 -106.75674) (xy 217.955107 -106.728207) (xy 217.912442 -106.709972) (xy 217.9025 -106.706166)
			(xy 217.881236 -106.706166) (xy 217.871294 -106.709972) (xy 217.828635 -106.728225) (xy 217.740342 -106.756768)
			(xy 217.649556 -106.775958) (xy 217.557264 -106.785589) (xy 217.510868 -106.786172) (xy 217.466823 -106.785646)
			(xy 217.379163 -106.776938) (xy 217.292793 -106.759609) (xy 217.208558 -106.733831) (xy 217.167714 -106.717338)
			(xy 217.158709 -106.713986) (xy 217.139512 -106.713599) (xy 217.130376 -106.716576) (xy 217.093 -106.7301)
			(xy 217.016359 -106.751198) (xy 216.938142 -106.765371) (xy 216.858971 -106.772505) (xy 216.819226 -106.772964)
			(xy 216.778112 -106.772477) (xy 216.696233 -106.764892) (xy 216.615404 -106.749785) (xy 216.536314 -106.727283)
			(xy 216.459637 -106.697581) (xy 216.386028 -106.66093) (xy 216.316115 -106.617643) (xy 216.250494 -106.568091)
			(xy 216.189725 -106.512694) (xy 216.134327 -106.451927) (xy 216.084773 -106.386308) (xy 216.041484 -106.316396)
			(xy 216.004831 -106.242788) (xy 215.975125 -106.166113) (xy 215.952622 -106.087023) (xy 215.937512 -106.006194)
			(xy 215.929925 -105.924316) (xy 215.929464 -105.883202) (xy 208.446621 -105.883202) (xy 208.446193 -105.924059)
			(xy 208.438601 -106.00593) (xy 208.423487 -106.08675) (xy 208.400978 -106.165831) (xy 208.371268 -106.242498)
			(xy 208.33461 -106.316096) (xy 208.291317 -106.385997) (xy 208.241758 -106.451604) (xy 208.186356 -106.512358)
			(xy 208.125584 -106.567741) (xy 208.059961 -106.617279) (xy 207.990046 -106.66055) (xy 207.916436 -106.697184)
			(xy 207.83976 -106.726869) (xy 207.760672 -106.749352) (xy 207.679846 -106.764441) (xy 207.597973 -106.772007)
			(xy 207.556862 -106.772456) (xy 207.515353 -106.771982) (xy 207.432694 -106.764263) (xy 207.351116 -106.748869)
			(xy 207.271329 -106.725933) (xy 207.232504 -106.711242) (xy 207.223007 -106.708067) (xy 207.203007 -106.708459)
			(xy 207.193642 -106.712004) (xy 207.151478 -106.729739) (xy 207.06432 -106.757511) (xy 206.974772 -106.776192)
			(xy 206.88378 -106.785585) (xy 206.838042 -106.786172) (xy 206.791647 -106.785577) (xy 206.699359 -106.775936)
			(xy 206.608575 -106.756744) (xy 206.520281 -106.728209) (xy 206.477616 -106.709972) (xy 206.467674 -106.706166)
			(xy 206.44641 -106.706166) (xy 206.436468 -106.709972) (xy 206.393799 -106.728201) (xy 206.305509 -106.756749)
			(xy 206.214726 -106.775947) (xy 206.122438 -106.785585) (xy 206.076042 -106.786172) (xy 206.029647 -106.785577)
			(xy 205.937359 -106.775936) (xy 205.846575 -106.756744) (xy 205.758281 -106.728209) (xy 205.715616 -106.709972)
			(xy 205.705674 -106.706166) (xy 205.68441 -106.706166) (xy 205.674468 -106.709972) (xy 205.631799 -106.728201)
			(xy 205.543509 -106.756749) (xy 205.452726 -106.775947) (xy 205.360438 -106.785585) (xy 205.314042 -106.786172)
			(xy 205.267647 -106.785577) (xy 205.175359 -106.775936) (xy 205.084575 -106.756744) (xy 204.996281 -106.728209)
			(xy 204.953616 -106.709972) (xy 204.943674 -106.706166) (xy 204.92241 -106.706166) (xy 204.912468 -106.709972)
			(xy 204.869799 -106.728201) (xy 204.781509 -106.756749) (xy 204.690726 -106.775947) (xy 204.598438 -106.785585)
			(xy 204.552042 -106.786172) (xy 204.505647 -106.785577) (xy 204.413359 -106.775936) (xy 204.322575 -106.756744)
			(xy 204.234281 -106.728209) (xy 204.191616 -106.709972) (xy 204.181674 -106.706166) (xy 204.16041 -106.706166)
			(xy 204.150468 -106.709972) (xy 204.107799 -106.728201) (xy 204.019509 -106.756749) (xy 203.928726 -106.775947)
			(xy 203.836438 -106.785585) (xy 203.790042 -106.786172) (xy 203.743647 -106.785577) (xy 203.651359 -106.775936)
			(xy 203.560575 -106.756744) (xy 203.472281 -106.728209) (xy 203.429616 -106.709972) (xy 203.419674 -106.706166)
			(xy 203.39841 -106.706166) (xy 203.388468 -106.709972) (xy 203.345799 -106.728201) (xy 203.257509 -106.756749)
			(xy 203.166726 -106.775947) (xy 203.074438 -106.785585) (xy 203.028042 -106.786172) (xy 202.983997 -106.785621)
			(xy 202.896338 -106.77692) (xy 202.809969 -106.759599) (xy 202.725733 -106.733828) (xy 202.684888 -106.717338)
			(xy 202.675887 -106.713972) (xy 202.656687 -106.713594) (xy 202.64755 -106.716576) (xy 202.610166 -106.730079)
			(xy 202.533529 -106.751183) (xy 202.455313 -106.765361) (xy 202.376145 -106.772501) (xy 202.3364 -106.772964)
			(xy 202.295288 -106.772547) (xy 202.213415 -106.764959) (xy 202.132592 -106.749847) (xy 202.053508 -106.727341)
			(xy 201.976839 -106.697632) (xy 201.903239 -106.660975) (xy 201.833336 -106.617681) (xy 201.767727 -106.568121)
			(xy 201.706971 -106.512718) (xy 201.651588 -106.451944) (xy 201.60205 -106.386318) (xy 201.55878 -106.316401)
			(xy 201.522147 -106.242788) (xy 201.492464 -106.166109) (xy 201.469984 -106.087018) (xy 201.4549 -106.00619)
			(xy 201.447339 -105.924314) (xy 201.446892 -105.883202) (xy 42.525034 -105.883202) (xy 42.53529 -105.931714)
			(xy 42.544923 -106.024004) (xy 42.545508 -106.0704) (xy 42.544925 -106.116796) (xy 42.53528 -106.209084)
			(xy 42.516084 -106.299868) (xy 42.487546 -106.388161) (xy 42.469308 -106.430826) (xy 42.465403 -106.440748)
			(xy 42.465403 -106.462052) (xy 42.469308 -106.471974) (xy 42.487553 -106.514636) (xy 42.516097 -106.602929)
			(xy 42.53529 -106.693714) (xy 42.544923 -106.786004) (xy 42.545508 -106.8324) (xy 42.544974 -106.876652)
			(xy 42.53619 -106.964719) (xy 42.51871 -107.05148) (xy 42.492705 -107.136077) (xy 42.458433 -107.217676)
			(xy 42.437812 -107.256834) (xy 42.432976 -107.266759) (xy 42.431544 -107.28877) (xy 42.435018 -107.299252)
			(xy 42.449342 -107.337668) (xy 42.471714 -107.416549) (xy 42.486727 -107.497156) (xy 42.494251 -107.578803)
			(xy 42.494708 -107.6198) (xy 42.494125 -107.666196) (xy 42.48448 -107.758484) (xy 42.465284 -107.849268)
			(xy 42.436746 -107.937561) (xy 42.418508 -107.980226) (xy 42.414603 -107.990148) (xy 42.414603 -108.011452)
			(xy 42.418508 -108.021374) (xy 42.436753 -108.064036) (xy 42.465297 -108.152329) (xy 42.48449 -108.243114)
			(xy 42.494123 -108.335404) (xy 42.494708 -108.3818) (xy 42.494233 -108.422902) (xy 42.486648 -108.504757)
			(xy 42.471543 -108.585562) (xy 42.449047 -108.664629) (xy 42.419351 -108.741283) (xy 42.382709 -108.81487)
			(xy 42.339434 -108.884762) (xy 42.289894 -108.950363) (xy 42.234513 -109.011113) (xy 42.173763 -109.066494)
			(xy 42.108162 -109.116034) (xy 42.03827 -109.159309) (xy 41.964683 -109.195951) (xy 41.888029 -109.225647)
			(xy 41.808962 -109.248143) (xy 41.728157 -109.263248) (xy 41.646302 -109.270833) (xy 41.6052 -109.271308)
			(xy 41.558821 -109.270703) (xy 41.466567 -109.261053) (xy 41.375818 -109.241858) (xy 41.287558 -109.213327)
			(xy 41.202745 -109.175768) (xy 41.162224 -109.153198) (xy 41.150947 -109.147546) (xy 41.125768 -109.146863)
			(xy 41.114218 -109.151928) (xy 41.077098 -109.169978) (xy 41.000167 -109.199902) (xy 40.920795 -109.222573)
			(xy 40.839665 -109.237796) (xy 40.757473 -109.24544) (xy 40.7162 -109.245908) (xy 40.672407 -109.245348)
			(xy 40.585246 -109.236718) (xy 40.499354 -109.219572) (xy 40.41556 -109.194075) (xy 40.334675 -109.160474)
			(xy 40.29583 -109.140244) (xy 40.284364 -109.134826) (xy 40.259036 -109.134826) (xy 40.24757 -109.140244)
			(xy 40.208728 -109.160483) (xy 40.127852 -109.194119) (xy 40.044059 -109.219632) (xy 39.958163 -109.236777)
			(xy 39.870996 -109.245387) (xy 39.8272 -109.245908) (xy 39.786098 -109.245433) (xy 39.704243 -109.237848)
			(xy 39.623438 -109.222743) (xy 39.544371 -109.200247) (xy 39.467717 -109.170551) (xy 39.39413 -109.133909)
			(xy 39.324238 -109.090634) (xy 39.258637 -109.041094) (xy 39.197887 -108.985713) (xy 39.142506 -108.924963)
			(xy 39.092966 -108.859362) (xy 39.049691 -108.78947) (xy 39.013049 -108.715883) (xy 38.983353 -108.639229)
			(xy 38.960857 -108.560162) (xy 38.945752 -108.479357) (xy 38.938167 -108.397502) (xy 38.937692 -108.3564)
			(xy 32.131508 -108.3564) (xy 32.131033 -108.397502) (xy 32.123448 -108.479357) (xy 32.108343 -108.560162)
			(xy 32.085847 -108.639229) (xy 32.056151 -108.715883) (xy 32.019509 -108.78947) (xy 31.976234 -108.859362)
			(xy 31.926694 -108.924963) (xy 31.871313 -108.985713) (xy 31.810563 -109.041094) (xy 31.744962 -109.090634)
			(xy 31.67507 -109.133909) (xy 31.601483 -109.170551) (xy 31.524829 -109.200247) (xy 31.445762 -109.222743)
			(xy 31.364957 -109.237848) (xy 31.283102 -109.245433) (xy 31.242 -109.245908) (xy 31.198207 -109.245348)
			(xy 31.111046 -109.236718) (xy 31.025154 -109.219572) (xy 30.94136 -109.194075) (xy 30.860475 -109.160474)
			(xy 30.82163 -109.140244) (xy 30.810164 -109.134826) (xy 30.784836 -109.134826) (xy 30.77337 -109.140244)
			(xy 30.734528 -109.160483) (xy 30.653652 -109.194119) (xy 30.569859 -109.219632) (xy 30.483963 -109.236777)
			(xy 30.396796 -109.245387) (xy 30.353 -109.245908) (xy 30.307377 -109.245294) (xy 30.216612 -109.235924)
			(xy 30.127284 -109.217312) (xy 30.040329 -109.189655) (xy 29.956662 -109.153242) (xy 29.916628 -109.131354)
			(xy 29.908405 -109.127232) (xy 29.890238 -109.12446) (xy 29.872258 -109.128261) (xy 29.864304 -109.132878)
			(xy 29.82866 -109.154937) (xy 29.753965 -109.19299) (xy 29.67602 -109.223846) (xy 29.595518 -109.247231)
			(xy 29.513173 -109.262937) (xy 29.429715 -109.270825) (xy 29.3878 -109.271308) (xy 29.346698 -109.270833)
			(xy 29.264843 -109.263248) (xy 29.184038 -109.248143) (xy 29.104971 -109.225647) (xy 29.028317 -109.195951)
			(xy 28.95473 -109.159309) (xy 28.884838 -109.116034) (xy 28.819237 -109.066494) (xy 28.758487 -109.011113)
			(xy 28.703106 -108.950363) (xy 28.653566 -108.884762) (xy 28.610291 -108.81487) (xy 28.573649 -108.741283)
			(xy 28.543953 -108.664629) (xy 28.521457 -108.585562) (xy 28.506352 -108.504757) (xy 28.498767 -108.422902)
			(xy 28.498292 -108.3818) (xy 0.509016 -108.3818) (xy 0.509016 -112.268) (xy 141.857988 -112.268)
			(xy 141.862018 -112.183399) (xy 141.874071 -112.099564) (xy 141.894039 -112.017255) (xy 141.921741 -111.937216)
			(xy 141.956925 -111.860173) (xy 141.999274 -111.786823) (xy 142.048403 -111.717831) (xy 142.103868 -111.653821)
			(xy 142.165166 -111.595373) (xy 142.231742 -111.543017) (xy 142.302994 -111.497227) (xy 142.378275 -111.458416)
			(xy 142.456905 -111.426937) (xy 142.538172 -111.403076) (xy 142.621338 -111.387047) (xy 142.705652 -111.378996)
			(xy 142.748 -111.378492) (xy 142.786284 -111.37888) (xy 142.862573 -111.385419) (xy 142.938015 -111.3985)
			(xy 143.012052 -111.418027) (xy 143.048228 -111.430562) (xy 143.056665 -111.433213) (xy 143.074335 -111.433213)
			(xy 143.082772 -111.430562) (xy 143.11895 -111.418037) (xy 143.19299 -111.398529) (xy 143.268431 -111.385449)
			(xy 143.344717 -111.378894) (xy 143.383 -111.378492) (xy 143.425348 -111.378996) (xy 143.509662 -111.387047)
			(xy 143.592828 -111.403076) (xy 143.674095 -111.426937) (xy 143.752725 -111.458416) (xy 143.828006 -111.497227)
			(xy 143.899258 -111.543017) (xy 143.965834 -111.595373) (xy 144.027132 -111.653821) (xy 144.082597 -111.717831)
			(xy 144.131726 -111.786823) (xy 144.174075 -111.860173) (xy 144.209259 -111.937216) (xy 144.236961 -112.017255)
			(xy 144.256929 -112.099564) (xy 144.268982 -112.183399) (xy 144.273013 -112.268) (xy 144.268982 -112.352601)
			(xy 144.256929 -112.436436) (xy 144.236961 -112.518745) (xy 144.209259 -112.598784) (xy 144.174075 -112.675827)
			(xy 144.131726 -112.749177) (xy 144.082597 -112.818169) (xy 144.027132 -112.882179) (xy 143.965834 -112.940627)
			(xy 143.899258 -112.992983) (xy 143.828006 -113.038773) (xy 143.752725 -113.077584) (xy 143.674095 -113.109063)
			(xy 143.592828 -113.132924) (xy 143.509662 -113.148953) (xy 143.425348 -113.157004) (xy 143.383 -113.157508)
			(xy 143.344716 -113.15712) (xy 143.268427 -113.150581) (xy 143.192985 -113.1375) (xy 143.118948 -113.117973)
			(xy 143.082772 -113.105438) (xy 143.074335 -113.102787) (xy 143.056665 -113.102787) (xy 143.048228 -113.105438)
			(xy 143.01205 -113.117963) (xy 142.93801 -113.137471) (xy 142.862569 -113.150551) (xy 142.786283 -113.157106)
			(xy 142.748 -113.157508) (xy 142.705652 -113.157004) (xy 142.621338 -113.148953) (xy 142.538172 -113.132924)
			(xy 142.456905 -113.109063) (xy 142.378275 -113.077584) (xy 142.302994 -113.038773) (xy 142.231742 -112.992983)
			(xy 142.165166 -112.940627) (xy 142.103868 -112.882179) (xy 142.048403 -112.818169) (xy 141.999274 -112.749177)
			(xy 141.956925 -112.675827) (xy 141.921741 -112.598784) (xy 141.894039 -112.518745) (xy 141.874071 -112.436436)
			(xy 141.862018 -112.352601) (xy 141.857988 -112.268) (xy 0.509016 -112.268) (xy 0.509016 -113.229898)
			(xy 0.509506 -113.299774) (xy 0.517342 -113.439307) (xy 0.53299 -113.578181) (xy 0.556399 -113.715959)
			(xy 0.573755 -113.792) (xy 268.350492 -113.792) (xy 268.351075 -113.745604) (xy 268.36072 -113.653316)
			(xy 268.379916 -113.562532) (xy 268.408454 -113.474239) (xy 268.426692 -113.431574) (xy 268.430498 -113.421632)
			(xy 268.430498 -113.400368) (xy 268.426692 -113.390426) (xy 268.408447 -113.347764) (xy 268.379903 -113.259471)
			(xy 268.36071 -113.168686) (xy 268.351077 -113.076396) (xy 268.350492 -113.03) (xy 268.351075 -112.983604)
			(xy 268.36072 -112.891316) (xy 268.379916 -112.800532) (xy 268.408454 -112.712239) (xy 268.426692 -112.669574)
			(xy 268.430498 -112.659632) (xy 268.430498 -112.638368) (xy 268.426692 -112.628426) (xy 268.408447 -112.585764)
			(xy 268.379903 -112.497471) (xy 268.36071 -112.406686) (xy 268.351077 -112.314396) (xy 268.350492 -112.268)
			(xy 268.351075 -112.221604) (xy 268.36072 -112.129316) (xy 268.379916 -112.038532) (xy 268.408454 -111.950239)
			(xy 268.426692 -111.907574) (xy 268.430498 -111.897632) (xy 268.430498 -111.876368) (xy 268.426692 -111.866426)
			(xy 268.408447 -111.823764) (xy 268.379903 -111.735471) (xy 268.36071 -111.644686) (xy 268.351077 -111.552396)
			(xy 268.350492 -111.506) (xy 268.351075 -111.459604) (xy 268.36072 -111.367316) (xy 268.379916 -111.276532)
			(xy 268.408454 -111.188239) (xy 268.426692 -111.145574) (xy 268.430498 -111.135632) (xy 268.430498 -111.114368)
			(xy 268.426692 -111.104426) (xy 268.408447 -111.061764) (xy 268.379903 -110.973471) (xy 268.36071 -110.882686)
			(xy 268.351077 -110.790396) (xy 268.350492 -110.744) (xy 268.351075 -110.697604) (xy 268.36072 -110.605316)
			(xy 268.379916 -110.514532) (xy 268.408454 -110.426239) (xy 268.426692 -110.383574) (xy 268.430498 -110.373632)
			(xy 268.430498 -110.352368) (xy 268.426692 -110.342426) (xy 268.408447 -110.299764) (xy 268.379903 -110.211471)
			(xy 268.36071 -110.120686) (xy 268.351077 -110.028396) (xy 268.350492 -109.982) (xy 268.350967 -109.940898)
			(xy 268.358552 -109.859043) (xy 268.373657 -109.778238) (xy 268.396153 -109.699171) (xy 268.425849 -109.622517)
			(xy 268.462491 -109.54893) (xy 268.505766 -109.479038) (xy 268.555306 -109.413437) (xy 268.610687 -109.352687)
			(xy 268.671437 -109.297306) (xy 268.737038 -109.247766) (xy 268.80693 -109.204491) (xy 268.880517 -109.167849)
			(xy 268.957171 -109.138153) (xy 269.036238 -109.115657) (xy 269.117043 -109.100552) (xy 269.198898 -109.092967)
			(xy 269.24 -109.092492) (xy 269.286396 -109.093075) (xy 269.378684 -109.10272) (xy 269.469468 -109.121916)
			(xy 269.557761 -109.150454) (xy 269.600426 -109.168692) (xy 269.610368 -109.172498) (xy 269.631632 -109.172498)
			(xy 269.641574 -109.168692) (xy 269.684236 -109.150447) (xy 269.772529 -109.121903) (xy 269.863314 -109.10271)
			(xy 269.955604 -109.093077) (xy 270.002 -109.092492) (xy 270.048396 -109.093075) (xy 270.140684 -109.10272)
			(xy 270.231468 -109.121916) (xy 270.319761 -109.150454) (xy 270.362426 -109.168692) (xy 270.372368 -109.172498)
			(xy 270.393632 -109.172498) (xy 270.403574 -109.168692) (xy 270.446236 -109.150447) (xy 270.534529 -109.121903)
			(xy 270.625314 -109.10271) (xy 270.717604 -109.093077) (xy 270.764 -109.092492) (xy 270.810396 -109.093075)
			(xy 270.902684 -109.10272) (xy 270.993468 -109.121916) (xy 271.081761 -109.150454) (xy 271.124426 -109.168692)
			(xy 271.134368 -109.172498) (xy 271.155632 -109.172498) (xy 271.165574 -109.168692) (xy 271.208236 -109.150447)
			(xy 271.296529 -109.121903) (xy 271.387314 -109.10271) (xy 271.479604 -109.093077) (xy 271.526 -109.092492)
			(xy 271.572396 -109.093075) (xy 271.664684 -109.10272) (xy 271.755468 -109.121916) (xy 271.843761 -109.150454)
			(xy 271.886426 -109.168692) (xy 271.896368 -109.172498) (xy 271.917632 -109.172498) (xy 271.927574 -109.168692)
			(xy 271.970236 -109.150447) (xy 272.058529 -109.121903) (xy 272.149314 -109.10271) (xy 272.241604 -109.093077)
			(xy 272.288 -109.092492) (xy 272.329102 -109.092967) (xy 272.410957 -109.100552) (xy 272.491762 -109.115657)
			(xy 272.570829 -109.138153) (xy 272.647483 -109.167849) (xy 272.72107 -109.204491) (xy 272.790962 -109.247766)
			(xy 272.856563 -109.297306) (xy 272.917313 -109.352687) (xy 272.972694 -109.413437) (xy 273.022234 -109.479038)
			(xy 273.065509 -109.54893) (xy 273.102151 -109.622517) (xy 273.131847 -109.699171) (xy 273.154343 -109.778238)
			(xy 273.169448 -109.859043) (xy 273.177033 -109.940898) (xy 273.177508 -109.982) (xy 273.176925 -110.028396)
			(xy 273.16728 -110.120684) (xy 273.148084 -110.211468) (xy 273.119546 -110.299761) (xy 273.101308 -110.342426)
			(xy 273.097502 -110.352368) (xy 273.097502 -110.373632) (xy 273.101308 -110.383574) (xy 273.119553 -110.426236)
			(xy 273.148097 -110.514529) (xy 273.16729 -110.605314) (xy 273.176923 -110.697604) (xy 273.177508 -110.744)
			(xy 273.177033 -110.785102) (xy 273.169448 -110.866957) (xy 273.154343 -110.947762) (xy 273.131847 -111.026829)
			(xy 273.102151 -111.103483) (xy 273.065509 -111.17707) (xy 273.022234 -111.246962) (xy 272.972694 -111.312563)
			(xy 272.917313 -111.373313) (xy 272.856563 -111.428694) (xy 272.790962 -111.478234) (xy 272.72107 -111.521509)
			(xy 272.647483 -111.558151) (xy 272.570829 -111.587847) (xy 272.491762 -111.610343) (xy 272.410957 -111.625448)
			(xy 272.329102 -111.633033) (xy 272.288 -111.633508) (xy 272.241604 -111.632925) (xy 272.149316 -111.62328)
			(xy 272.058532 -111.604084) (xy 271.970239 -111.575546) (xy 271.927574 -111.557308) (xy 271.917632 -111.553502)
			(xy 271.896368 -111.553502) (xy 271.886426 -111.557308) (xy 271.853507 -111.571537) (xy 271.785822 -111.595257)
			(xy 271.716442 -111.613437) (xy 271.681194 -111.620046) (xy 271.67107 -111.622344) (xy 271.653749 -111.633749)
			(xy 271.642344 -111.65107) (xy 271.640046 -111.661194) (xy 271.633416 -111.696437) (xy 271.61522 -111.76581)
			(xy 271.591513 -111.833498) (xy 271.577308 -111.866426) (xy 271.573502 -111.876368) (xy 271.573502 -111.897632)
			(xy 271.577308 -111.907574) (xy 271.591537 -111.940493) (xy 271.615257 -112.008178) (xy 271.633437 -112.077558)
			(xy 271.640046 -112.112806) (xy 271.642344 -112.12293) (xy 271.653749 -112.140251) (xy 271.67107 -112.151656)
			(xy 271.681194 -112.153954) (xy 271.716437 -112.160584) (xy 271.78581 -112.17878) (xy 271.853498 -112.202487)
			(xy 271.886426 -112.216692) (xy 271.896368 -112.220498) (xy 271.917632 -112.220498) (xy 271.927574 -112.216692)
			(xy 271.970236 -112.198447) (xy 272.058529 -112.169903) (xy 272.149314 -112.15071) (xy 272.241604 -112.141077)
			(xy 272.288 -112.140492) (xy 272.329102 -112.140967) (xy 272.410957 -112.148552) (xy 272.491762 -112.163657)
			(xy 272.570829 -112.186153) (xy 272.647483 -112.215849) (xy 272.72107 -112.252491) (xy 272.790962 -112.295766)
			(xy 272.856563 -112.345306) (xy 272.917313 -112.400687) (xy 272.972694 -112.461437) (xy 273.022234 -112.527038)
			(xy 273.065509 -112.59693) (xy 273.102151 -112.670517) (xy 273.131847 -112.747171) (xy 273.154343 -112.826238)
			(xy 273.169448 -112.907043) (xy 273.177033 -112.988898) (xy 273.177508 -113.03) (xy 273.176925 -113.076396)
			(xy 273.16728 -113.168684) (xy 273.148084 -113.259468) (xy 273.119546 -113.347761) (xy 273.101308 -113.390426)
			(xy 273.097502 -113.400368) (xy 273.097502 -113.421632) (xy 273.101308 -113.431574) (xy 273.119553 -113.474236)
			(xy 273.148097 -113.562529) (xy 273.16729 -113.653314) (xy 273.176923 -113.745604) (xy 273.177508 -113.792)
			(xy 273.177033 -113.833102) (xy 273.169448 -113.914957) (xy 273.154343 -113.995762) (xy 273.131847 -114.074829)
			(xy 273.102151 -114.151483) (xy 273.065509 -114.22507) (xy 273.022234 -114.294962) (xy 272.972694 -114.360563)
			(xy 272.917313 -114.421313) (xy 272.856563 -114.476694) (xy 272.790962 -114.526234) (xy 272.72107 -114.569509)
			(xy 272.647483 -114.606151) (xy 272.570829 -114.635847) (xy 272.491762 -114.658343) (xy 272.410957 -114.673448)
			(xy 272.329102 -114.681033) (xy 272.288 -114.681508) (xy 272.241604 -114.680925) (xy 272.149316 -114.67128)
			(xy 272.058532 -114.652084) (xy 271.970239 -114.623546) (xy 271.927574 -114.605308) (xy 271.917632 -114.601502)
			(xy 271.896368 -114.601502) (xy 271.886426 -114.605308) (xy 271.843764 -114.623553) (xy 271.755471 -114.652097)
			(xy 271.664686 -114.67129) (xy 271.572396 -114.680923) (xy 271.526 -114.681508) (xy 271.479604 -114.680925)
			(xy 271.387316 -114.67128) (xy 271.296532 -114.652084) (xy 271.208239 -114.623546) (xy 271.165574 -114.605308)
			(xy 271.155632 -114.601502) (xy 271.134368 -114.601502) (xy 271.124426 -114.605308) (xy 271.081764 -114.623553)
			(xy 270.993471 -114.652097) (xy 270.902686 -114.67129) (xy 270.810396 -114.680923) (xy 270.764 -114.681508)
			(xy 270.717604 -114.680925) (xy 270.625316 -114.67128) (xy 270.534532 -114.652084) (xy 270.446239 -114.623546)
			(xy 270.403574 -114.605308) (xy 270.393632 -114.601502) (xy 270.372368 -114.601502) (xy 270.362426 -114.605308)
			(xy 270.319764 -114.623553) (xy 270.231471 -114.652097) (xy 270.140686 -114.67129) (xy 270.048396 -114.680923)
			(xy 270.002 -114.681508) (xy 269.955604 -114.680925) (xy 269.863316 -114.67128) (xy 269.772532 -114.652084)
			(xy 269.684239 -114.623546) (xy 269.641574 -114.605308) (xy 269.631632 -114.601502) (xy 269.610368 -114.601502)
			(xy 269.600426 -114.605308) (xy 269.557764 -114.623553) (xy 269.469471 -114.652097) (xy 269.378686 -114.67129)
			(xy 269.286396 -114.680923) (xy 269.24 -114.681508) (xy 269.198898 -114.681033) (xy 269.117043 -114.673448)
			(xy 269.036238 -114.658343) (xy 268.957171 -114.635847) (xy 268.880517 -114.606151) (xy 268.80693 -114.569509)
			(xy 268.737038 -114.526234) (xy 268.671437 -114.476694) (xy 268.610687 -114.421313) (xy 268.555306 -114.360563)
			(xy 268.505766 -114.294962) (xy 268.462491 -114.22507) (xy 268.425849 -114.151483) (xy 268.396153 -114.074829)
			(xy 268.373657 -113.995762) (xy 268.358552 -113.914957) (xy 268.350967 -113.833102) (xy 268.350492 -113.792)
			(xy 0.573755 -113.792) (xy 0.587497 -113.852208) (xy 0.626186 -113.986499) (xy 0.672343 -114.118409)
			(xy 0.725824 -114.247524) (xy 0.78646 -114.373436) (xy 0.854061 -114.495751) (xy 0.928414 -114.614083)
			(xy 1.009285 -114.72806) (xy 1.09642 -114.837323) (xy 1.189543 -114.941529) (xy 1.288363 -115.040349)
			(xy 1.392569 -115.133472) (xy 1.501832 -115.220607) (xy 1.615809 -115.301478) (xy 1.734141 -115.375831)
			(xy 1.856456 -115.443432) (xy 1.982368 -115.504068) (xy 2.111483 -115.557549) (xy 2.243393 -115.603706)
			(xy 2.377684 -115.642395) (xy 2.513933 -115.673493) (xy 2.651711 -115.696902) (xy 2.790585 -115.71255)
			(xy 2.930118 -115.720386) (xy 2.999994 -115.720876) (xy 9.59993 -115.720876) (xy 9.643968 -115.721358)
			(xy 9.731709 -115.729037) (xy 9.818446 -115.744333) (xy 9.90352 -115.767131) (xy 9.986284 -115.797257)
			(xy 10.066107 -115.834482) (xy 10.142382 -115.878522) (xy 10.214528 -115.929042) (xy 10.281997 -115.985658)
			(xy 10.344275 -116.047939) (xy 10.400887 -116.11541) (xy 10.451404 -116.187559) (xy 10.49544 -116.263836)
			(xy 10.532661 -116.34366) (xy 10.562783 -116.426425) (xy 10.585577 -116.511501) (xy 10.60087 -116.598239)
			(xy 10.608544 -116.68598) (xy 10.609072 -116.730018) (xy 10.609072 -116.971769) (xy 270.314162 -116.971769)
			(xy 270.314162 -116.887047) (xy 270.322215 -116.80271) (xy 270.338249 -116.71952) (xy 270.362117 -116.63823)
			(xy 270.393605 -116.559578) (xy 270.432427 -116.484275) (xy 270.47823 -116.413003) (xy 270.530601 -116.346407)
			(xy 270.589066 -116.285092) (xy 270.653094 -116.229611) (xy 270.722106 -116.180468) (xy 270.795476 -116.138108)
			(xy 270.872541 -116.102913) (xy 270.952603 -116.075204) (xy 271.034936 -116.05523) (xy 271.118795 -116.043173)
			(xy 271.20342 -116.039142) (xy 271.288045 -116.043173) (xy 271.371904 -116.05523) (xy 271.454237 -116.075204)
			(xy 271.534299 -116.102913) (xy 271.611364 -116.138108) (xy 271.684734 -116.180468) (xy 271.753746 -116.229611)
			(xy 271.817774 -116.285092) (xy 271.876239 -116.346407) (xy 271.92861 -116.413003) (xy 271.974413 -116.484275)
			(xy 272.013235 -116.559578) (xy 272.044723 -116.63823) (xy 272.068591 -116.71952) (xy 272.084625 -116.80271)
			(xy 272.092678 -116.887047) (xy 272.093182 -116.929408) (xy 272.092678 -116.971769) (xy 272.084625 -117.056106)
			(xy 272.068591 -117.139296) (xy 272.044723 -117.220586) (xy 272.013235 -117.299238) (xy 271.974413 -117.374541)
			(xy 271.92861 -117.445813) (xy 271.876239 -117.512409) (xy 271.817774 -117.573724) (xy 271.753746 -117.629205)
			(xy 271.684734 -117.678348) (xy 271.611364 -117.720708) (xy 271.534299 -117.755903) (xy 271.454237 -117.783612)
			(xy 271.371904 -117.803586) (xy 271.288045 -117.815643) (xy 271.20342 -117.819675) (xy 271.118795 -117.815643)
			(xy 271.034936 -117.803586) (xy 270.952603 -117.783612) (xy 270.872541 -117.755903) (xy 270.795476 -117.720708)
			(xy 270.722106 -117.678348) (xy 270.653094 -117.629205) (xy 270.589066 -117.573724) (xy 270.530601 -117.512409)
			(xy 270.47823 -117.445813) (xy 270.432427 -117.374541) (xy 270.393605 -117.299238) (xy 270.362117 -117.220586)
			(xy 270.338249 -117.139296) (xy 270.322215 -117.056106) (xy 270.314162 -116.971769) (xy 10.609072 -116.971769)
			(xy 10.609072 -122.48007) (xy 12.909653 -122.48007) (xy 12.913615 -122.339639) (xy 12.92549 -122.199655)
			(xy 12.94524 -122.060564) (xy 12.972802 -121.922808) (xy 13.008088 -121.786825) (xy 13.050986 -121.653048)
			(xy 13.101359 -121.521903) (xy 13.159047 -121.393807) (xy 13.223867 -121.269168) (xy 13.295611 -121.148382)
			(xy 13.374053 -121.031834) (xy 13.458942 -120.919895) (xy 13.550008 -120.812921) (xy 13.646962 -120.711253)
			(xy 13.749494 -120.615213) (xy 13.857279 -120.525108) (xy 13.969973 -120.441224) (xy 14.087218 -120.363828)
			(xy 14.208641 -120.293167) (xy 14.333855 -120.229466) (xy 14.462462 -120.172926) (xy 14.594052 -120.123729)
			(xy 14.728208 -120.08203) (xy 14.864501 -120.047962) (xy 15.002499 -120.021634) (xy 15.141762 -120.00313)
			(xy 15.281846 -119.992508) (xy 15.422307 -119.989803) (xy 15.562696 -119.995022) (xy 15.702568 -120.008149)
			(xy 15.841477 -120.029143) (xy 15.978981 -120.057936) (xy 16.114643 -120.094438) (xy 16.248031 -120.138531)
			(xy 16.37872 -120.190076) (xy 16.506295 -120.248908) (xy 16.630349 -120.31484) (xy 16.750487 -120.387663)
			(xy 16.866328 -120.467145) (xy 16.977503 -120.553032) (xy 17.083658 -120.645052) (xy 17.184455 -120.742911)
			(xy 17.232376 -120.794272) (xy 17.241266 -120.803924) (xy 17.264888 -120.812052) (xy 17.3736 -120.795542)
			(xy 17.393666 -120.780556) (xy 17.399 -120.768872) (xy 17.438151 -120.687) (xy 17.522868 -120.526483)
			(xy 17.614754 -120.36996) (xy 17.713621 -120.21775) (xy 17.819267 -120.070165) (xy 17.931475 -119.927505)
			(xy 18.050018 -119.790064) (xy 18.174651 -119.65812) (xy 18.305121 -119.531945) (xy 18.441161 -119.411797)
			(xy 18.582492 -119.29792) (xy 18.728826 -119.190548) (xy 18.879864 -119.089899) (xy 19.035297 -118.996181)
			(xy 19.194807 -118.909584) (xy 19.358068 -118.830285) (xy 19.524747 -118.758447) (xy 19.694502 -118.694216)
			(xy 19.866987 -118.637724) (xy 20.04185 -118.589086) (xy 20.218732 -118.548401) (xy 20.397272 -118.515753)
			(xy 20.577105 -118.491209) (xy 20.757864 -118.474818) (xy 20.93918 -118.466614) (xy 21.02993 -118.466108)
			(xy 21.120007 -118.466613) (xy 21.147082 -118.467829) (xy 268.757142 -118.467829) (xy 268.757142 -118.383107)
			(xy 268.765195 -118.29877) (xy 268.781229 -118.21558) (xy 268.805097 -118.13429) (xy 268.836585 -118.055638)
			(xy 268.875407 -117.980335) (xy 268.92121 -117.909063) (xy 268.973581 -117.842467) (xy 269.032046 -117.781152)
			(xy 269.096074 -117.725671) (xy 269.165086 -117.676528) (xy 269.238456 -117.634168) (xy 269.315521 -117.598973)
			(xy 269.395583 -117.571264) (xy 269.477916 -117.55129) (xy 269.561775 -117.539233) (xy 269.6464 -117.535202)
			(xy 269.731025 -117.539233) (xy 269.814884 -117.55129) (xy 269.897217 -117.571264) (xy 269.977279 -117.598973)
			(xy 270.054344 -117.634168) (xy 270.127714 -117.676528) (xy 270.196726 -117.725671) (xy 270.260754 -117.781152)
			(xy 270.319219 -117.842467) (xy 270.37159 -117.909063) (xy 270.417393 -117.980335) (xy 270.456215 -118.055638)
			(xy 270.487703 -118.13429) (xy 270.511571 -118.21558) (xy 270.527605 -118.29877) (xy 270.535658 -118.383107)
			(xy 270.536162 -118.425468) (xy 270.535658 -118.467829) (xy 270.527605 -118.552166) (xy 270.511571 -118.635356)
			(xy 270.487703 -118.716646) (xy 270.456215 -118.795298) (xy 270.417393 -118.870601) (xy 270.37159 -118.941873)
			(xy 270.319219 -119.008469) (xy 270.260754 -119.069784) (xy 270.196726 -119.125265) (xy 270.127714 -119.174408)
			(xy 270.054344 -119.216768) (xy 269.977279 -119.251963) (xy 269.897217 -119.279672) (xy 269.814884 -119.299646)
			(xy 269.731025 -119.311703) (xy 269.6464 -119.315735) (xy 269.561775 -119.311703) (xy 269.477916 -119.299646)
			(xy 269.395583 -119.279672) (xy 269.315521 -119.251963) (xy 269.238456 -119.216768) (xy 269.165086 -119.174408)
			(xy 269.096074 -119.125265) (xy 269.032046 -119.069784) (xy 268.973581 -119.008469) (xy 268.92121 -118.941873)
			(xy 268.875407 -118.870601) (xy 268.836585 -118.795298) (xy 268.805097 -118.716646) (xy 268.781229 -118.635356)
			(xy 268.765195 -118.552166) (xy 268.757142 -118.467829) (xy 21.147082 -118.467829) (xy 21.299979 -118.474696)
			(xy 21.479408 -118.490845) (xy 21.657931 -118.515027) (xy 21.83519 -118.547195) (xy 22.010827 -118.587283)
			(xy 22.184488 -118.63521) (xy 22.355825 -118.690881) (xy 22.524491 -118.754183) (xy 22.690147 -118.824987)
			(xy 22.85246 -118.903153) (xy 23.011103 -118.988522) (xy 23.165755 -119.080923) (xy 23.316107 -119.180169)
			(xy 23.461854 -119.286061) (xy 23.602704 -119.398385) (xy 23.738373 -119.516915) (xy 23.868587 -119.641413)
			(xy 23.993085 -119.771627) (xy 24.111615 -119.907296) (xy 24.223939 -120.048146) (xy 24.329831 -120.193893)
			(xy 24.429077 -120.344245) (xy 24.521478 -120.498897) (xy 24.606847 -120.65754) (xy 24.685013 -120.819853)
			(xy 24.755817 -120.985509) (xy 24.819119 -121.154175) (xy 24.87479 -121.325512) (xy 24.922717 -121.499173)
			(xy 24.962805 -121.67481) (xy 24.994973 -121.852069) (xy 25.019155 -122.030592) (xy 25.035304 -122.210021)
			(xy 25.043387 -122.389993) (xy 25.043387 -122.48007) (xy 25.159471 -122.48007) (xy 25.16346 -122.339172)
			(xy 25.175414 -122.198725) (xy 25.195294 -122.05918) (xy 25.223037 -121.920983) (xy 25.258555 -121.784577)
			(xy 25.301732 -121.650398) (xy 25.352432 -121.518878) (xy 25.410492 -121.390436) (xy 25.475724 -121.265485)
			(xy 25.547922 -121.144424) (xy 25.626853 -121.027642) (xy 25.712264 -120.915513) (xy 25.803883 -120.808395)
			(xy 25.901415 -120.706632) (xy 26.004547 -120.61055) (xy 26.112951 -120.520457) (xy 26.226278 -120.43664)
			(xy 26.344165 -120.35937) (xy 26.466235 -120.288893) (xy 26.592097 -120.225434) (xy 26.721347 -120.169199)
			(xy 26.853572 -120.120365) (xy 26.988348 -120.07909) (xy 27.125243 -120.045507) (xy 27.263819 -120.019722)
			(xy 27.403632 -120.001818) (xy 27.544234 -119.991853) (xy 27.685174 -119.989858) (xy 27.826002 -119.995841)
			(xy 27.966265 -120.009781) (xy 28.105515 -120.031634) (xy 28.243306 -120.06133) (xy 28.379196 -120.098774)
			(xy 28.51275 -120.143846) (xy 28.64354 -120.196402) (xy 28.771147 -120.256273) (xy 28.895163 -120.323268)
			(xy 29.015189 -120.397171) (xy 29.130843 -120.477747) (xy 29.241752 -120.564736) (xy 29.347563 -120.657861)
			(xy 29.447935 -120.756823) (xy 29.542548 -120.861305) (xy 29.631099 -120.970973) (xy 29.713303 -121.085475)
			(xy 29.788897 -121.204444) (xy 29.791898 -121.209816) (xy 62.652667 -121.209816) (xy 62.65664 -121.089706)
			(xy 62.668543 -120.970121) (xy 62.688324 -120.851584) (xy 62.715895 -120.734613) (xy 62.751137 -120.61972)
			(xy 62.793894 -120.507408) (xy 62.843982 -120.398167) (xy 62.901179 -120.292476) (xy 62.965237 -120.190795)
			(xy 63.035874 -120.093571) (xy 63.112783 -120.001228) (xy 63.195627 -119.914169) (xy 63.284043 -119.832776)
			(xy 63.377646 -119.757405) (xy 63.476025 -119.688384) (xy 63.57875 -119.626016) (xy 63.685373 -119.570574)
			(xy 63.795427 -119.5223) (xy 63.908431 -119.481405) (xy 64.023891 -119.448068) (xy 64.141301 -119.422434)
			(xy 64.260149 -119.404616) (xy 64.379915 -119.394692) (xy 64.500074 -119.392705) (xy 64.620102 -119.398664)
			(xy 64.739474 -119.412543) (xy 64.857668 -119.43428) (xy 64.974167 -119.463782) (xy 65.088461 -119.500918)
			(xy 65.200051 -119.545527) (xy 65.308449 -119.597414) (xy 65.41318 -119.656351) (xy 65.513787 -119.722081)
			(xy 65.609831 -119.794316) (xy 65.70089 -119.872742) (xy 65.786567 -119.957013) (xy 65.866487 -120.046763)
			(xy 65.9403 -120.141599) (xy 66.007685 -120.241106) (xy 66.068346 -120.344849) (xy 66.122017 -120.452374)
			(xy 66.168465 -120.563211) (xy 66.207486 -120.676875) (xy 66.23891 -120.79287) (xy 66.262599 -120.910689)
			(xy 66.278449 -121.029815) (xy 66.286391 -121.149728) (xy 66.286888 -121.209816) (xy 102.652587 -121.209816)
			(xy 102.65656 -121.089706) (xy 102.668463 -120.970121) (xy 102.688244 -120.851584) (xy 102.715815 -120.734613)
			(xy 102.751057 -120.61972) (xy 102.793814 -120.507408) (xy 102.843902 -120.398167) (xy 102.901099 -120.292476)
			(xy 102.965157 -120.190795) (xy 103.035794 -120.093571) (xy 103.112703 -120.001228) (xy 103.195547 -119.914169)
			(xy 103.283963 -119.832776) (xy 103.377566 -119.757405) (xy 103.475945 -119.688384) (xy 103.57867 -119.626016)
			(xy 103.685293 -119.570574) (xy 103.795347 -119.5223) (xy 103.908351 -119.481405) (xy 104.023811 -119.448068)
			(xy 104.141221 -119.422434) (xy 104.260069 -119.404616) (xy 104.379835 -119.394692) (xy 104.499994 -119.392705)
			(xy 104.620022 -119.398664) (xy 104.739394 -119.412543) (xy 104.857588 -119.43428) (xy 104.974087 -119.463782)
			(xy 105.088381 -119.500918) (xy 105.199971 -119.545527) (xy 105.308369 -119.597414) (xy 105.4131 -119.656351)
			(xy 105.513707 -119.722081) (xy 105.609751 -119.794316) (xy 105.70081 -119.872742) (xy 105.786487 -119.957013)
			(xy 105.866407 -120.046763) (xy 105.94022 -120.141599) (xy 106.007605 -120.241106) (xy 106.068266 -120.344849)
			(xy 106.121937 -120.452374) (xy 106.168385 -120.563211) (xy 106.207406 -120.676875) (xy 106.23883 -120.79287)
			(xy 106.262519 -120.910689) (xy 106.278369 -121.029815) (xy 106.286311 -121.149728) (xy 106.286808 -121.209816)
			(xy 142.652761 -121.209816) (xy 142.656734 -121.089706) (xy 142.668637 -120.970121) (xy 142.688418 -120.851584)
			(xy 142.715989 -120.734613) (xy 142.751231 -120.61972) (xy 142.793988 -120.507408) (xy 142.844076 -120.398167)
			(xy 142.901273 -120.292476) (xy 142.965331 -120.190795) (xy 143.035968 -120.093571) (xy 143.112877 -120.001228)
			(xy 143.195721 -119.914169) (xy 143.284137 -119.832776) (xy 143.37774 -119.757405) (xy 143.476119 -119.688384)
			(xy 143.578844 -119.626016) (xy 143.685467 -119.570574) (xy 143.795521 -119.5223) (xy 143.908525 -119.481405)
			(xy 144.023985 -119.448068) (xy 144.141395 -119.422434) (xy 144.260243 -119.404616) (xy 144.380009 -119.394692)
			(xy 144.500168 -119.392705) (xy 144.620196 -119.398664) (xy 144.739568 -119.412543) (xy 144.857762 -119.43428)
			(xy 144.974261 -119.463782) (xy 145.088555 -119.500918) (xy 145.200145 -119.545527) (xy 145.308543 -119.597414)
			(xy 145.413274 -119.656351) (xy 145.513881 -119.722081) (xy 145.609925 -119.794316) (xy 145.700984 -119.872742)
			(xy 145.786661 -119.957013) (xy 145.866581 -120.046763) (xy 145.940394 -120.141599) (xy 146.007779 -120.241106)
			(xy 146.06844 -120.344849) (xy 146.122111 -120.452374) (xy 146.168559 -120.563211) (xy 146.20758 -120.676875)
			(xy 146.239004 -120.79287) (xy 146.262693 -120.910689) (xy 146.278543 -121.029815) (xy 146.286485 -121.149728)
			(xy 146.286982 -121.209816) (xy 182.652935 -121.209816) (xy 182.656908 -121.089706) (xy 182.668811 -120.970121)
			(xy 182.688592 -120.851584) (xy 182.716163 -120.734613) (xy 182.751405 -120.61972) (xy 182.794162 -120.507408)
			(xy 182.84425 -120.398167) (xy 182.901447 -120.292476) (xy 182.965505 -120.190795) (xy 183.036142 -120.093571)
			(xy 183.113051 -120.001228) (xy 183.195895 -119.914169) (xy 183.284311 -119.832776) (xy 183.377914 -119.757405)
			(xy 183.476293 -119.688384) (xy 183.579018 -119.626016) (xy 183.685641 -119.570574) (xy 183.795695 -119.5223)
			(xy 183.908699 -119.481405) (xy 184.024159 -119.448068) (xy 184.141569 -119.422434) (xy 184.260417 -119.404616)
			(xy 184.380183 -119.394692) (xy 184.500342 -119.392705) (xy 184.62037 -119.398664) (xy 184.739742 -119.412543)
			(xy 184.857936 -119.43428) (xy 184.974435 -119.463782) (xy 185.088729 -119.500918) (xy 185.200319 -119.545527)
			(xy 185.308717 -119.597414) (xy 185.413448 -119.656351) (xy 185.514055 -119.722081) (xy 185.610099 -119.794316)
			(xy 185.701158 -119.872742) (xy 185.786835 -119.957013) (xy 185.866755 -120.046763) (xy 185.940568 -120.141599)
			(xy 186.007953 -120.241106) (xy 186.068614 -120.344849) (xy 186.122285 -120.452374) (xy 186.168733 -120.563211)
			(xy 186.207754 -120.676875) (xy 186.239178 -120.79287) (xy 186.262867 -120.910689) (xy 186.278717 -121.029815)
			(xy 186.286659 -121.149728) (xy 186.287156 -121.209816) (xy 186.286659 -121.269904) (xy 186.278717 -121.389817)
			(xy 186.262867 -121.508943) (xy 186.239178 -121.626762) (xy 186.207754 -121.742757) (xy 186.168733 -121.856421)
			(xy 186.122285 -121.967258) (xy 186.068614 -122.074783) (xy 186.007953 -122.178526) (xy 185.940568 -122.278033)
			(xy 185.866755 -122.372869) (xy 185.786835 -122.462619) (xy 185.701158 -122.54689) (xy 185.610099 -122.625316)
			(xy 185.514055 -122.697551) (xy 185.413448 -122.763281) (xy 185.330851 -122.809762) (xy 201.460608 -122.809762)
			(xy 201.461219 -122.763359) (xy 201.470913 -122.671062) (xy 201.490171 -122.580276) (xy 201.518784 -122.491991)
			(xy 201.537062 -122.449336) (xy 201.540892 -122.439401) (xy 201.540877 -122.41813) (xy 201.537062 -122.408188)
			(xy 201.518789 -122.365532) (xy 201.490198 -122.277242) (xy 201.470944 -122.186458) (xy 201.461235 -122.094163)
			(xy 201.460608 -122.047762) (xy 201.461152 -122.004334) (xy 201.469646 -121.917893) (xy 201.486519 -121.83269)
			(xy 201.511611 -121.749536) (xy 201.527664 -121.70918) (xy 201.531108 -121.699762) (xy 201.531126 -121.679728)
			(xy 201.527664 -121.670318) (xy 201.511607 -121.629963) (xy 201.486507 -121.54681) (xy 201.469633 -121.461607)
			(xy 201.461143 -121.375165) (xy 201.460608 -121.331736) (xy 201.46121 -121.285333) (xy 201.470907 -121.193035)
			(xy 201.490167 -121.10225) (xy 201.518783 -121.013965) (xy 201.537062 -120.97131) (xy 201.540848 -120.961362)
			(xy 201.540862 -120.940104) (xy 201.537062 -120.930162) (xy 201.518813 -120.887496) (xy 201.490216 -120.79921)
			(xy 201.470955 -120.708428) (xy 201.461239 -120.616137) (xy 201.460608 -120.569736) (xy 201.461087 -120.528625)
			(xy 201.468672 -120.446755) (xy 201.48378 -120.365934) (xy 201.506282 -120.286852) (xy 201.535987 -120.210185)
			(xy 201.57264 -120.136586) (xy 201.61593 -120.066683) (xy 201.665486 -120.001075) (xy 201.720885 -119.940319)
			(xy 201.781655 -119.884936) (xy 201.847277 -119.835397) (xy 201.91719 -119.792126) (xy 201.990799 -119.755492)
			(xy 202.067474 -119.725808) (xy 202.146562 -119.703326) (xy 202.227387 -119.688239) (xy 202.309259 -119.680676)
			(xy 202.35037 -119.680228) (xy 202.396765 -119.680818) (xy 202.489054 -119.690461) (xy 202.579837 -119.709654)
			(xy 202.668131 -119.738191) (xy 202.710796 -119.756428) (xy 202.720738 -119.760234) (xy 202.742002 -119.760234)
			(xy 202.751944 -119.756428) (xy 202.794611 -119.738195) (xy 202.882902 -119.709648) (xy 202.973685 -119.690451)
			(xy 203.065974 -119.680814) (xy 203.11237 -119.680228) (xy 203.158765 -119.680818) (xy 203.251054 -119.690461)
			(xy 203.341837 -119.709654) (xy 203.430131 -119.738191) (xy 203.472796 -119.756428) (xy 203.482738 -119.760234)
			(xy 203.504002 -119.760234) (xy 203.513944 -119.756428) (xy 203.556611 -119.738195) (xy 203.644902 -119.709648)
			(xy 203.735685 -119.690451) (xy 203.827974 -119.680814) (xy 203.87437 -119.680228) (xy 203.920765 -119.680818)
			(xy 204.013054 -119.690461) (xy 204.103837 -119.709654) (xy 204.192131 -119.738191) (xy 204.234796 -119.756428)
			(xy 204.244738 -119.760234) (xy 204.266002 -119.760234) (xy 204.275944 -119.756428) (xy 204.318611 -119.738195)
			(xy 204.406902 -119.709648) (xy 204.497685 -119.690451) (xy 204.589974 -119.680814) (xy 204.63637 -119.680228)
			(xy 204.682765 -119.680818) (xy 204.775054 -119.690461) (xy 204.865837 -119.709654) (xy 204.954131 -119.738191)
			(xy 204.996796 -119.756428) (xy 205.006738 -119.760234) (xy 205.028002 -119.760234) (xy 205.037944 -119.756428)
			(xy 205.080611 -119.738195) (xy 205.168902 -119.709648) (xy 205.259685 -119.690451) (xy 205.351974 -119.680814)
			(xy 205.39837 -119.680228) (xy 205.444765 -119.680818) (xy 205.537054 -119.690461) (xy 205.627837 -119.709654)
			(xy 205.716131 -119.738191) (xy 205.758796 -119.756428) (xy 205.768738 -119.760234) (xy 205.790002 -119.760234)
			(xy 205.799944 -119.756428) (xy 205.842611 -119.738195) (xy 205.930902 -119.709648) (xy 206.021685 -119.690451)
			(xy 206.113974 -119.680814) (xy 206.16037 -119.680228) (xy 206.206765 -119.680818) (xy 206.299054 -119.690461)
			(xy 206.389837 -119.709654) (xy 206.478131 -119.738191) (xy 206.520796 -119.756428) (xy 206.530738 -119.760234)
			(xy 206.552002 -119.760234) (xy 206.561944 -119.756428) (xy 206.604611 -119.738195) (xy 206.692902 -119.709648)
			(xy 206.783685 -119.690451) (xy 206.875974 -119.680814) (xy 206.92237 -119.680228) (xy 206.968765 -119.680818)
			(xy 207.061054 -119.690461) (xy 207.151837 -119.709654) (xy 207.240131 -119.738191) (xy 207.282796 -119.756428)
			(xy 207.292738 -119.760234) (xy 207.314002 -119.760234) (xy 207.323944 -119.756428) (xy 207.366611 -119.738195)
			(xy 207.454902 -119.709648) (xy 207.545685 -119.690451) (xy 207.637974 -119.680814) (xy 207.68437 -119.680228)
			(xy 207.725476 -119.680741) (xy 207.807338 -119.688323) (xy 207.888151 -119.703424) (xy 207.967226 -119.725916)
			(xy 208.043889 -119.755607) (xy 208.117486 -119.792244) (xy 208.18739 -119.835514) (xy 208.253003 -119.885048)
			(xy 208.313767 -119.940425) (xy 208.369164 -120.00117) (xy 208.41872 -120.066768) (xy 208.462013 -120.136657)
			(xy 208.498674 -120.210242) (xy 208.528391 -120.286895) (xy 208.550909 -120.365963) (xy 208.566037 -120.446771)
			(xy 208.573645 -120.52863) (xy 208.574132 -120.569736) (xy 208.573517 -120.616138) (xy 208.563823 -120.708436)
			(xy 208.544566 -120.799221) (xy 208.515955 -120.887506) (xy 208.497678 -120.930162) (xy 208.493853 -120.940098)
			(xy 208.493867 -120.961367) (xy 208.497678 -120.97131) (xy 208.515953 -121.013966) (xy 208.544542 -121.102256)
			(xy 208.563796 -121.19304) (xy 208.573505 -121.285335) (xy 208.574132 -121.331736) (xy 208.573584 -121.375164)
			(xy 208.565091 -121.461605) (xy 208.548219 -121.546808) (xy 208.523128 -121.629962) (xy 208.507076 -121.670318)
			(xy 208.503705 -121.679744) (xy 208.503722 -121.699746) (xy 208.507076 -121.70918) (xy 208.523129 -121.749537)
			(xy 208.54823 -121.832688) (xy 208.565107 -121.917891) (xy 208.573597 -122.004333) (xy 208.574132 -122.047762)
			(xy 208.573526 -122.094165) (xy 208.56383 -122.186463) (xy 208.54457 -122.277248) (xy 208.515957 -122.365533)
			(xy 208.497678 -122.408188) (xy 208.493897 -122.418137) (xy 208.493882 -122.439394) (xy 208.497678 -122.449336)
			(xy 208.515928 -122.492002) (xy 208.544524 -122.580288) (xy 208.563785 -122.671069) (xy 208.573501 -122.763361)
			(xy 208.574132 -122.809762) (xy 215.837516 -122.809762) (xy 215.838126 -122.763359) (xy 215.847821 -122.671062)
			(xy 215.867079 -122.580276) (xy 215.895692 -122.491991) (xy 215.91397 -122.449336) (xy 215.917799 -122.439401)
			(xy 215.917785 -122.41813) (xy 215.91397 -122.408188) (xy 215.895691 -122.365534) (xy 215.867103 -122.277243)
			(xy 215.847851 -122.186458) (xy 215.838143 -122.094164) (xy 215.837516 -122.047762) (xy 215.83806 -122.004334)
			(xy 215.846553 -121.917893) (xy 215.863427 -121.83269) (xy 215.888519 -121.749536) (xy 215.904572 -121.70918)
			(xy 215.908015 -121.699762) (xy 215.908033 -121.679728) (xy 215.904572 -121.670318) (xy 215.888515 -121.629963)
			(xy 215.863416 -121.54681) (xy 215.846541 -121.461607) (xy 215.838051 -121.375165) (xy 215.837516 -121.331736)
			(xy 215.838117 -121.285333) (xy 215.847814 -121.193035) (xy 215.867075 -121.10225) (xy 215.89569 -121.013965)
			(xy 215.91397 -120.97131) (xy 215.917755 -120.961361) (xy 215.917769 -120.940104) (xy 215.91397 -120.930162)
			(xy 215.895716 -120.887498) (xy 215.867121 -120.799211) (xy 215.847862 -120.708429) (xy 215.838147 -120.616137)
			(xy 215.837516 -120.569736) (xy 215.837987 -120.528625) (xy 215.845572 -120.446754) (xy 215.86068 -120.365933)
			(xy 215.883183 -120.286851) (xy 215.912888 -120.210183) (xy 215.949542 -120.136583) (xy 215.992832 -120.066681)
			(xy 216.042388 -120.001072) (xy 216.097788 -119.940317) (xy 216.158558 -119.884933) (xy 216.224181 -119.835395)
			(xy 216.294095 -119.792124) (xy 216.367704 -119.75549) (xy 216.44438 -119.725806) (xy 216.523469 -119.703324)
			(xy 216.604294 -119.688238) (xy 216.686167 -119.680676) (xy 216.727278 -119.680228) (xy 216.773673 -119.680816)
			(xy 216.865962 -119.690459) (xy 216.956746 -119.709653) (xy 217.045039 -119.738191) (xy 217.087704 -119.756428)
			(xy 217.097646 -119.760234) (xy 217.11891 -119.760234) (xy 217.128852 -119.756428) (xy 217.171518 -119.738193)
			(xy 217.259809 -119.709646) (xy 217.350593 -119.69045) (xy 217.442882 -119.680814) (xy 217.489278 -119.680228)
			(xy 217.535673 -119.680816) (xy 217.627962 -119.690459) (xy 217.718746 -119.709653) (xy 217.807039 -119.738191)
			(xy 217.849704 -119.756428) (xy 217.859646 -119.760234) (xy 217.88091 -119.760234) (xy 217.890852 -119.756428)
			(xy 217.933518 -119.738193) (xy 218.021809 -119.709646) (xy 218.112593 -119.69045) (xy 218.204882 -119.680814)
			(xy 218.251278 -119.680228) (xy 218.297673 -119.680816) (xy 218.389962 -119.690459) (xy 218.480746 -119.709653)
			(xy 218.569039 -119.738191) (xy 218.611704 -119.756428) (xy 218.621646 -119.760234) (xy 218.64291 -119.760234)
			(xy 218.652852 -119.756428) (xy 218.695518 -119.738193) (xy 218.783809 -119.709646) (xy 218.874593 -119.69045)
			(xy 218.966882 -119.680814) (xy 219.013278 -119.680228) (xy 219.059673 -119.680816) (xy 219.151962 -119.690459)
			(xy 219.242746 -119.709653) (xy 219.331039 -119.738191) (xy 219.373704 -119.756428) (xy 219.383646 -119.760234)
			(xy 219.40491 -119.760234) (xy 219.414852 -119.756428) (xy 219.457518 -119.738193) (xy 219.545809 -119.709646)
			(xy 219.636593 -119.69045) (xy 219.728882 -119.680814) (xy 219.775278 -119.680228) (xy 219.821673 -119.680816)
			(xy 219.913962 -119.690459) (xy 220.004746 -119.709653) (xy 220.093039 -119.738191) (xy 220.135704 -119.756428)
			(xy 220.145646 -119.760234) (xy 220.16691 -119.760234) (xy 220.176852 -119.756428) (xy 220.219518 -119.738193)
			(xy 220.307809 -119.709646) (xy 220.398593 -119.69045) (xy 220.490882 -119.680814) (xy 220.537278 -119.680228)
			(xy 220.583673 -119.680816) (xy 220.675962 -119.690459) (xy 220.766746 -119.709653) (xy 220.855039 -119.738191)
			(xy 220.897704 -119.756428) (xy 220.907646 -119.760234) (xy 220.92891 -119.760234) (xy 220.938852 -119.756428)
			(xy 220.981518 -119.738193) (xy 221.069809 -119.709646) (xy 221.160593 -119.69045) (xy 221.252882 -119.680814)
			(xy 221.299278 -119.680228) (xy 221.345673 -119.680816) (xy 221.437962 -119.690459) (xy 221.528746 -119.709653)
			(xy 221.617039 -119.738191) (xy 221.659704 -119.756428) (xy 221.669646 -119.760234) (xy 221.69091 -119.760234)
			(xy 221.700852 -119.756428) (xy 221.743518 -119.738193) (xy 221.831809 -119.709646) (xy 221.922593 -119.69045)
			(xy 222.014882 -119.680814) (xy 222.061278 -119.680228) (xy 222.102384 -119.680733) (xy 222.184246 -119.688316)
			(xy 222.265059 -119.703418) (xy 222.344135 -119.72591) (xy 222.420798 -119.755602) (xy 222.494395 -119.792239)
			(xy 222.564298 -119.83551) (xy 222.629912 -119.885045) (xy 222.690676 -119.940422) (xy 222.746072 -120.001168)
			(xy 222.795628 -120.066766) (xy 222.838921 -120.136655) (xy 222.875582 -120.21024) (xy 222.905299 -120.286894)
			(xy 222.927817 -120.365962) (xy 222.942945 -120.446771) (xy 222.950553 -120.52863) (xy 222.95104 -120.569736)
			(xy 222.950424 -120.616138) (xy 222.940731 -120.708436) (xy 222.921474 -120.799221) (xy 222.892863 -120.887506)
			(xy 222.874586 -120.930162) (xy 222.87076 -120.940098) (xy 222.870774 -120.961367) (xy 222.874586 -120.97131)
			(xy 222.892861 -121.013965) (xy 222.921451 -121.102256) (xy 222.940704 -121.19304) (xy 222.950413 -121.285335)
			(xy 222.95104 -121.331736) (xy 222.950499 -121.375165) (xy 222.942005 -121.461606) (xy 222.925131 -121.546808)
			(xy 222.900038 -121.629962) (xy 222.883984 -121.670318) (xy 222.880612 -121.679744) (xy 222.88063 -121.699746)
			(xy 222.883984 -121.70918) (xy 222.900038 -121.749536) (xy 222.925139 -121.832688) (xy 222.942015 -121.917891)
			(xy 222.950505 -122.004333) (xy 222.95104 -122.047762) (xy 222.950434 -122.094165) (xy 222.940737 -122.186463)
			(xy 222.921478 -122.277248) (xy 222.892864 -122.365533) (xy 222.874586 -122.408188) (xy 222.870804 -122.418137)
			(xy 222.87079 -122.439394) (xy 222.874586 -122.449336) (xy 222.892837 -122.492001) (xy 222.921433 -122.580288)
			(xy 222.940693 -122.671069) (xy 222.950409 -122.763361) (xy 222.95104 -122.809762) (xy 222.950563 -122.851239)
			(xy 222.942823 -122.933832) (xy 222.927426 -123.015345) (xy 222.904504 -123.09507) (xy 222.889826 -123.133866)
			(xy 222.886651 -123.143365) (xy 222.887035 -123.163366) (xy 222.890588 -123.172728) (xy 222.908345 -123.214883)
			(xy 222.936112 -123.302044) (xy 222.954787 -123.391595) (xy 222.964172 -123.482589) (xy 222.964756 -123.528328)
			(xy 222.964274 -123.569438) (xy 222.956685 -123.651306) (xy 222.941572 -123.732125) (xy 222.919067 -123.811204)
			(xy 222.88936 -123.887869) (xy 222.852705 -123.961465) (xy 222.809414 -124.031365) (xy 222.759859 -124.096972)
			(xy 222.70446 -124.157726) (xy 222.643692 -124.213108) (xy 222.578072 -124.262647) (xy 222.508161 -124.305918)
			(xy 222.434555 -124.342554) (xy 222.357882 -124.372241) (xy 222.278797 -124.394726) (xy 222.197974 -124.409817)
			(xy 222.116104 -124.417385) (xy 222.074994 -124.417836) (xy 222.028598 -124.417253) (xy 221.93631 -124.407607)
			(xy 221.845526 -124.388412) (xy 221.757233 -124.359874) (xy 221.714568 -124.341636) (xy 221.704626 -124.33783)
			(xy 221.683362 -124.33783) (xy 221.67342 -124.341636) (xy 221.630759 -124.359884) (xy 221.542466 -124.388427)
			(xy 221.451681 -124.407619) (xy 221.35939 -124.417251) (xy 221.312994 -124.417836) (xy 221.266598 -124.417253)
			(xy 221.17431 -124.407607) (xy 221.083526 -124.388412) (xy 220.995233 -124.359874) (xy 220.952568 -124.341636)
			(xy 220.942626 -124.33783) (xy 220.921362 -124.33783) (xy 220.91142 -124.341636) (xy 220.868759 -124.359884)
			(xy 220.780466 -124.388427) (xy 220.689681 -124.407619) (xy 220.59739 -124.417251) (xy 220.550994 -124.417836)
			(xy 220.504598 -124.417253) (xy 220.41231 -124.407607) (xy 220.321526 -124.388412) (xy 220.233233 -124.359874)
			(xy 220.190568 -124.341636) (xy 220.180626 -124.33783) (xy 220.159362 -124.33783) (xy 220.14942 -124.341636)
			(xy 220.106759 -124.359884) (xy 220.018466 -124.388427) (xy 219.927681 -124.407619) (xy 219.83539 -124.417251)
			(xy 219.788994 -124.417836) (xy 219.742598 -124.417253) (xy 219.65031 -124.407607) (xy 219.559526 -124.388412)
			(xy 219.471233 -124.359874) (xy 219.428568 -124.341636) (xy 219.418626 -124.33783) (xy 219.397362 -124.33783)
			(xy 219.38742 -124.341636) (xy 219.344759 -124.359884) (xy 219.256466 -124.388427) (xy 219.165681 -124.407619)
			(xy 219.07339 -124.417251) (xy 219.026994 -124.417836) (xy 218.980598 -124.417253) (xy 218.88831 -124.407607)
			(xy 218.797526 -124.388412) (xy 218.709233 -124.359874) (xy 218.666568 -124.341636) (xy 218.656626 -124.33783)
			(xy 218.635362 -124.33783) (xy 218.62542 -124.341636) (xy 218.582759 -124.359884) (xy 218.494466 -124.388427)
			(xy 218.403681 -124.407619) (xy 218.31139 -124.417251) (xy 218.264994 -124.417836) (xy 218.218598 -124.417253)
			(xy 218.12631 -124.407607) (xy 218.035526 -124.388412) (xy 217.947233 -124.359874) (xy 217.904568 -124.341636)
			(xy 217.894626 -124.33783) (xy 217.873362 -124.33783) (xy 217.86342 -124.341636) (xy 217.820759 -124.359884)
			(xy 217.732466 -124.388427) (xy 217.641681 -124.407619) (xy 217.54939 -124.417251) (xy 217.502994 -124.417836)
			(xy 217.456598 -124.417253) (xy 217.36431 -124.407607) (xy 217.273526 -124.388412) (xy 217.185233 -124.359874)
			(xy 217.142568 -124.341636) (xy 217.132626 -124.33783) (xy 217.111362 -124.33783) (xy 217.10142 -124.341636)
			(xy 217.058759 -124.359884) (xy 216.970466 -124.388427) (xy 216.879681 -124.407619) (xy 216.78739 -124.417251)
			(xy 216.740994 -124.417836) (xy 216.699886 -124.417393) (xy 216.618022 -124.409808) (xy 216.537206 -124.394703)
			(xy 216.458128 -124.372207) (xy 216.381463 -124.342511) (xy 216.307865 -124.30587) (xy 216.23796 -124.262595)
			(xy 216.172346 -124.213056) (xy 216.111582 -124.157675) (xy 216.056186 -124.096925) (xy 216.00663 -124.031323)
			(xy 215.963338 -123.961429) (xy 215.926678 -123.88784) (xy 215.896964 -123.811182) (xy 215.874448 -123.73211)
			(xy 215.859323 -123.651298) (xy 215.851717 -123.569436) (xy 215.851232 -123.528328) (xy 215.851707 -123.486851)
			(xy 215.859448 -123.404258) (xy 215.874846 -123.322745) (xy 215.897768 -123.24302) (xy 215.912446 -123.204224)
			(xy 215.915622 -123.194726) (xy 215.915236 -123.174725) (xy 215.911684 -123.165362) (xy 215.893922 -123.123209)
			(xy 215.866157 -123.036047) (xy 215.847484 -122.946496) (xy 215.838099 -122.855501) (xy 215.837516 -122.809762)
			(xy 208.574132 -122.809762) (xy 208.573649 -122.851239) (xy 208.56591 -122.933831) (xy 208.550514 -123.015344)
			(xy 208.527595 -123.09507) (xy 208.512918 -123.133866) (xy 208.509744 -123.143365) (xy 208.510127 -123.163365)
			(xy 208.51368 -123.172728) (xy 208.531436 -123.214883) (xy 208.559204 -123.302044) (xy 208.577878 -123.391595)
			(xy 208.587264 -123.482589) (xy 208.587848 -123.528328) (xy 208.587374 -123.569438) (xy 208.579784 -123.651307)
			(xy 208.564672 -123.732126) (xy 208.542166 -123.811205) (xy 208.512459 -123.887871) (xy 208.475803 -123.961467)
			(xy 208.432513 -124.031368) (xy 208.382957 -124.096975) (xy 208.327557 -124.157729) (xy 208.266788 -124.213111)
			(xy 208.201168 -124.26265) (xy 208.131256 -124.305921) (xy 208.057649 -124.342556) (xy 207.980976 -124.372243)
			(xy 207.90189 -124.394727) (xy 207.821067 -124.409818) (xy 207.739196 -124.417385) (xy 207.698086 -124.417836)
			(xy 207.65169 -124.417256) (xy 207.559402 -124.407609) (xy 207.468618 -124.388413) (xy 207.380325 -124.359874)
			(xy 207.33766 -124.341636) (xy 207.327718 -124.33783) (xy 207.306454 -124.33783) (xy 207.296512 -124.341636)
			(xy 207.253852 -124.359887) (xy 207.165559 -124.388429) (xy 207.074773 -124.40762) (xy 206.982482 -124.417252)
			(xy 206.936086 -124.417836) (xy 206.88969 -124.417256) (xy 206.797402 -124.407609) (xy 206.706618 -124.388413)
			(xy 206.618325 -124.359874) (xy 206.57566 -124.341636) (xy 206.565718 -124.33783) (xy 206.544454 -124.33783)
			(xy 206.534512 -124.341636) (xy 206.491852 -124.359887) (xy 206.403559 -124.388429) (xy 206.312773 -124.40762)
			(xy 206.220482 -124.417252) (xy 206.174086 -124.417836) (xy 206.12769 -124.417256) (xy 206.035402 -124.407609)
			(xy 205.944618 -124.388413) (xy 205.856325 -124.359874) (xy 205.81366 -124.341636) (xy 205.803718 -124.33783)
			(xy 205.782454 -124.33783) (xy 205.772512 -124.341636) (xy 205.729852 -124.359887) (xy 205.641559 -124.388429)
			(xy 205.550773 -124.40762) (xy 205.458482 -124.417252) (xy 205.412086 -124.417836) (xy 205.36569 -124.417256)
			(xy 205.273402 -124.407609) (xy 205.182618 -124.388413) (xy 205.094325 -124.359874) (xy 205.05166 -124.341636)
			(xy 205.041718 -124.33783) (xy 205.020454 -124.33783) (xy 205.010512 -124.341636) (xy 204.967852 -124.359887)
			(xy 204.879559 -124.388429) (xy 204.788773 -124.40762) (xy 204.696482 -124.417252) (xy 204.650086 -124.417836)
			(xy 204.60369 -124.417256) (xy 204.511402 -124.407609) (xy 204.420618 -124.388413) (xy 204.332325 -124.359874)
			(xy 204.28966 -124.341636) (xy 204.279718 -124.33783) (xy 204.258454 -124.33783) (xy 204.248512 -124.341636)
			(xy 204.205852 -124.359887) (xy 204.117559 -124.388429) (xy 204.026773 -124.40762) (xy 203.934482 -124.417252)
			(xy 203.888086 -124.417836) (xy 203.84169 -124.417256) (xy 203.749402 -124.407609) (xy 203.658618 -124.388413)
			(xy 203.570325 -124.359874) (xy 203.52766 -124.341636) (xy 203.517718 -124.33783) (xy 203.496454 -124.33783)
			(xy 203.486512 -124.341636) (xy 203.443852 -124.359887) (xy 203.355559 -124.388429) (xy 203.264773 -124.40762)
			(xy 203.172482 -124.417252) (xy 203.126086 -124.417836) (xy 203.07969 -124.417256) (xy 202.987402 -124.407609)
			(xy 202.896618 -124.388413) (xy 202.808325 -124.359874) (xy 202.76566 -124.341636) (xy 202.755718 -124.33783)
			(xy 202.734454 -124.33783) (xy 202.724512 -124.341636) (xy 202.681852 -124.359887) (xy 202.593559 -124.388429)
			(xy 202.502773 -124.40762) (xy 202.410482 -124.417252) (xy 202.364086 -124.417836) (xy 202.322978 -124.417401)
			(xy 202.241113 -124.409815) (xy 202.160298 -124.394709) (xy 202.08122 -124.372212) (xy 202.004555 -124.342516)
			(xy 201.930956 -124.305875) (xy 201.861052 -124.262599) (xy 201.795437 -124.21306) (xy 201.734673 -124.157678)
			(xy 201.679277 -124.096927) (xy 201.629722 -124.031325) (xy 201.58643 -123.961431) (xy 201.54977 -123.887841)
			(xy 201.520056 -123.811183) (xy 201.49754 -123.732111) (xy 201.482415 -123.651299) (xy 201.474809 -123.569436)
			(xy 201.474324 -123.528328) (xy 201.4748 -123.486851) (xy 201.48254 -123.404258) (xy 201.497938 -123.322745)
			(xy 201.52086 -123.24302) (xy 201.535538 -123.204224) (xy 201.538714 -123.194726) (xy 201.538328 -123.174725)
			(xy 201.534776 -123.165362) (xy 201.517014 -123.123209) (xy 201.489249 -123.036047) (xy 201.470576 -122.946496)
			(xy 201.461191 -122.855501) (xy 201.460608 -122.809762) (xy 185.330851 -122.809762) (xy 185.308717 -122.822218)
			(xy 185.200319 -122.874105) (xy 185.088729 -122.918714) (xy 184.974435 -122.95585) (xy 184.857936 -122.985352)
			(xy 184.739742 -123.007089) (xy 184.62037 -123.020968) (xy 184.500342 -123.026927) (xy 184.380183 -123.02494)
			(xy 184.260417 -123.015016) (xy 184.141569 -122.997198) (xy 184.024159 -122.971564) (xy 183.908699 -122.938227)
			(xy 183.795695 -122.897332) (xy 183.685641 -122.849058) (xy 183.579018 -122.793616) (xy 183.476293 -122.731248)
			(xy 183.377914 -122.662227) (xy 183.284311 -122.586856) (xy 183.195895 -122.505463) (xy 183.113051 -122.418404)
			(xy 183.036142 -122.326061) (xy 182.965505 -122.228837) (xy 182.901447 -122.127156) (xy 182.84425 -122.021465)
			(xy 182.794162 -121.912224) (xy 182.751405 -121.799912) (xy 182.716163 -121.685019) (xy 182.688592 -121.568048)
			(xy 182.668811 -121.449511) (xy 182.656908 -121.329926) (xy 182.652935 -121.209816) (xy 146.286982 -121.209816)
			(xy 146.286485 -121.269904) (xy 146.278543 -121.389817) (xy 146.262693 -121.508943) (xy 146.239004 -121.626762)
			(xy 146.20758 -121.742757) (xy 146.168559 -121.856421) (xy 146.122111 -121.967258) (xy 146.06844 -122.074783)
			(xy 146.007779 -122.178526) (xy 145.940394 -122.278033) (xy 145.866581 -122.372869) (xy 145.786661 -122.462619)
			(xy 145.700984 -122.54689) (xy 145.609925 -122.625316) (xy 145.513881 -122.697551) (xy 145.413274 -122.763281)
			(xy 145.308543 -122.822218) (xy 145.200145 -122.874105) (xy 145.088555 -122.918714) (xy 144.974261 -122.95585)
			(xy 144.857762 -122.985352) (xy 144.739568 -123.007089) (xy 144.620196 -123.020968) (xy 144.500168 -123.026927)
			(xy 144.380009 -123.02494) (xy 144.260243 -123.015016) (xy 144.141395 -122.997198) (xy 144.023985 -122.971564)
			(xy 143.908525 -122.938227) (xy 143.795521 -122.897332) (xy 143.685467 -122.849058) (xy 143.578844 -122.793616)
			(xy 143.476119 -122.731248) (xy 143.37774 -122.662227) (xy 143.284137 -122.586856) (xy 143.195721 -122.505463)
			(xy 143.112877 -122.418404) (xy 143.035968 -122.326061) (xy 142.965331 -122.228837) (xy 142.901273 -122.127156)
			(xy 142.844076 -122.021465) (xy 142.793988 -121.912224) (xy 142.751231 -121.799912) (xy 142.715989 -121.685019)
			(xy 142.688418 -121.568048) (xy 142.668637 -121.449511) (xy 142.656734 -121.329926) (xy 142.652761 -121.209816)
			(xy 106.286808 -121.209816) (xy 106.286311 -121.269904) (xy 106.278369 -121.389817) (xy 106.262519 -121.508943)
			(xy 106.23883 -121.626762) (xy 106.207406 -121.742757) (xy 106.168385 -121.856421) (xy 106.121937 -121.967258)
			(xy 106.068266 -122.074783) (xy 106.007605 -122.178526) (xy 105.94022 -122.278033) (xy 105.866407 -122.372869)
			(xy 105.786487 -122.462619) (xy 105.70081 -122.54689) (xy 105.609751 -122.625316) (xy 105.513707 -122.697551)
			(xy 105.4131 -122.763281) (xy 105.308369 -122.822218) (xy 105.199971 -122.874105) (xy 105.088381 -122.918714)
			(xy 104.974087 -122.95585) (xy 104.857588 -122.985352) (xy 104.739394 -123.007089) (xy 104.620022 -123.020968)
			(xy 104.499994 -123.026927) (xy 104.379835 -123.02494) (xy 104.260069 -123.015016) (xy 104.141221 -122.997198)
			(xy 104.023811 -122.971564) (xy 103.908351 -122.938227) (xy 103.795347 -122.897332) (xy 103.685293 -122.849058)
			(xy 103.57867 -122.793616) (xy 103.475945 -122.731248) (xy 103.377566 -122.662227) (xy 103.283963 -122.586856)
			(xy 103.195547 -122.505463) (xy 103.112703 -122.418404) (xy 103.035794 -122.326061) (xy 102.965157 -122.228837)
			(xy 102.901099 -122.127156) (xy 102.843902 -122.021465) (xy 102.793814 -121.912224) (xy 102.751057 -121.799912)
			(xy 102.715815 -121.685019) (xy 102.688244 -121.568048) (xy 102.668463 -121.449511) (xy 102.65656 -121.329926)
			(xy 102.652587 -121.209816) (xy 66.286888 -121.209816) (xy 66.286391 -121.269904) (xy 66.278449 -121.389817)
			(xy 66.262599 -121.508943) (xy 66.23891 -121.626762) (xy 66.207486 -121.742757) (xy 66.168465 -121.856421)
			(xy 66.122017 -121.967258) (xy 66.068346 -122.074783) (xy 66.007685 -122.178526) (xy 65.9403 -122.278033)
			(xy 65.866487 -122.372869) (xy 65.786567 -122.462619) (xy 65.70089 -122.54689) (xy 65.609831 -122.625316)
			(xy 65.513787 -122.697551) (xy 65.41318 -122.763281) (xy 65.308449 -122.822218) (xy 65.200051 -122.874105)
			(xy 65.088461 -122.918714) (xy 64.974167 -122.95585) (xy 64.857668 -122.985352) (xy 64.739474 -123.007089)
			(xy 64.620102 -123.020968) (xy 64.500074 -123.026927) (xy 64.379915 -123.02494) (xy 64.260149 -123.015016)
			(xy 64.141301 -122.997198) (xy 64.023891 -122.971564) (xy 63.908431 -122.938227) (xy 63.795427 -122.897332)
			(xy 63.685373 -122.849058) (xy 63.57875 -122.793616) (xy 63.476025 -122.731248) (xy 63.377646 -122.662227)
			(xy 63.284043 -122.586856) (xy 63.195627 -122.505463) (xy 63.112783 -122.418404) (xy 63.035874 -122.326061)
			(xy 62.965237 -122.228837) (xy 62.901179 -122.127156) (xy 62.843982 -122.021465) (xy 62.793894 -121.912224)
			(xy 62.751137 -121.799912) (xy 62.715895 -121.685019) (xy 62.688324 -121.568048) (xy 62.668543 -121.449511)
			(xy 62.65664 -121.329926) (xy 62.652667 -121.209816) (xy 29.791898 -121.209816) (xy 29.85764 -121.327499)
			(xy 29.919311 -121.454246) (xy 29.973712 -121.584279) (xy 30.02067 -121.717182) (xy 30.060033 -121.852528)
			(xy 30.091676 -121.989885) (xy 30.115498 -122.128812) (xy 30.131421 -122.268864) (xy 30.139396 -122.409593)
			(xy 30.139894 -122.48007) (xy 30.139396 -122.550547) (xy 30.131421 -122.691276) (xy 30.115498 -122.831328)
			(xy 30.091676 -122.970255) (xy 30.060033 -123.107612) (xy 30.02067 -123.242958) (xy 29.973712 -123.375861)
			(xy 29.919311 -123.505894) (xy 29.85764 -123.632641) (xy 29.788897 -123.755696) (xy 29.713303 -123.874665)
			(xy 29.631099 -123.989167) (xy 29.542548 -124.098835) (xy 29.447935 -124.203317) (xy 29.347563 -124.302279)
			(xy 29.241752 -124.395404) (xy 29.130843 -124.482393) (xy 29.015189 -124.562969) (xy 28.895163 -124.636872)
			(xy 28.771147 -124.703867) (xy 28.64354 -124.763738) (xy 28.51275 -124.816294) (xy 28.379196 -124.861366)
			(xy 28.243306 -124.89881) (xy 28.105515 -124.928506) (xy 27.966265 -124.950359) (xy 27.826002 -124.964299)
			(xy 27.685174 -124.970282) (xy 27.544234 -124.968287) (xy 27.403632 -124.958322) (xy 27.263819 -124.940418)
			(xy 27.125243 -124.914633) (xy 26.988348 -124.88105) (xy 26.853572 -124.839775) (xy 26.721347 -124.790941)
			(xy 26.592097 -124.734706) (xy 26.466235 -124.671247) (xy 26.344165 -124.60077) (xy 26.226278 -124.5235)
			(xy 26.112951 -124.439683) (xy 26.004547 -124.34959) (xy 25.901415 -124.253508) (xy 25.803883 -124.151745)
			(xy 25.712264 -124.044627) (xy 25.626853 -123.932498) (xy 25.547922 -123.815716) (xy 25.475724 -123.694655)
			(xy 25.410492 -123.569704) (xy 25.352432 -123.441262) (xy 25.301732 -123.309742) (xy 25.258555 -123.175563)
			(xy 25.223037 -123.039157) (xy 25.195294 -122.90096) (xy 25.175414 -122.761415) (xy 25.16346 -122.620968)
			(xy 25.159471 -122.48007) (xy 25.043387 -122.48007) (xy 25.043387 -122.570147) (xy 25.035304 -122.750119)
			(xy 25.019155 -122.929548) (xy 24.994973 -123.108071) (xy 24.962805 -123.28533) (xy 24.922717 -123.460967)
			(xy 24.87479 -123.634628) (xy 24.819119 -123.805965) (xy 24.755817 -123.974631) (xy 24.685013 -124.140287)
			(xy 24.606847 -124.3026) (xy 24.521478 -124.461243) (xy 24.429077 -124.615895) (xy 24.329831 -124.766247)
			(xy 24.223939 -124.911994) (xy 24.111615 -125.052844) (xy 23.993085 -125.188513) (xy 23.868587 -125.318727)
			(xy 23.738373 -125.443225) (xy 23.602704 -125.561755) (xy 23.461854 -125.674079) (xy 23.316107 -125.779971)
			(xy 23.165755 -125.879217) (xy 23.011103 -125.971618) (xy 22.85246 -126.056987) (xy 22.690147 -126.135153)
			(xy 22.524491 -126.205957) (xy 22.355825 -126.269259) (xy 22.184488 -126.32493) (xy 22.010827 -126.372857)
			(xy 21.83519 -126.412945) (xy 21.657931 -126.445113) (xy 21.479408 -126.469295) (xy 21.299979 -126.485444)
			(xy 21.154006 -126.492) (xy 42.020472 -126.492) (xy 42.024502 -126.407397) (xy 42.036556 -126.32356)
			(xy 42.056525 -126.241249) (xy 42.084227 -126.161209) (xy 42.119412 -126.084164) (xy 42.161762 -126.010813)
			(xy 42.210892 -125.941819) (xy 42.266358 -125.877808) (xy 42.327658 -125.81936) (xy 42.394236 -125.767002)
			(xy 42.465489 -125.721211) (xy 42.540773 -125.6824) (xy 42.619405 -125.650921) (xy 42.700673 -125.627059)
			(xy 42.783841 -125.61103) (xy 42.868157 -125.60298) (xy 42.910506 -125.602492) (xy 42.956902 -125.603073)
			(xy 43.04919 -125.612718) (xy 43.139974 -125.631915) (xy 43.228267 -125.660454) (xy 43.270932 -125.678692)
			(xy 43.280874 -125.682498) (xy 43.302138 -125.682498) (xy 43.31208 -125.678692) (xy 43.354741 -125.660445)
			(xy 43.443034 -125.631902) (xy 43.533819 -125.612709) (xy 43.62611 -125.603077) (xy 43.672506 -125.602492)
			(xy 43.714854 -125.602996) (xy 43.799167 -125.611047) (xy 43.882333 -125.627077) (xy 43.963599 -125.650939)
			(xy 44.042229 -125.682418) (xy 44.11751 -125.721229) (xy 44.188761 -125.767019) (xy 44.255337 -125.819376)
			(xy 44.316634 -125.877823) (xy 44.372099 -125.941833) (xy 44.421227 -126.010825) (xy 44.463575 -126.084174)
			(xy 44.49876 -126.161217) (xy 44.526461 -126.241256) (xy 44.546429 -126.323565) (xy 44.558482 -126.407399)
			(xy 44.562513 -126.492) (xy 54.212472 -126.492) (xy 54.216502 -126.407397) (xy 54.228556 -126.32356)
			(xy 54.248525 -126.241249) (xy 54.276227 -126.161209) (xy 54.311412 -126.084164) (xy 54.353762 -126.010813)
			(xy 54.402892 -125.941819) (xy 54.458358 -125.877808) (xy 54.519658 -125.81936) (xy 54.586236 -125.767002)
			(xy 54.657489 -125.721211) (xy 54.732773 -125.6824) (xy 54.811405 -125.650921) (xy 54.892673 -125.627059)
			(xy 54.975841 -125.61103) (xy 55.060157 -125.60298) (xy 55.102506 -125.602492) (xy 55.148902 -125.603073)
			(xy 55.24119 -125.612718) (xy 55.331974 -125.631915) (xy 55.420267 -125.660454) (xy 55.462932 -125.678692)
			(xy 55.472874 -125.682498) (xy 55.494138 -125.682498) (xy 55.50408 -125.678692) (xy 55.546741 -125.660445)
			(xy 55.635034 -125.631902) (xy 55.725819 -125.612709) (xy 55.81811 -125.603077) (xy 55.864506 -125.602492)
			(xy 55.906854 -125.602996) (xy 55.991167 -125.611047) (xy 56.074333 -125.627077) (xy 56.155599 -125.650939)
			(xy 56.234229 -125.682418) (xy 56.30951 -125.721229) (xy 56.380761 -125.767019) (xy 56.447337 -125.819376)
			(xy 56.508634 -125.877823) (xy 56.564099 -125.941833) (xy 56.613227 -126.010825) (xy 56.655575 -126.084174)
			(xy 56.69076 -126.161217) (xy 56.718461 -126.241256) (xy 56.738429 -126.323565) (xy 56.750482 -126.407399)
			(xy 56.754513 -126.492) (xy 66.404472 -126.492) (xy 66.408502 -126.407397) (xy 66.420556 -126.32356)
			(xy 66.440525 -126.241249) (xy 66.468227 -126.161209) (xy 66.503412 -126.084164) (xy 66.545762 -126.010813)
			(xy 66.594892 -125.941819) (xy 66.650358 -125.877808) (xy 66.711658 -125.81936) (xy 66.778236 -125.767002)
			(xy 66.849489 -125.721211) (xy 66.924773 -125.6824) (xy 67.003405 -125.650921) (xy 67.084673 -125.627059)
			(xy 67.167841 -125.61103) (xy 67.252157 -125.60298) (xy 67.294506 -125.602492) (xy 67.340902 -125.603073)
			(xy 67.43319 -125.612718) (xy 67.523974 -125.631915) (xy 67.612267 -125.660454) (xy 67.654932 -125.678692)
			(xy 67.664874 -125.682498) (xy 67.686138 -125.682498) (xy 67.69608 -125.678692) (xy 67.738741 -125.660445)
			(xy 67.827034 -125.631902) (xy 67.917819 -125.612709) (xy 68.01011 -125.603077) (xy 68.056506 -125.602492)
			(xy 68.098854 -125.602996) (xy 68.183167 -125.611047) (xy 68.266333 -125.627077) (xy 68.347599 -125.650939)
			(xy 68.426229 -125.682418) (xy 68.50151 -125.721229) (xy 68.572761 -125.767019) (xy 68.639337 -125.819376)
			(xy 68.700634 -125.877823) (xy 68.756099 -125.941833) (xy 68.805227 -126.010825) (xy 68.847575 -126.084174)
			(xy 68.88276 -126.161217) (xy 68.910461 -126.241256) (xy 68.930429 -126.323565) (xy 68.942482 -126.407399)
			(xy 68.946513 -126.492) (xy 82.020372 -126.492) (xy 82.024402 -126.407396) (xy 82.036457 -126.323558)
			(xy 82.056426 -126.241246) (xy 82.084129 -126.161204) (xy 82.119315 -126.084159) (xy 82.161666 -126.010807)
			(xy 82.210798 -125.941813) (xy 82.266265 -125.877801) (xy 82.327566 -125.819352) (xy 82.394146 -125.766995)
			(xy 82.465401 -125.721204) (xy 82.540686 -125.682394) (xy 82.61932 -125.650916) (xy 82.700589 -125.627055)
			(xy 82.783759 -125.611028) (xy 82.868076 -125.602979) (xy 82.910426 -125.602492) (xy 82.956821 -125.603101)
			(xy 83.049109 -125.612738) (xy 83.139892 -125.631927) (xy 83.228187 -125.660458) (xy 83.270852 -125.678692)
			(xy 83.280794 -125.682498) (xy 83.302058 -125.682498) (xy 83.312 -125.678692) (xy 83.354659 -125.660439)
			(xy 83.442952 -125.631897) (xy 83.533738 -125.612706) (xy 83.62603 -125.603076) (xy 83.672426 -125.602492)
			(xy 83.714774 -125.602997) (xy 83.799085 -125.61105) (xy 83.88225 -125.627081) (xy 83.963514 -125.650944)
			(xy 84.042142 -125.682424) (xy 84.117421 -125.721235) (xy 84.188671 -125.767026) (xy 84.255245 -125.819383)
			(xy 84.316541 -125.87783) (xy 84.372004 -125.941839) (xy 84.421131 -126.010831) (xy 84.463478 -126.08418)
			(xy 84.498661 -126.161222) (xy 84.526362 -126.241259) (xy 84.546329 -126.323567) (xy 84.558383 -126.407401)
			(xy 84.562413 -126.492) (xy 94.212372 -126.492) (xy 94.216402 -126.407396) (xy 94.228457 -126.323558)
			(xy 94.248426 -126.241246) (xy 94.276129 -126.161204) (xy 94.311315 -126.084159) (xy 94.353666 -126.010807)
			(xy 94.402798 -125.941813) (xy 94.458265 -125.877801) (xy 94.519566 -125.819352) (xy 94.586146 -125.766995)
			(xy 94.657401 -125.721204) (xy 94.732686 -125.682394) (xy 94.81132 -125.650916) (xy 94.892589 -125.627055)
			(xy 94.975759 -125.611028) (xy 95.060076 -125.602979) (xy 95.102426 -125.602492) (xy 95.148821 -125.603101)
			(xy 95.241109 -125.612738) (xy 95.331892 -125.631927) (xy 95.420187 -125.660458) (xy 95.462852 -125.678692)
			(xy 95.472794 -125.682498) (xy 95.494058 -125.682498) (xy 95.504 -125.678692) (xy 95.546659 -125.660439)
			(xy 95.634952 -125.631897) (xy 95.725738 -125.612706) (xy 95.81803 -125.603076) (xy 95.864426 -125.602492)
			(xy 95.906774 -125.602997) (xy 95.991085 -125.61105) (xy 96.07425 -125.627081) (xy 96.155514 -125.650944)
			(xy 96.234142 -125.682424) (xy 96.309421 -125.721235) (xy 96.380671 -125.767026) (xy 96.447245 -125.819383)
			(xy 96.508541 -125.87783) (xy 96.564004 -125.941839) (xy 96.613131 -126.010831) (xy 96.655478 -126.08418)
			(xy 96.690661 -126.161222) (xy 96.718362 -126.241259) (xy 96.738329 -126.323567) (xy 96.750383 -126.407401)
			(xy 96.754413 -126.492) (xy 106.404372 -126.492) (xy 106.408402 -126.407396) (xy 106.420457 -126.323558)
			(xy 106.440426 -126.241246) (xy 106.468129 -126.161204) (xy 106.503315 -126.084159) (xy 106.545666 -126.010807)
			(xy 106.594798 -125.941813) (xy 106.650265 -125.877801) (xy 106.711566 -125.819352) (xy 106.778146 -125.766995)
			(xy 106.849401 -125.721204) (xy 106.924686 -125.682394) (xy 107.00332 -125.650916) (xy 107.084589 -125.627055)
			(xy 107.167759 -125.611028) (xy 107.252076 -125.602979) (xy 107.294426 -125.602492) (xy 107.340821 -125.603101)
			(xy 107.433109 -125.612738) (xy 107.523892 -125.631927) (xy 107.612187 -125.660458) (xy 107.654852 -125.678692)
			(xy 107.664794 -125.682498) (xy 107.686058 -125.682498) (xy 107.696 -125.678692) (xy 107.738659 -125.660439)
			(xy 107.826952 -125.631897) (xy 107.917738 -125.612706) (xy 108.01003 -125.603076) (xy 108.056426 -125.602492)
			(xy 108.098774 -125.602997) (xy 108.183085 -125.61105) (xy 108.26625 -125.627081) (xy 108.347514 -125.650944)
			(xy 108.426142 -125.682424) (xy 108.501421 -125.721235) (xy 108.572671 -125.767026) (xy 108.639245 -125.819383)
			(xy 108.700541 -125.87783) (xy 108.756004 -125.941839) (xy 108.805131 -126.010831) (xy 108.847478 -126.08418)
			(xy 108.882661 -126.161222) (xy 108.910362 -126.241259) (xy 108.930329 -126.323567) (xy 108.942383 -126.407401)
			(xy 108.946413 -126.492) (xy 122.020588 -126.492) (xy 122.024618 -126.407399) (xy 122.036671 -126.323564)
			(xy 122.056639 -126.241255) (xy 122.084341 -126.161216) (xy 122.119525 -126.084173) (xy 122.161874 -126.010823)
			(xy 122.211003 -125.941831) (xy 122.266468 -125.877821) (xy 122.327766 -125.819373) (xy 122.394342 -125.767017)
			(xy 122.465594 -125.721227) (xy 122.540875 -125.682416) (xy 122.619505 -125.650937) (xy 122.700772 -125.627076)
			(xy 122.783938 -125.611047) (xy 122.868252 -125.602996) (xy 122.9106 -125.602492) (xy 122.956996 -125.603075)
			(xy 123.049284 -125.61272) (xy 123.140068 -125.631916) (xy 123.228361 -125.660454) (xy 123.271026 -125.678692)
			(xy 123.280968 -125.682498) (xy 123.302232 -125.682498) (xy 123.312174 -125.678692) (xy 123.354836 -125.660447)
			(xy 123.443129 -125.631903) (xy 123.533914 -125.61271) (xy 123.626204 -125.603077) (xy 123.6726 -125.602492)
			(xy 123.714948 -125.602996) (xy 123.799262 -125.611047) (xy 123.882428 -125.627076) (xy 123.963695 -125.650937)
			(xy 124.042325 -125.682416) (xy 124.117606 -125.721227) (xy 124.188858 -125.767017) (xy 124.255434 -125.819373)
			(xy 124.316732 -125.877821) (xy 124.372197 -125.941831) (xy 124.421326 -126.010823) (xy 124.463675 -126.084173)
			(xy 124.498859 -126.161216) (xy 124.526561 -126.241255) (xy 124.546529 -126.323564) (xy 124.558582 -126.407399)
			(xy 124.562613 -126.492) (xy 134.212588 -126.492) (xy 134.216618 -126.407399) (xy 134.228671 -126.323564)
			(xy 134.248639 -126.241255) (xy 134.276341 -126.161216) (xy 134.311525 -126.084173) (xy 134.353874 -126.010823)
			(xy 134.403003 -125.941831) (xy 134.458468 -125.877821) (xy 134.519766 -125.819373) (xy 134.586342 -125.767017)
			(xy 134.657594 -125.721227) (xy 134.732875 -125.682416) (xy 134.811505 -125.650937) (xy 134.892772 -125.627076)
			(xy 134.975938 -125.611047) (xy 135.060252 -125.602996) (xy 135.1026 -125.602492) (xy 135.148996 -125.603075)
			(xy 135.241284 -125.61272) (xy 135.332068 -125.631916) (xy 135.420361 -125.660454) (xy 135.463026 -125.678692)
			(xy 135.472968 -125.682498) (xy 135.494232 -125.682498) (xy 135.504174 -125.678692) (xy 135.546836 -125.660447)
			(xy 135.635129 -125.631903) (xy 135.725914 -125.61271) (xy 135.818204 -125.603077) (xy 135.8646 -125.602492)
			(xy 135.906948 -125.602996) (xy 135.991262 -125.611047) (xy 136.074428 -125.627076) (xy 136.155695 -125.650937)
			(xy 136.234325 -125.682416) (xy 136.309606 -125.721227) (xy 136.380858 -125.767017) (xy 136.447434 -125.819373)
			(xy 136.508732 -125.877821) (xy 136.564197 -125.941831) (xy 136.613326 -126.010823) (xy 136.655675 -126.084173)
			(xy 136.690859 -126.161216) (xy 136.718561 -126.241255) (xy 136.738529 -126.323564) (xy 136.750582 -126.407399)
			(xy 136.754613 -126.492) (xy 146.404588 -126.492) (xy 146.408618 -126.407399) (xy 146.420671 -126.323564)
			(xy 146.440639 -126.241255) (xy 146.468341 -126.161216) (xy 146.503525 -126.084173) (xy 146.545874 -126.010823)
			(xy 146.595003 -125.941831) (xy 146.650468 -125.877821) (xy 146.711766 -125.819373) (xy 146.778342 -125.767017)
			(xy 146.849594 -125.721227) (xy 146.924875 -125.682416) (xy 147.003505 -125.650937) (xy 147.084772 -125.627076)
			(xy 147.167938 -125.611047) (xy 147.252252 -125.602996) (xy 147.2946 -125.602492) (xy 147.340996 -125.603075)
			(xy 147.433284 -125.61272) (xy 147.524068 -125.631916) (xy 147.612361 -125.660454) (xy 147.655026 -125.678692)
			(xy 147.664968 -125.682498) (xy 147.686232 -125.682498) (xy 147.696174 -125.678692) (xy 147.738836 -125.660447)
			(xy 147.827129 -125.631903) (xy 147.917914 -125.61271) (xy 148.010204 -125.603077) (xy 148.0566 -125.602492)
			(xy 148.098948 -125.602996) (xy 148.183262 -125.611047) (xy 148.266428 -125.627076) (xy 148.347695 -125.650937)
			(xy 148.426325 -125.682416) (xy 148.501606 -125.721227) (xy 148.572858 -125.767017) (xy 148.639434 -125.819373)
			(xy 148.700732 -125.877821) (xy 148.756197 -125.941831) (xy 148.805326 -126.010823) (xy 148.847675 -126.084173)
			(xy 148.882859 -126.161216) (xy 148.910561 -126.241255) (xy 148.930529 -126.323564) (xy 148.942582 -126.407399)
			(xy 148.946613 -126.492) (xy 162.020787 -126.492) (xy 162.024817 -126.407401) (xy 162.036871 -126.323567)
			(xy 162.056838 -126.241259) (xy 162.084539 -126.161222) (xy 162.119722 -126.08418) (xy 162.162069 -126.010831)
			(xy 162.211196 -125.941839) (xy 162.266659 -125.87783) (xy 162.327955 -125.819383) (xy 162.394529 -125.767026)
			(xy 162.465779 -125.721235) (xy 162.541058 -125.682424) (xy 162.619686 -125.650944) (xy 162.70095 -125.627081)
			(xy 162.784115 -125.61105) (xy 162.868426 -125.602997) (xy 162.910774 -125.602492) (xy 162.957169 -125.603084)
			(xy 163.049457 -125.612726) (xy 163.140241 -125.63192) (xy 163.228535 -125.660455) (xy 163.2712 -125.678692)
			(xy 163.281142 -125.682498) (xy 163.302406 -125.682498) (xy 163.312348 -125.678692) (xy 163.355014 -125.660456)
			(xy 163.443305 -125.63191) (xy 163.534089 -125.612714) (xy 163.626378 -125.603078) (xy 163.672774 -125.602492)
			(xy 163.715124 -125.602979) (xy 163.799441 -125.611028) (xy 163.882611 -125.627055) (xy 163.96388 -125.650916)
			(xy 164.042514 -125.682394) (xy 164.117799 -125.721204) (xy 164.189054 -125.766995) (xy 164.255634 -125.819352)
			(xy 164.316935 -125.877801) (xy 164.372402 -125.941813) (xy 164.421534 -126.010807) (xy 164.463885 -126.084159)
			(xy 164.499071 -126.161204) (xy 164.526774 -126.241246) (xy 164.546743 -126.323558) (xy 164.558798 -126.407396)
			(xy 164.562828 -126.492) (xy 174.212787 -126.492) (xy 174.216817 -126.407401) (xy 174.228871 -126.323567)
			(xy 174.248838 -126.241259) (xy 174.276539 -126.161222) (xy 174.311722 -126.08418) (xy 174.354069 -126.010831)
			(xy 174.403196 -125.941839) (xy 174.458659 -125.87783) (xy 174.519955 -125.819383) (xy 174.586529 -125.767026)
			(xy 174.657779 -125.721235) (xy 174.733058 -125.682424) (xy 174.811686 -125.650944) (xy 174.89295 -125.627081)
			(xy 174.976115 -125.61105) (xy 175.060426 -125.602997) (xy 175.102774 -125.602492) (xy 175.149169 -125.603084)
			(xy 175.241457 -125.612726) (xy 175.332241 -125.63192) (xy 175.420535 -125.660455) (xy 175.4632 -125.678692)
			(xy 175.473142 -125.682498) (xy 175.494406 -125.682498) (xy 175.504348 -125.678692) (xy 175.547014 -125.660456)
			(xy 175.635305 -125.63191) (xy 175.726089 -125.612714) (xy 175.818378 -125.603078) (xy 175.864774 -125.602492)
			(xy 175.907124 -125.602979) (xy 175.991441 -125.611028) (xy 176.074611 -125.627055) (xy 176.15588 -125.650916)
			(xy 176.234514 -125.682394) (xy 176.309799 -125.721204) (xy 176.381054 -125.766995) (xy 176.447634 -125.819352)
			(xy 176.508935 -125.877801) (xy 176.564402 -125.941813) (xy 176.613534 -126.010807) (xy 176.655885 -126.084159)
			(xy 176.691071 -126.161204) (xy 176.718774 -126.241246) (xy 176.738743 -126.323558) (xy 176.750798 -126.407396)
			(xy 176.754828 -126.492) (xy 186.404787 -126.492) (xy 186.408817 -126.407401) (xy 186.420871 -126.323567)
			(xy 186.440838 -126.241259) (xy 186.468539 -126.161222) (xy 186.503722 -126.08418) (xy 186.546069 -126.010831)
			(xy 186.595196 -125.941839) (xy 186.650659 -125.87783) (xy 186.711955 -125.819383) (xy 186.778529 -125.767026)
			(xy 186.849779 -125.721235) (xy 186.925058 -125.682424) (xy 187.003686 -125.650944) (xy 187.08495 -125.627081)
			(xy 187.168115 -125.61105) (xy 187.252426 -125.602997) (xy 187.294774 -125.602492) (xy 187.341169 -125.603084)
			(xy 187.433457 -125.612726) (xy 187.524241 -125.63192) (xy 187.612535 -125.660455) (xy 187.6552 -125.678692)
			(xy 187.665142 -125.682498) (xy 187.686406 -125.682498) (xy 187.696348 -125.678692) (xy 187.739014 -125.660456)
			(xy 187.827305 -125.63191) (xy 187.918089 -125.612714) (xy 188.010378 -125.603078) (xy 188.056774 -125.602492)
			(xy 188.099124 -125.602979) (xy 188.183441 -125.611028) (xy 188.266611 -125.627055) (xy 188.34788 -125.650916)
			(xy 188.426514 -125.682394) (xy 188.501799 -125.721204) (xy 188.573054 -125.766995) (xy 188.639634 -125.819352)
			(xy 188.700935 -125.877801) (xy 188.756402 -125.941813) (xy 188.805534 -126.010807) (xy 188.847885 -126.084159)
			(xy 188.883071 -126.161204) (xy 188.910774 -126.241246) (xy 188.930743 -126.323558) (xy 188.942798 -126.407396)
			(xy 188.946828 -126.492) (xy 188.942798 -126.576604) (xy 188.930743 -126.660442) (xy 188.910774 -126.742754)
			(xy 188.883071 -126.822796) (xy 188.847885 -126.899841) (xy 188.805534 -126.973193) (xy 188.756402 -127.042187)
			(xy 188.700935 -127.106199) (xy 188.639634 -127.164648) (xy 188.573054 -127.217005) (xy 188.501799 -127.262796)
			(xy 188.426514 -127.301606) (xy 188.34788 -127.333084) (xy 188.266611 -127.356945) (xy 188.183441 -127.372972)
			(xy 188.099124 -127.381021) (xy 188.056774 -127.381508) (xy 188.010379 -127.380899) (xy 187.918091 -127.371262)
			(xy 187.827308 -127.352073) (xy 187.739013 -127.323542) (xy 187.696348 -127.305308) (xy 187.686406 -127.301502)
			(xy 187.665142 -127.301502) (xy 187.6552 -127.305308) (xy 187.612541 -127.323561) (xy 187.524248 -127.352103)
			(xy 187.433462 -127.371294) (xy 187.34117 -127.380924) (xy 187.294774 -127.381508) (xy 187.252426 -127.381003)
			(xy 187.168115 -127.37295) (xy 187.08495 -127.356919) (xy 187.003686 -127.333056) (xy 186.925058 -127.301576)
			(xy 186.849779 -127.262765) (xy 186.778529 -127.216974) (xy 186.711955 -127.164617) (xy 186.650659 -127.10617)
			(xy 186.595196 -127.042161) (xy 186.546069 -126.973169) (xy 186.503722 -126.89982) (xy 186.468539 -126.822778)
			(xy 186.440838 -126.742741) (xy 186.420871 -126.660433) (xy 186.408817 -126.576599) (xy 186.404787 -126.492)
			(xy 176.754828 -126.492) (xy 176.750798 -126.576604) (xy 176.738743 -126.660442) (xy 176.718774 -126.742754)
			(xy 176.691071 -126.822796) (xy 176.655885 -126.899841) (xy 176.613534 -126.973193) (xy 176.564402 -127.042187)
			(xy 176.508935 -127.106199) (xy 176.447634 -127.164648) (xy 176.381054 -127.217005) (xy 176.309799 -127.262796)
			(xy 176.234514 -127.301606) (xy 176.15588 -127.333084) (xy 176.074611 -127.356945) (xy 175.991441 -127.372972)
			(xy 175.907124 -127.381021) (xy 175.864774 -127.381508) (xy 175.818379 -127.380899) (xy 175.726091 -127.371262)
			(xy 175.635308 -127.352073) (xy 175.547013 -127.323542) (xy 175.504348 -127.305308) (xy 175.494406 -127.301502)
			(xy 175.473142 -127.301502) (xy 175.4632 -127.305308) (xy 175.420541 -127.323561) (xy 175.332248 -127.352103)
			(xy 175.241462 -127.371294) (xy 175.14917 -127.380924) (xy 175.102774 -127.381508) (xy 175.060426 -127.381003)
			(xy 174.976115 -127.37295) (xy 174.89295 -127.356919) (xy 174.811686 -127.333056) (xy 174.733058 -127.301576)
			(xy 174.657779 -127.262765) (xy 174.586529 -127.216974) (xy 174.519955 -127.164617) (xy 174.458659 -127.10617)
			(xy 174.403196 -127.042161) (xy 174.354069 -126.973169) (xy 174.311722 -126.89982) (xy 174.276539 -126.822778)
			(xy 174.248838 -126.742741) (xy 174.228871 -126.660433) (xy 174.216817 -126.576599) (xy 174.212787 -126.492)
			(xy 164.562828 -126.492) (xy 164.558798 -126.576604) (xy 164.546743 -126.660442) (xy 164.526774 -126.742754)
			(xy 164.499071 -126.822796) (xy 164.463885 -126.899841) (xy 164.421534 -126.973193) (xy 164.372402 -127.042187)
			(xy 164.316935 -127.106199) (xy 164.255634 -127.164648) (xy 164.189054 -127.217005) (xy 164.117799 -127.262796)
			(xy 164.042514 -127.301606) (xy 163.96388 -127.333084) (xy 163.882611 -127.356945) (xy 163.799441 -127.372972)
			(xy 163.715124 -127.381021) (xy 163.672774 -127.381508) (xy 163.626379 -127.380899) (xy 163.534091 -127.371262)
			(xy 163.443308 -127.352073) (xy 163.355013 -127.323542) (xy 163.312348 -127.305308) (xy 163.302406 -127.301502)
			(xy 163.281142 -127.301502) (xy 163.2712 -127.305308) (xy 163.228541 -127.323561) (xy 163.140248 -127.352103)
			(xy 163.049462 -127.371294) (xy 162.95717 -127.380924) (xy 162.910774 -127.381508) (xy 162.868426 -127.381003)
			(xy 162.784115 -127.37295) (xy 162.70095 -127.356919) (xy 162.619686 -127.333056) (xy 162.541058 -127.301576)
			(xy 162.465779 -127.262765) (xy 162.394529 -127.216974) (xy 162.327955 -127.164617) (xy 162.266659 -127.10617)
			(xy 162.211196 -127.042161) (xy 162.162069 -126.973169) (xy 162.119722 -126.89982) (xy 162.084539 -126.822778)
			(xy 162.056838 -126.742741) (xy 162.036871 -126.660433) (xy 162.024817 -126.576599) (xy 162.020787 -126.492)
			(xy 148.946613 -126.492) (xy 148.942582 -126.576601) (xy 148.930529 -126.660436) (xy 148.910561 -126.742745)
			(xy 148.882859 -126.822784) (xy 148.847675 -126.899827) (xy 148.805326 -126.973177) (xy 148.756197 -127.042169)
			(xy 148.700732 -127.106179) (xy 148.639434 -127.164627) (xy 148.572858 -127.216983) (xy 148.501606 -127.262773)
			(xy 148.426325 -127.301584) (xy 148.347695 -127.333063) (xy 148.266428 -127.356924) (xy 148.183262 -127.372953)
			(xy 148.098948 -127.381004) (xy 148.0566 -127.381508) (xy 148.010204 -127.380925) (xy 147.917916 -127.37128)
			(xy 147.827132 -127.352084) (xy 147.738839 -127.323546) (xy 147.696174 -127.305308) (xy 147.686232 -127.301502)
			(xy 147.664968 -127.301502) (xy 147.655026 -127.305308) (xy 147.612364 -127.323553) (xy 147.524071 -127.352097)
			(xy 147.433286 -127.37129) (xy 147.340996 -127.380923) (xy 147.2946 -127.381508) (xy 147.252252 -127.381004)
			(xy 147.167938 -127.372953) (xy 147.084772 -127.356924) (xy 147.003505 -127.333063) (xy 146.924875 -127.301584)
			(xy 146.849594 -127.262773) (xy 146.778342 -127.216983) (xy 146.711766 -127.164627) (xy 146.650468 -127.106179)
			(xy 146.595003 -127.042169) (xy 146.545874 -126.973177) (xy 146.503525 -126.899827) (xy 146.468341 -126.822784)
			(xy 146.440639 -126.742745) (xy 146.420671 -126.660436) (xy 146.408618 -126.576601) (xy 146.404588 -126.492)
			(xy 136.754613 -126.492) (xy 136.750582 -126.576601) (xy 136.738529 -126.660436) (xy 136.718561 -126.742745)
			(xy 136.690859 -126.822784) (xy 136.655675 -126.899827) (xy 136.613326 -126.973177) (xy 136.564197 -127.042169)
			(xy 136.508732 -127.106179) (xy 136.447434 -127.164627) (xy 136.380858 -127.216983) (xy 136.309606 -127.262773)
			(xy 136.234325 -127.301584) (xy 136.155695 -127.333063) (xy 136.074428 -127.356924) (xy 135.991262 -127.372953)
			(xy 135.906948 -127.381004) (xy 135.8646 -127.381508) (xy 135.818204 -127.380925) (xy 135.725916 -127.37128)
			(xy 135.635132 -127.352084) (xy 135.546839 -127.323546) (xy 135.504174 -127.305308) (xy 135.494232 -127.301502)
			(xy 135.472968 -127.301502) (xy 135.463026 -127.305308) (xy 135.420364 -127.323553) (xy 135.332071 -127.352097)
			(xy 135.241286 -127.37129) (xy 135.148996 -127.380923) (xy 135.1026 -127.381508) (xy 135.060252 -127.381004)
			(xy 134.975938 -127.372953) (xy 134.892772 -127.356924) (xy 134.811505 -127.333063) (xy 134.732875 -127.301584)
			(xy 134.657594 -127.262773) (xy 134.586342 -127.216983) (xy 134.519766 -127.164627) (xy 134.458468 -127.106179)
			(xy 134.403003 -127.042169) (xy 134.353874 -126.973177) (xy 134.311525 -126.899827) (xy 134.276341 -126.822784)
			(xy 134.248639 -126.742745) (xy 134.228671 -126.660436) (xy 134.216618 -126.576601) (xy 134.212588 -126.492)
			(xy 124.562613 -126.492) (xy 124.558582 -126.576601) (xy 124.546529 -126.660436) (xy 124.526561 -126.742745)
			(xy 124.498859 -126.822784) (xy 124.463675 -126.899827) (xy 124.421326 -126.973177) (xy 124.372197 -127.042169)
			(xy 124.316732 -127.106179) (xy 124.255434 -127.164627) (xy 124.188858 -127.216983) (xy 124.117606 -127.262773)
			(xy 124.042325 -127.301584) (xy 123.963695 -127.333063) (xy 123.882428 -127.356924) (xy 123.799262 -127.372953)
			(xy 123.714948 -127.381004) (xy 123.6726 -127.381508) (xy 123.626204 -127.380925) (xy 123.533916 -127.37128)
			(xy 123.443132 -127.352084) (xy 123.354839 -127.323546) (xy 123.312174 -127.305308) (xy 123.302232 -127.301502)
			(xy 123.280968 -127.301502) (xy 123.271026 -127.305308) (xy 123.228364 -127.323553) (xy 123.140071 -127.352097)
			(xy 123.049286 -127.37129) (xy 122.956996 -127.380923) (xy 122.9106 -127.381508) (xy 122.868252 -127.381004)
			(xy 122.783938 -127.372953) (xy 122.700772 -127.356924) (xy 122.619505 -127.333063) (xy 122.540875 -127.301584)
			(xy 122.465594 -127.262773) (xy 122.394342 -127.216983) (xy 122.327766 -127.164627) (xy 122.266468 -127.106179)
			(xy 122.211003 -127.042169) (xy 122.161874 -126.973177) (xy 122.119525 -126.899827) (xy 122.084341 -126.822784)
			(xy 122.056639 -126.742745) (xy 122.036671 -126.660436) (xy 122.024618 -126.576601) (xy 122.020588 -126.492)
			(xy 108.946413 -126.492) (xy 108.942383 -126.576599) (xy 108.930329 -126.660433) (xy 108.910362 -126.742741)
			(xy 108.882661 -126.822778) (xy 108.847478 -126.89982) (xy 108.805131 -126.973169) (xy 108.756004 -127.042161)
			(xy 108.700541 -127.10617) (xy 108.639245 -127.164617) (xy 108.572671 -127.216974) (xy 108.501421 -127.262765)
			(xy 108.426142 -127.301576) (xy 108.347514 -127.333056) (xy 108.26625 -127.356919) (xy 108.183085 -127.37295)
			(xy 108.098774 -127.381003) (xy 108.056426 -127.381508) (xy 108.010031 -127.380916) (xy 107.917743 -127.371274)
			(xy 107.826959 -127.35208) (xy 107.738665 -127.323545) (xy 107.696 -127.305308) (xy 107.686058 -127.301502)
			(xy 107.664794 -127.301502) (xy 107.654852 -127.305308) (xy 107.612186 -127.323544) (xy 107.523895 -127.35209)
			(xy 107.433111 -127.371286) (xy 107.340822 -127.380922) (xy 107.294426 -127.381508) (xy 107.252076 -127.381021)
			(xy 107.167759 -127.372972) (xy 107.084589 -127.356945) (xy 107.00332 -127.333084) (xy 106.924686 -127.301606)
			(xy 106.849401 -127.262796) (xy 106.778146 -127.217005) (xy 106.711566 -127.164648) (xy 106.650265 -127.106199)
			(xy 106.594798 -127.042187) (xy 106.545666 -126.973193) (xy 106.503315 -126.899841) (xy 106.468129 -126.822796)
			(xy 106.440426 -126.742754) (xy 106.420457 -126.660442) (xy 106.408402 -126.576604) (xy 106.404372 -126.492)
			(xy 96.754413 -126.492) (xy 96.750383 -126.576599) (xy 96.738329 -126.660433) (xy 96.718362 -126.742741)
			(xy 96.690661 -126.822778) (xy 96.655478 -126.89982) (xy 96.613131 -126.973169) (xy 96.564004 -127.042161)
			(xy 96.508541 -127.10617) (xy 96.447245 -127.164617) (xy 96.380671 -127.216974) (xy 96.309421 -127.262765)
			(xy 96.234142 -127.301576) (xy 96.155514 -127.333056) (xy 96.07425 -127.356919) (xy 95.991085 -127.37295)
			(xy 95.906774 -127.381003) (xy 95.864426 -127.381508) (xy 95.818031 -127.380916) (xy 95.725743 -127.371274)
			(xy 95.634959 -127.35208) (xy 95.546665 -127.323545) (xy 95.504 -127.305308) (xy 95.494058 -127.301502)
			(xy 95.472794 -127.301502) (xy 95.462852 -127.305308) (xy 95.420186 -127.323544) (xy 95.331895 -127.35209)
			(xy 95.241111 -127.371286) (xy 95.148822 -127.380922) (xy 95.102426 -127.381508) (xy 95.060076 -127.381021)
			(xy 94.975759 -127.372972) (xy 94.892589 -127.356945) (xy 94.81132 -127.333084) (xy 94.732686 -127.301606)
			(xy 94.657401 -127.262796) (xy 94.586146 -127.217005) (xy 94.519566 -127.164648) (xy 94.458265 -127.106199)
			(xy 94.402798 -127.042187) (xy 94.353666 -126.973193) (xy 94.311315 -126.899841) (xy 94.276129 -126.822796)
			(xy 94.248426 -126.742754) (xy 94.228457 -126.660442) (xy 94.216402 -126.576604) (xy 94.212372 -126.492)
			(xy 84.562413 -126.492) (xy 84.558383 -126.576599) (xy 84.546329 -126.660433) (xy 84.526362 -126.742741)
			(xy 84.498661 -126.822778) (xy 84.463478 -126.89982) (xy 84.421131 -126.973169) (xy 84.372004 -127.042161)
			(xy 84.316541 -127.10617) (xy 84.255245 -127.164617) (xy 84.188671 -127.216974) (xy 84.117421 -127.262765)
			(xy 84.042142 -127.301576) (xy 83.963514 -127.333056) (xy 83.88225 -127.356919) (xy 83.799085 -127.37295)
			(xy 83.714774 -127.381003) (xy 83.672426 -127.381508) (xy 83.626031 -127.380916) (xy 83.533743 -127.371274)
			(xy 83.442959 -127.35208) (xy 83.354665 -127.323545) (xy 83.312 -127.305308) (xy 83.302058 -127.301502)
			(xy 83.280794 -127.301502) (xy 83.270852 -127.305308) (xy 83.228186 -127.323544) (xy 83.139895 -127.35209)
			(xy 83.049111 -127.371286) (xy 82.956822 -127.380922) (xy 82.910426 -127.381508) (xy 82.868076 -127.381021)
			(xy 82.783759 -127.372972) (xy 82.700589 -127.356945) (xy 82.61932 -127.333084) (xy 82.540686 -127.301606)
			(xy 82.465401 -127.262796) (xy 82.394146 -127.217005) (xy 82.327566 -127.164648) (xy 82.266265 -127.106199)
			(xy 82.210798 -127.042187) (xy 82.161666 -126.973193) (xy 82.119315 -126.899841) (xy 82.084129 -126.822796)
			(xy 82.056426 -126.742754) (xy 82.036457 -126.660442) (xy 82.024402 -126.576604) (xy 82.020372 -126.492)
			(xy 68.946513 -126.492) (xy 68.942482 -126.576601) (xy 68.930429 -126.660435) (xy 68.910461 -126.742744)
			(xy 68.88276 -126.822783) (xy 68.847575 -126.899826) (xy 68.805227 -126.973175) (xy 68.756099 -127.042167)
			(xy 68.700634 -127.106177) (xy 68.639337 -127.164624) (xy 68.572761 -127.216981) (xy 68.50151 -127.262771)
			(xy 68.426229 -127.301582) (xy 68.347599 -127.333061) (xy 68.266333 -127.356923) (xy 68.183167 -127.372953)
			(xy 68.098854 -127.381004) (xy 68.056506 -127.381508) (xy 68.01011 -127.380923) (xy 67.917822 -127.371279)
			(xy 67.827038 -127.352083) (xy 67.738745 -127.323546) (xy 67.69608 -127.305308) (xy 67.686138 -127.301502)
			(xy 67.664874 -127.301502) (xy 67.654932 -127.305308) (xy 67.612269 -127.323551) (xy 67.523977 -127.352095)
			(xy 67.433192 -127.371289) (xy 67.340902 -127.380923) (xy 67.294506 -127.381508) (xy 67.252157 -127.38102)
			(xy 67.167841 -127.37297) (xy 67.084673 -127.356941) (xy 67.003405 -127.333079) (xy 66.924773 -127.3016)
			(xy 66.849489 -127.262789) (xy 66.778236 -127.216998) (xy 66.711658 -127.16464) (xy 66.650358 -127.106192)
			(xy 66.594892 -127.042181) (xy 66.545762 -126.973187) (xy 66.503412 -126.899836) (xy 66.468227 -126.822791)
			(xy 66.440525 -126.742751) (xy 66.420556 -126.66044) (xy 66.408502 -126.576603) (xy 66.404472 -126.492)
			(xy 56.754513 -126.492) (xy 56.750482 -126.576601) (xy 56.738429 -126.660435) (xy 56.718461 -126.742744)
			(xy 56.69076 -126.822783) (xy 56.655575 -126.899826) (xy 56.613227 -126.973175) (xy 56.564099 -127.042167)
			(xy 56.508634 -127.106177) (xy 56.447337 -127.164624) (xy 56.380761 -127.216981) (xy 56.30951 -127.262771)
			(xy 56.234229 -127.301582) (xy 56.155599 -127.333061) (xy 56.074333 -127.356923) (xy 55.991167 -127.372953)
			(xy 55.906854 -127.381004) (xy 55.864506 -127.381508) (xy 55.81811 -127.380923) (xy 55.725822 -127.371279)
			(xy 55.635038 -127.352083) (xy 55.546745 -127.323546) (xy 55.50408 -127.305308) (xy 55.494138 -127.301502)
			(xy 55.472874 -127.301502) (xy 55.462932 -127.305308) (xy 55.420269 -127.323551) (xy 55.331977 -127.352095)
			(xy 55.241192 -127.371289) (xy 55.148902 -127.380923) (xy 55.102506 -127.381508) (xy 55.060157 -127.38102)
			(xy 54.975841 -127.37297) (xy 54.892673 -127.356941) (xy 54.811405 -127.333079) (xy 54.732773 -127.3016)
			(xy 54.657489 -127.262789) (xy 54.586236 -127.216998) (xy 54.519658 -127.16464) (xy 54.458358 -127.106192)
			(xy 54.402892 -127.042181) (xy 54.353762 -126.973187) (xy 54.311412 -126.899836) (xy 54.276227 -126.822791)
			(xy 54.248525 -126.742751) (xy 54.228556 -126.66044) (xy 54.216502 -126.576603) (xy 54.212472 -126.492)
			(xy 44.562513 -126.492) (xy 44.558482 -126.576601) (xy 44.546429 -126.660435) (xy 44.526461 -126.742744)
			(xy 44.49876 -126.822783) (xy 44.463575 -126.899826) (xy 44.421227 -126.973175) (xy 44.372099 -127.042167)
			(xy 44.316634 -127.106177) (xy 44.255337 -127.164624) (xy 44.188761 -127.216981) (xy 44.11751 -127.262771)
			(xy 44.042229 -127.301582) (xy 43.963599 -127.333061) (xy 43.882333 -127.356923) (xy 43.799167 -127.372953)
			(xy 43.714854 -127.381004) (xy 43.672506 -127.381508) (xy 43.62611 -127.380923) (xy 43.533822 -127.371279)
			(xy 43.443038 -127.352083) (xy 43.354745 -127.323546) (xy 43.31208 -127.305308) (xy 43.302138 -127.301502)
			(xy 43.280874 -127.301502) (xy 43.270932 -127.305308) (xy 43.228269 -127.323551) (xy 43.139977 -127.352095)
			(xy 43.049192 -127.371289) (xy 42.956902 -127.380923) (xy 42.910506 -127.381508) (xy 42.868157 -127.38102)
			(xy 42.783841 -127.37297) (xy 42.700673 -127.356941) (xy 42.619405 -127.333079) (xy 42.540773 -127.3016)
			(xy 42.465489 -127.262789) (xy 42.394236 -127.216998) (xy 42.327658 -127.16464) (xy 42.266358 -127.106192)
			(xy 42.210892 -127.042181) (xy 42.161762 -126.973187) (xy 42.119412 -126.899836) (xy 42.084227 -126.822791)
			(xy 42.056525 -126.742751) (xy 42.036556 -126.66044) (xy 42.024502 -126.576603) (xy 42.020472 -126.492)
			(xy 21.154006 -126.492) (xy 21.120007 -126.493527) (xy 21.02993 -126.494032) (xy 20.93918 -126.493524)
			(xy 20.757865 -126.48532) (xy 20.577106 -126.468929) (xy 20.397272 -126.444384) (xy 20.218732 -126.411736)
			(xy 20.04185 -126.371051) (xy 19.866988 -126.322413) (xy 19.694503 -126.265921) (xy 19.524747 -126.20169)
			(xy 19.358069 -126.129852) (xy 19.194807 -126.050553) (xy 19.035297 -125.963956) (xy 18.879864 -125.870238)
			(xy 18.728826 -125.76959) (xy 18.582492 -125.662218) (xy 18.44116 -125.548342) (xy 18.30512 -125.428193)
			(xy 18.17465 -125.302019) (xy 18.050016 -125.170076) (xy 17.931473 -125.032635) (xy 17.819264 -124.889976)
			(xy 17.713618 -124.742391) (xy 17.61475 -124.590181) (xy 17.522864 -124.433659) (xy 17.438146 -124.273143)
			(xy 17.399 -124.191268) (xy 17.393666 -124.179584) (xy 17.3736 -124.164598) (xy 17.264888 -124.148088)
			(xy 17.241266 -124.156216) (xy 17.232376 -124.165868) (xy 17.184455 -124.217229) (xy 17.083658 -124.315088)
			(xy 16.977503 -124.407108) (xy 16.866328 -124.492995) (xy 16.750487 -124.572477) (xy 16.630349 -124.6453)
			(xy 16.506295 -124.711232) (xy 16.37872 -124.770064) (xy 16.248031 -124.821609) (xy 16.114643 -124.865702)
			(xy 15.978981 -124.902204) (xy 15.841477 -124.930997) (xy 15.702568 -124.951991) (xy 15.562696 -124.965118)
			(xy 15.422307 -124.970337) (xy 15.281846 -124.967632) (xy 15.141762 -124.95701) (xy 15.002499 -124.938506)
			(xy 14.864501 -124.912178) (xy 14.728208 -124.87811) (xy 14.594052 -124.836411) (xy 14.462462 -124.787214)
			(xy 14.333855 -124.730674) (xy 14.208641 -124.666973) (xy 14.087218 -124.596312) (xy 13.969973 -124.518916)
			(xy 13.857279 -124.435032) (xy 13.749494 -124.344927) (xy 13.646962 -124.248887) (xy 13.550008 -124.147219)
			(xy 13.458942 -124.040245) (xy 13.374053 -123.928306) (xy 13.295611 -123.811758) (xy 13.223867 -123.690972)
			(xy 13.159047 -123.566333) (xy 13.101359 -123.438237) (xy 13.050986 -123.307092) (xy 13.008088 -123.173315)
			(xy 12.972802 -123.037332) (xy 12.94524 -122.899576) (xy 12.92549 -122.760485) (xy 12.913615 -122.620501)
			(xy 12.909653 -122.48007) (xy 10.609072 -122.48007) (xy 10.609072 -128.230122) (xy 10.608605 -128.27415)
			(xy 10.60093 -128.361872) (xy 10.585639 -128.448591) (xy 10.562848 -128.533648) (xy 10.532731 -128.616394)
			(xy 10.495516 -128.696201) (xy 10.451487 -128.77246) (xy 10.40098 -128.844592) (xy 10.344377 -128.912047)
			(xy 10.282112 -128.974313) (xy 10.214656 -129.030914) (xy 10.142523 -129.081422) (xy 10.066264 -129.12545)
			(xy 9.986457 -129.162664) (xy 9.90371 -129.192781) (xy 9.818654 -129.215571) (xy 9.731934 -129.230861)
			(xy 9.644212 -129.238536) (xy 9.600184 -129.23901) (xy 2.999994 -129.23901) (xy 2.930118 -129.2395)
			(xy 2.790585 -129.247336) (xy 2.651711 -129.262984) (xy 2.513933 -129.286393) (xy 2.377684 -129.317491)
			(xy 2.243393 -129.35618) (xy 2.111483 -129.402337) (xy 1.982368 -129.455818) (xy 1.856456 -129.516454)
			(xy 1.734141 -129.584055) (xy 1.615809 -129.658408) (xy 1.501832 -129.739279) (xy 1.392569 -129.826414)
			(xy 1.288363 -129.919537) (xy 1.189543 -130.018357) (xy 1.09642 -130.122563) (xy 1.009285 -130.231826)
			(xy 0.928414 -130.345803) (xy 0.854061 -130.464135) (xy 0.78646 -130.58645) (xy 0.725824 -130.712362)
			(xy 0.672343 -130.841477) (xy 0.626186 -130.973387) (xy 0.587497 -131.107678) (xy 0.556399 -131.243927)
			(xy 0.53299 -131.381705) (xy 0.517342 -131.520579) (xy 0.514454 -131.572) (xy 42.020472 -131.572)
			(xy 42.024502 -131.487397) (xy 42.036556 -131.40356) (xy 42.056525 -131.321249) (xy 42.084227 -131.241209)
			(xy 42.119412 -131.164164) (xy 42.161762 -131.090813) (xy 42.210892 -131.021819) (xy 42.266358 -130.957808)
			(xy 42.327658 -130.89936) (xy 42.394236 -130.847002) (xy 42.465489 -130.801211) (xy 42.540773 -130.7624)
			(xy 42.619405 -130.730921) (xy 42.700673 -130.707059) (xy 42.783841 -130.69103) (xy 42.868157 -130.68298)
			(xy 42.910506 -130.682492) (xy 42.956902 -130.683073) (xy 43.04919 -130.692718) (xy 43.139974 -130.711915)
			(xy 43.228267 -130.740454) (xy 43.270932 -130.758692) (xy 43.280874 -130.762498) (xy 43.302138 -130.762498)
			(xy 43.31208 -130.758692) (xy 43.354741 -130.740445) (xy 43.443034 -130.711902) (xy 43.533819 -130.692709)
			(xy 43.62611 -130.683077) (xy 43.672506 -130.682492) (xy 43.714854 -130.682996) (xy 43.799167 -130.691047)
			(xy 43.882333 -130.707077) (xy 43.963599 -130.730939) (xy 44.042229 -130.762418) (xy 44.11751 -130.801229)
			(xy 44.188761 -130.847019) (xy 44.255337 -130.899376) (xy 44.316634 -130.957823) (xy 44.372099 -131.021833)
			(xy 44.421227 -131.090825) (xy 44.463575 -131.164174) (xy 44.49876 -131.241217) (xy 44.526461 -131.321256)
			(xy 44.546429 -131.403565) (xy 44.558482 -131.487399) (xy 44.562513 -131.572) (xy 54.212472 -131.572)
			(xy 54.216502 -131.487397) (xy 54.228556 -131.40356) (xy 54.248525 -131.321249) (xy 54.276227 -131.241209)
			(xy 54.311412 -131.164164) (xy 54.353762 -131.090813) (xy 54.402892 -131.021819) (xy 54.458358 -130.957808)
			(xy 54.519658 -130.89936) (xy 54.586236 -130.847002) (xy 54.657489 -130.801211) (xy 54.732773 -130.7624)
			(xy 54.811405 -130.730921) (xy 54.892673 -130.707059) (xy 54.975841 -130.69103) (xy 55.060157 -130.68298)
			(xy 55.102506 -130.682492) (xy 55.148902 -130.683073) (xy 55.24119 -130.692718) (xy 55.331974 -130.711915)
			(xy 55.420267 -130.740454) (xy 55.462932 -130.758692) (xy 55.472874 -130.762498) (xy 55.494138 -130.762498)
			(xy 55.50408 -130.758692) (xy 55.546741 -130.740445) (xy 55.635034 -130.711902) (xy 55.725819 -130.692709)
			(xy 55.81811 -130.683077) (xy 55.864506 -130.682492) (xy 55.906854 -130.682996) (xy 55.991167 -130.691047)
			(xy 56.074333 -130.707077) (xy 56.155599 -130.730939) (xy 56.234229 -130.762418) (xy 56.30951 -130.801229)
			(xy 56.380761 -130.847019) (xy 56.447337 -130.899376) (xy 56.508634 -130.957823) (xy 56.564099 -131.021833)
			(xy 56.613227 -131.090825) (xy 56.655575 -131.164174) (xy 56.69076 -131.241217) (xy 56.718461 -131.321256)
			(xy 56.738429 -131.403565) (xy 56.750482 -131.487399) (xy 56.754513 -131.572) (xy 66.404472 -131.572)
			(xy 66.408502 -131.487397) (xy 66.420556 -131.40356) (xy 66.440525 -131.321249) (xy 66.468227 -131.241209)
			(xy 66.503412 -131.164164) (xy 66.545762 -131.090813) (xy 66.594892 -131.021819) (xy 66.650358 -130.957808)
			(xy 66.711658 -130.89936) (xy 66.778236 -130.847002) (xy 66.849489 -130.801211) (xy 66.924773 -130.7624)
			(xy 67.003405 -130.730921) (xy 67.084673 -130.707059) (xy 67.167841 -130.69103) (xy 67.252157 -130.68298)
			(xy 67.294506 -130.682492) (xy 67.340902 -130.683073) (xy 67.43319 -130.692718) (xy 67.523974 -130.711915)
			(xy 67.612267 -130.740454) (xy 67.654932 -130.758692) (xy 67.664874 -130.762498) (xy 67.686138 -130.762498)
			(xy 67.69608 -130.758692) (xy 67.738741 -130.740445) (xy 67.827034 -130.711902) (xy 67.917819 -130.692709)
			(xy 68.01011 -130.683077) (xy 68.056506 -130.682492) (xy 68.098854 -130.682996) (xy 68.183167 -130.691047)
			(xy 68.266333 -130.707077) (xy 68.347599 -130.730939) (xy 68.426229 -130.762418) (xy 68.50151 -130.801229)
			(xy 68.572761 -130.847019) (xy 68.639337 -130.899376) (xy 68.700634 -130.957823) (xy 68.756099 -131.021833)
			(xy 68.805227 -131.090825) (xy 68.847575 -131.164174) (xy 68.88276 -131.241217) (xy 68.910461 -131.321256)
			(xy 68.930429 -131.403565) (xy 68.942482 -131.487399) (xy 68.946513 -131.572) (xy 82.020372 -131.572)
			(xy 82.024402 -131.487396) (xy 82.036457 -131.403558) (xy 82.056426 -131.321246) (xy 82.084129 -131.241204)
			(xy 82.119315 -131.164159) (xy 82.161666 -131.090807) (xy 82.210798 -131.021813) (xy 82.266265 -130.957801)
			(xy 82.327566 -130.899352) (xy 82.394146 -130.846995) (xy 82.465401 -130.801204) (xy 82.540686 -130.762394)
			(xy 82.61932 -130.730916) (xy 82.700589 -130.707055) (xy 82.783759 -130.691028) (xy 82.868076 -130.682979)
			(xy 82.910426 -130.682492) (xy 82.956821 -130.683101) (xy 83.049109 -130.692738) (xy 83.139892 -130.711927)
			(xy 83.228187 -130.740458) (xy 83.270852 -130.758692) (xy 83.280794 -130.762498) (xy 83.302058 -130.762498)
			(xy 83.312 -130.758692) (xy 83.354659 -130.740439) (xy 83.442952 -130.711897) (xy 83.533738 -130.692706)
			(xy 83.62603 -130.683076) (xy 83.672426 -130.682492) (xy 83.714774 -130.682997) (xy 83.799085 -130.69105)
			(xy 83.88225 -130.707081) (xy 83.963514 -130.730944) (xy 84.042142 -130.762424) (xy 84.117421 -130.801235)
			(xy 84.188671 -130.847026) (xy 84.255245 -130.899383) (xy 84.316541 -130.95783) (xy 84.372004 -131.021839)
			(xy 84.421131 -131.090831) (xy 84.463478 -131.16418) (xy 84.498661 -131.241222) (xy 84.526362 -131.321259)
			(xy 84.546329 -131.403567) (xy 84.558383 -131.487401) (xy 84.562413 -131.572) (xy 94.212372 -131.572)
			(xy 94.216402 -131.487396) (xy 94.228457 -131.403558) (xy 94.248426 -131.321246) (xy 94.276129 -131.241204)
			(xy 94.311315 -131.164159) (xy 94.353666 -131.090807) (xy 94.402798 -131.021813) (xy 94.458265 -130.957801)
			(xy 94.519566 -130.899352) (xy 94.586146 -130.846995) (xy 94.657401 -130.801204) (xy 94.732686 -130.762394)
			(xy 94.81132 -130.730916) (xy 94.892589 -130.707055) (xy 94.975759 -130.691028) (xy 95.060076 -130.682979)
			(xy 95.102426 -130.682492) (xy 95.148821 -130.683101) (xy 95.241109 -130.692738) (xy 95.331892 -130.711927)
			(xy 95.420187 -130.740458) (xy 95.462852 -130.758692) (xy 95.472794 -130.762498) (xy 95.494058 -130.762498)
			(xy 95.504 -130.758692) (xy 95.546659 -130.740439) (xy 95.634952 -130.711897) (xy 95.725738 -130.692706)
			(xy 95.81803 -130.683076) (xy 95.864426 -130.682492) (xy 95.906774 -130.682997) (xy 95.991085 -130.69105)
			(xy 96.07425 -130.707081) (xy 96.155514 -130.730944) (xy 96.234142 -130.762424) (xy 96.309421 -130.801235)
			(xy 96.380671 -130.847026) (xy 96.447245 -130.899383) (xy 96.508541 -130.95783) (xy 96.564004 -131.021839)
			(xy 96.613131 -131.090831) (xy 96.655478 -131.16418) (xy 96.690661 -131.241222) (xy 96.718362 -131.321259)
			(xy 96.738329 -131.403567) (xy 96.750383 -131.487401) (xy 96.754413 -131.572) (xy 106.404372 -131.572)
			(xy 106.408402 -131.487396) (xy 106.420457 -131.403558) (xy 106.440426 -131.321246) (xy 106.468129 -131.241204)
			(xy 106.503315 -131.164159) (xy 106.545666 -131.090807) (xy 106.594798 -131.021813) (xy 106.650265 -130.957801)
			(xy 106.711566 -130.899352) (xy 106.778146 -130.846995) (xy 106.849401 -130.801204) (xy 106.924686 -130.762394)
			(xy 107.00332 -130.730916) (xy 107.084589 -130.707055) (xy 107.167759 -130.691028) (xy 107.252076 -130.682979)
			(xy 107.294426 -130.682492) (xy 107.340821 -130.683101) (xy 107.433109 -130.692738) (xy 107.523892 -130.711927)
			(xy 107.612187 -130.740458) (xy 107.654852 -130.758692) (xy 107.664794 -130.762498) (xy 107.686058 -130.762498)
			(xy 107.696 -130.758692) (xy 107.738659 -130.740439) (xy 107.826952 -130.711897) (xy 107.917738 -130.692706)
			(xy 108.01003 -130.683076) (xy 108.056426 -130.682492) (xy 108.098774 -130.682997) (xy 108.183085 -130.69105)
			(xy 108.26625 -130.707081) (xy 108.347514 -130.730944) (xy 108.426142 -130.762424) (xy 108.501421 -130.801235)
			(xy 108.572671 -130.847026) (xy 108.639245 -130.899383) (xy 108.700541 -130.95783) (xy 108.756004 -131.021839)
			(xy 108.805131 -131.090831) (xy 108.847478 -131.16418) (xy 108.882661 -131.241222) (xy 108.910362 -131.321259)
			(xy 108.930329 -131.403567) (xy 108.942383 -131.487401) (xy 108.946413 -131.572) (xy 122.020588 -131.572)
			(xy 122.024618 -131.487399) (xy 122.036671 -131.403564) (xy 122.056639 -131.321255) (xy 122.084341 -131.241216)
			(xy 122.119525 -131.164173) (xy 122.161874 -131.090823) (xy 122.211003 -131.021831) (xy 122.266468 -130.957821)
			(xy 122.327766 -130.899373) (xy 122.394342 -130.847017) (xy 122.465594 -130.801227) (xy 122.540875 -130.762416)
			(xy 122.619505 -130.730937) (xy 122.700772 -130.707076) (xy 122.783938 -130.691047) (xy 122.868252 -130.682996)
			(xy 122.9106 -130.682492) (xy 122.956996 -130.683075) (xy 123.049284 -130.69272) (xy 123.140068 -130.711916)
			(xy 123.228361 -130.740454) (xy 123.271026 -130.758692) (xy 123.280968 -130.762498) (xy 123.302232 -130.762498)
			(xy 123.312174 -130.758692) (xy 123.354836 -130.740447) (xy 123.443129 -130.711903) (xy 123.533914 -130.69271)
			(xy 123.626204 -130.683077) (xy 123.6726 -130.682492) (xy 123.714948 -130.682996) (xy 123.799262 -130.691047)
			(xy 123.882428 -130.707076) (xy 123.963695 -130.730937) (xy 124.042325 -130.762416) (xy 124.117606 -130.801227)
			(xy 124.188858 -130.847017) (xy 124.255434 -130.899373) (xy 124.316732 -130.957821) (xy 124.372197 -131.021831)
			(xy 124.421326 -131.090823) (xy 124.463675 -131.164173) (xy 124.498859 -131.241216) (xy 124.526561 -131.321255)
			(xy 124.546529 -131.403564) (xy 124.558582 -131.487399) (xy 124.562613 -131.572) (xy 134.212588 -131.572)
			(xy 134.216618 -131.487399) (xy 134.228671 -131.403564) (xy 134.248639 -131.321255) (xy 134.276341 -131.241216)
			(xy 134.311525 -131.164173) (xy 134.353874 -131.090823) (xy 134.403003 -131.021831) (xy 134.458468 -130.957821)
			(xy 134.519766 -130.899373) (xy 134.586342 -130.847017) (xy 134.657594 -130.801227) (xy 134.732875 -130.762416)
			(xy 134.811505 -130.730937) (xy 134.892772 -130.707076) (xy 134.975938 -130.691047) (xy 135.060252 -130.682996)
			(xy 135.1026 -130.682492) (xy 135.148996 -130.683075) (xy 135.241284 -130.69272) (xy 135.332068 -130.711916)
			(xy 135.420361 -130.740454) (xy 135.463026 -130.758692) (xy 135.472968 -130.762498) (xy 135.494232 -130.762498)
			(xy 135.504174 -130.758692) (xy 135.546836 -130.740447) (xy 135.635129 -130.711903) (xy 135.725914 -130.69271)
			(xy 135.818204 -130.683077) (xy 135.8646 -130.682492) (xy 135.906948 -130.682996) (xy 135.991262 -130.691047)
			(xy 136.074428 -130.707076) (xy 136.155695 -130.730937) (xy 136.234325 -130.762416) (xy 136.309606 -130.801227)
			(xy 136.380858 -130.847017) (xy 136.447434 -130.899373) (xy 136.508732 -130.957821) (xy 136.564197 -131.021831)
			(xy 136.613326 -131.090823) (xy 136.655675 -131.164173) (xy 136.690859 -131.241216) (xy 136.718561 -131.321255)
			(xy 136.738529 -131.403564) (xy 136.750582 -131.487399) (xy 136.754613 -131.572) (xy 146.404588 -131.572)
			(xy 146.408618 -131.487399) (xy 146.420671 -131.403564) (xy 146.440639 -131.321255) (xy 146.468341 -131.241216)
			(xy 146.503525 -131.164173) (xy 146.545874 -131.090823) (xy 146.595003 -131.021831) (xy 146.650468 -130.957821)
			(xy 146.711766 -130.899373) (xy 146.778342 -130.847017) (xy 146.849594 -130.801227) (xy 146.924875 -130.762416)
			(xy 147.003505 -130.730937) (xy 147.084772 -130.707076) (xy 147.167938 -130.691047) (xy 147.252252 -130.682996)
			(xy 147.2946 -130.682492) (xy 147.340996 -130.683075) (xy 147.433284 -130.69272) (xy 147.524068 -130.711916)
			(xy 147.612361 -130.740454) (xy 147.655026 -130.758692) (xy 147.664968 -130.762498) (xy 147.686232 -130.762498)
			(xy 147.696174 -130.758692) (xy 147.738836 -130.740447) (xy 147.827129 -130.711903) (xy 147.917914 -130.69271)
			(xy 148.010204 -130.683077) (xy 148.0566 -130.682492) (xy 148.098948 -130.682996) (xy 148.183262 -130.691047)
			(xy 148.266428 -130.707076) (xy 148.347695 -130.730937) (xy 148.426325 -130.762416) (xy 148.501606 -130.801227)
			(xy 148.572858 -130.847017) (xy 148.639434 -130.899373) (xy 148.700732 -130.957821) (xy 148.756197 -131.021831)
			(xy 148.805326 -131.090823) (xy 148.847675 -131.164173) (xy 148.882859 -131.241216) (xy 148.910561 -131.321255)
			(xy 148.930529 -131.403564) (xy 148.942582 -131.487399) (xy 148.946613 -131.572) (xy 162.020787 -131.572)
			(xy 162.024817 -131.487401) (xy 162.036871 -131.403567) (xy 162.056838 -131.321259) (xy 162.084539 -131.241222)
			(xy 162.119722 -131.16418) (xy 162.162069 -131.090831) (xy 162.211196 -131.021839) (xy 162.266659 -130.95783)
			(xy 162.327955 -130.899383) (xy 162.394529 -130.847026) (xy 162.465779 -130.801235) (xy 162.541058 -130.762424)
			(xy 162.619686 -130.730944) (xy 162.70095 -130.707081) (xy 162.784115 -130.69105) (xy 162.868426 -130.682997)
			(xy 162.910774 -130.682492) (xy 162.957169 -130.683084) (xy 163.049457 -130.692726) (xy 163.140241 -130.71192)
			(xy 163.228535 -130.740455) (xy 163.2712 -130.758692) (xy 163.281142 -130.762498) (xy 163.302406 -130.762498)
			(xy 163.312348 -130.758692) (xy 163.355014 -130.740456) (xy 163.443305 -130.71191) (xy 163.534089 -130.692714)
			(xy 163.626378 -130.683078) (xy 163.672774 -130.682492) (xy 163.715124 -130.682979) (xy 163.799441 -130.691028)
			(xy 163.882611 -130.707055) (xy 163.96388 -130.730916) (xy 164.042514 -130.762394) (xy 164.117799 -130.801204)
			(xy 164.189054 -130.846995) (xy 164.255634 -130.899352) (xy 164.316935 -130.957801) (xy 164.372402 -131.021813)
			(xy 164.421534 -131.090807) (xy 164.463885 -131.164159) (xy 164.499071 -131.241204) (xy 164.526774 -131.321246)
			(xy 164.546743 -131.403558) (xy 164.558798 -131.487396) (xy 164.562828 -131.572) (xy 174.212787 -131.572)
			(xy 174.216817 -131.487401) (xy 174.228871 -131.403567) (xy 174.248838 -131.321259) (xy 174.276539 -131.241222)
			(xy 174.311722 -131.16418) (xy 174.354069 -131.090831) (xy 174.403196 -131.021839) (xy 174.458659 -130.95783)
			(xy 174.519955 -130.899383) (xy 174.586529 -130.847026) (xy 174.657779 -130.801235) (xy 174.733058 -130.762424)
			(xy 174.811686 -130.730944) (xy 174.89295 -130.707081) (xy 174.976115 -130.69105) (xy 175.060426 -130.682997)
			(xy 175.102774 -130.682492) (xy 175.149169 -130.683084) (xy 175.241457 -130.692726) (xy 175.332241 -130.71192)
			(xy 175.420535 -130.740455) (xy 175.4632 -130.758692) (xy 175.473142 -130.762498) (xy 175.494406 -130.762498)
			(xy 175.504348 -130.758692) (xy 175.547014 -130.740456) (xy 175.635305 -130.71191) (xy 175.726089 -130.692714)
			(xy 175.818378 -130.683078) (xy 175.864774 -130.682492) (xy 175.907124 -130.682979) (xy 175.991441 -130.691028)
			(xy 176.074611 -130.707055) (xy 176.15588 -130.730916) (xy 176.234514 -130.762394) (xy 176.309799 -130.801204)
			(xy 176.381054 -130.846995) (xy 176.447634 -130.899352) (xy 176.508935 -130.957801) (xy 176.564402 -131.021813)
			(xy 176.613534 -131.090807) (xy 176.655885 -131.164159) (xy 176.691071 -131.241204) (xy 176.718774 -131.321246)
			(xy 176.738743 -131.403558) (xy 176.750798 -131.487396) (xy 176.754828 -131.572) (xy 186.404787 -131.572)
			(xy 186.408817 -131.487401) (xy 186.420871 -131.403567) (xy 186.440838 -131.321259) (xy 186.468539 -131.241222)
			(xy 186.503722 -131.16418) (xy 186.546069 -131.090831) (xy 186.595196 -131.021839) (xy 186.650659 -130.95783)
			(xy 186.711955 -130.899383) (xy 186.778529 -130.847026) (xy 186.849779 -130.801235) (xy 186.925058 -130.762424)
			(xy 187.003686 -130.730944) (xy 187.08495 -130.707081) (xy 187.168115 -130.69105) (xy 187.252426 -130.682997)
			(xy 187.294774 -130.682492) (xy 187.341169 -130.683084) (xy 187.433457 -130.692726) (xy 187.524241 -130.71192)
			(xy 187.612535 -130.740455) (xy 187.6552 -130.758692) (xy 187.665142 -130.762498) (xy 187.686406 -130.762498)
			(xy 187.696348 -130.758692) (xy 187.739014 -130.740456) (xy 187.827305 -130.71191) (xy 187.918089 -130.692714)
			(xy 188.010378 -130.683078) (xy 188.056774 -130.682492) (xy 188.099124 -130.682979) (xy 188.183441 -130.691028)
			(xy 188.266611 -130.707055) (xy 188.34788 -130.730916) (xy 188.426514 -130.762394) (xy 188.501799 -130.801204)
			(xy 188.573054 -130.846995) (xy 188.639634 -130.899352) (xy 188.700935 -130.957801) (xy 188.756402 -131.021813)
			(xy 188.805534 -131.090807) (xy 188.847885 -131.164159) (xy 188.883071 -131.241204) (xy 188.910774 -131.321246)
			(xy 188.930743 -131.403558) (xy 188.942798 -131.487396) (xy 188.946828 -131.572) (xy 188.942798 -131.656604)
			(xy 188.930743 -131.740442) (xy 188.910774 -131.822754) (xy 188.883071 -131.902796) (xy 188.847885 -131.979841)
			(xy 188.805534 -132.053193) (xy 188.756402 -132.122187) (xy 188.700935 -132.186199) (xy 188.639634 -132.244648)
			(xy 188.573054 -132.297005) (xy 188.501799 -132.342796) (xy 188.426514 -132.381606) (xy 188.34788 -132.413084)
			(xy 188.266611 -132.436945) (xy 188.183441 -132.452972) (xy 188.099124 -132.461021) (xy 188.056774 -132.461508)
			(xy 188.010379 -132.460899) (xy 187.918091 -132.451262) (xy 187.827308 -132.432073) (xy 187.739013 -132.403542)
			(xy 187.696348 -132.385308) (xy 187.686406 -132.381502) (xy 187.665142 -132.381502) (xy 187.6552 -132.385308)
			(xy 187.612541 -132.403561) (xy 187.524248 -132.432103) (xy 187.433462 -132.451294) (xy 187.34117 -132.460924)
			(xy 187.294774 -132.461508) (xy 187.252426 -132.461003) (xy 187.168115 -132.45295) (xy 187.08495 -132.436919)
			(xy 187.003686 -132.413056) (xy 186.925058 -132.381576) (xy 186.849779 -132.342765) (xy 186.778529 -132.296974)
			(xy 186.711955 -132.244617) (xy 186.650659 -132.18617) (xy 186.595196 -132.122161) (xy 186.546069 -132.053169)
			(xy 186.503722 -131.97982) (xy 186.468539 -131.902778) (xy 186.440838 -131.822741) (xy 186.420871 -131.740433)
			(xy 186.408817 -131.656599) (xy 186.404787 -131.572) (xy 176.754828 -131.572) (xy 176.750798 -131.656604)
			(xy 176.738743 -131.740442) (xy 176.718774 -131.822754) (xy 176.691071 -131.902796) (xy 176.655885 -131.979841)
			(xy 176.613534 -132.053193) (xy 176.564402 -132.122187) (xy 176.508935 -132.186199) (xy 176.447634 -132.244648)
			(xy 176.381054 -132.297005) (xy 176.309799 -132.342796) (xy 176.234514 -132.381606) (xy 176.15588 -132.413084)
			(xy 176.074611 -132.436945) (xy 175.991441 -132.452972) (xy 175.907124 -132.461021) (xy 175.864774 -132.461508)
			(xy 175.818379 -132.460899) (xy 175.726091 -132.451262) (xy 175.635308 -132.432073) (xy 175.547013 -132.403542)
			(xy 175.504348 -132.385308) (xy 175.494406 -132.381502) (xy 175.473142 -132.381502) (xy 175.4632 -132.385308)
			(xy 175.420541 -132.403561) (xy 175.332248 -132.432103) (xy 175.241462 -132.451294) (xy 175.14917 -132.460924)
			(xy 175.102774 -132.461508) (xy 175.060426 -132.461003) (xy 174.976115 -132.45295) (xy 174.89295 -132.436919)
			(xy 174.811686 -132.413056) (xy 174.733058 -132.381576) (xy 174.657779 -132.342765) (xy 174.586529 -132.296974)
			(xy 174.519955 -132.244617) (xy 174.458659 -132.18617) (xy 174.403196 -132.122161) (xy 174.354069 -132.053169)
			(xy 174.311722 -131.97982) (xy 174.276539 -131.902778) (xy 174.248838 -131.822741) (xy 174.228871 -131.740433)
			(xy 174.216817 -131.656599) (xy 174.212787 -131.572) (xy 164.562828 -131.572) (xy 164.558798 -131.656604)
			(xy 164.546743 -131.740442) (xy 164.526774 -131.822754) (xy 164.499071 -131.902796) (xy 164.463885 -131.979841)
			(xy 164.421534 -132.053193) (xy 164.372402 -132.122187) (xy 164.316935 -132.186199) (xy 164.255634 -132.244648)
			(xy 164.189054 -132.297005) (xy 164.117799 -132.342796) (xy 164.042514 -132.381606) (xy 163.96388 -132.413084)
			(xy 163.882611 -132.436945) (xy 163.799441 -132.452972) (xy 163.715124 -132.461021) (xy 163.672774 -132.461508)
			(xy 163.626379 -132.460899) (xy 163.534091 -132.451262) (xy 163.443308 -132.432073) (xy 163.355013 -132.403542)
			(xy 163.312348 -132.385308) (xy 163.302406 -132.381502) (xy 163.281142 -132.381502) (xy 163.2712 -132.385308)
			(xy 163.228541 -132.403561) (xy 163.140248 -132.432103) (xy 163.049462 -132.451294) (xy 162.95717 -132.460924)
			(xy 162.910774 -132.461508) (xy 162.868426 -132.461003) (xy 162.784115 -132.45295) (xy 162.70095 -132.436919)
			(xy 162.619686 -132.413056) (xy 162.541058 -132.381576) (xy 162.465779 -132.342765) (xy 162.394529 -132.296974)
			(xy 162.327955 -132.244617) (xy 162.266659 -132.18617) (xy 162.211196 -132.122161) (xy 162.162069 -132.053169)
			(xy 162.119722 -131.97982) (xy 162.084539 -131.902778) (xy 162.056838 -131.822741) (xy 162.036871 -131.740433)
			(xy 162.024817 -131.656599) (xy 162.020787 -131.572) (xy 148.946613 -131.572) (xy 148.942582 -131.656601)
			(xy 148.930529 -131.740436) (xy 148.910561 -131.822745) (xy 148.882859 -131.902784) (xy 148.847675 -131.979827)
			(xy 148.805326 -132.053177) (xy 148.756197 -132.122169) (xy 148.700732 -132.186179) (xy 148.639434 -132.244627)
			(xy 148.572858 -132.296983) (xy 148.501606 -132.342773) (xy 148.426325 -132.381584) (xy 148.347695 -132.413063)
			(xy 148.266428 -132.436924) (xy 148.183262 -132.452953) (xy 148.098948 -132.461004) (xy 148.0566 -132.461508)
			(xy 148.010204 -132.460925) (xy 147.917916 -132.45128) (xy 147.827132 -132.432084) (xy 147.738839 -132.403546)
			(xy 147.696174 -132.385308) (xy 147.686232 -132.381502) (xy 147.664968 -132.381502) (xy 147.655026 -132.385308)
			(xy 147.612364 -132.403553) (xy 147.524071 -132.432097) (xy 147.433286 -132.45129) (xy 147.340996 -132.460923)
			(xy 147.2946 -132.461508) (xy 147.252252 -132.461004) (xy 147.167938 -132.452953) (xy 147.084772 -132.436924)
			(xy 147.003505 -132.413063) (xy 146.924875 -132.381584) (xy 146.849594 -132.342773) (xy 146.778342 -132.296983)
			(xy 146.711766 -132.244627) (xy 146.650468 -132.186179) (xy 146.595003 -132.122169) (xy 146.545874 -132.053177)
			(xy 146.503525 -131.979827) (xy 146.468341 -131.902784) (xy 146.440639 -131.822745) (xy 146.420671 -131.740436)
			(xy 146.408618 -131.656601) (xy 146.404588 -131.572) (xy 136.754613 -131.572) (xy 136.750582 -131.656601)
			(xy 136.738529 -131.740436) (xy 136.718561 -131.822745) (xy 136.690859 -131.902784) (xy 136.655675 -131.979827)
			(xy 136.613326 -132.053177) (xy 136.564197 -132.122169) (xy 136.508732 -132.186179) (xy 136.447434 -132.244627)
			(xy 136.380858 -132.296983) (xy 136.309606 -132.342773) (xy 136.234325 -132.381584) (xy 136.155695 -132.413063)
			(xy 136.074428 -132.436924) (xy 135.991262 -132.452953) (xy 135.906948 -132.461004) (xy 135.8646 -132.461508)
			(xy 135.818204 -132.460925) (xy 135.725916 -132.45128) (xy 135.635132 -132.432084) (xy 135.546839 -132.403546)
			(xy 135.504174 -132.385308) (xy 135.494232 -132.381502) (xy 135.472968 -132.381502) (xy 135.463026 -132.385308)
			(xy 135.420364 -132.403553) (xy 135.332071 -132.432097) (xy 135.241286 -132.45129) (xy 135.148996 -132.460923)
			(xy 135.1026 -132.461508) (xy 135.060252 -132.461004) (xy 134.975938 -132.452953) (xy 134.892772 -132.436924)
			(xy 134.811505 -132.413063) (xy 134.732875 -132.381584) (xy 134.657594 -132.342773) (xy 134.586342 -132.296983)
			(xy 134.519766 -132.244627) (xy 134.458468 -132.186179) (xy 134.403003 -132.122169) (xy 134.353874 -132.053177)
			(xy 134.311525 -131.979827) (xy 134.276341 -131.902784) (xy 134.248639 -131.822745) (xy 134.228671 -131.740436)
			(xy 134.216618 -131.656601) (xy 134.212588 -131.572) (xy 124.562613 -131.572) (xy 124.558582 -131.656601)
			(xy 124.546529 -131.740436) (xy 124.526561 -131.822745) (xy 124.498859 -131.902784) (xy 124.463675 -131.979827)
			(xy 124.421326 -132.053177) (xy 124.372197 -132.122169) (xy 124.316732 -132.186179) (xy 124.255434 -132.244627)
			(xy 124.188858 -132.296983) (xy 124.117606 -132.342773) (xy 124.042325 -132.381584) (xy 123.963695 -132.413063)
			(xy 123.882428 -132.436924) (xy 123.799262 -132.452953) (xy 123.714948 -132.461004) (xy 123.6726 -132.461508)
			(xy 123.626204 -132.460925) (xy 123.533916 -132.45128) (xy 123.443132 -132.432084) (xy 123.354839 -132.403546)
			(xy 123.312174 -132.385308) (xy 123.302232 -132.381502) (xy 123.280968 -132.381502) (xy 123.271026 -132.385308)
			(xy 123.228364 -132.403553) (xy 123.140071 -132.432097) (xy 123.049286 -132.45129) (xy 122.956996 -132.460923)
			(xy 122.9106 -132.461508) (xy 122.868252 -132.461004) (xy 122.783938 -132.452953) (xy 122.700772 -132.436924)
			(xy 122.619505 -132.413063) (xy 122.540875 -132.381584) (xy 122.465594 -132.342773) (xy 122.394342 -132.296983)
			(xy 122.327766 -132.244627) (xy 122.266468 -132.186179) (xy 122.211003 -132.122169) (xy 122.161874 -132.053177)
			(xy 122.119525 -131.979827) (xy 122.084341 -131.902784) (xy 122.056639 -131.822745) (xy 122.036671 -131.740436)
			(xy 122.024618 -131.656601) (xy 122.020588 -131.572) (xy 108.946413 -131.572) (xy 108.942383 -131.656599)
			(xy 108.930329 -131.740433) (xy 108.910362 -131.822741) (xy 108.882661 -131.902778) (xy 108.847478 -131.97982)
			(xy 108.805131 -132.053169) (xy 108.756004 -132.122161) (xy 108.700541 -132.18617) (xy 108.639245 -132.244617)
			(xy 108.572671 -132.296974) (xy 108.501421 -132.342765) (xy 108.426142 -132.381576) (xy 108.347514 -132.413056)
			(xy 108.26625 -132.436919) (xy 108.183085 -132.45295) (xy 108.098774 -132.461003) (xy 108.056426 -132.461508)
			(xy 108.010031 -132.460916) (xy 107.917743 -132.451274) (xy 107.826959 -132.43208) (xy 107.738665 -132.403545)
			(xy 107.696 -132.385308) (xy 107.686058 -132.381502) (xy 107.664794 -132.381502) (xy 107.654852 -132.385308)
			(xy 107.612186 -132.403544) (xy 107.523895 -132.43209) (xy 107.433111 -132.451286) (xy 107.340822 -132.460922)
			(xy 107.294426 -132.461508) (xy 107.252076 -132.461021) (xy 107.167759 -132.452972) (xy 107.084589 -132.436945)
			(xy 107.00332 -132.413084) (xy 106.924686 -132.381606) (xy 106.849401 -132.342796) (xy 106.778146 -132.297005)
			(xy 106.711566 -132.244648) (xy 106.650265 -132.186199) (xy 106.594798 -132.122187) (xy 106.545666 -132.053193)
			(xy 106.503315 -131.979841) (xy 106.468129 -131.902796) (xy 106.440426 -131.822754) (xy 106.420457 -131.740442)
			(xy 106.408402 -131.656604) (xy 106.404372 -131.572) (xy 96.754413 -131.572) (xy 96.750383 -131.656599)
			(xy 96.738329 -131.740433) (xy 96.718362 -131.822741) (xy 96.690661 -131.902778) (xy 96.655478 -131.97982)
			(xy 96.613131 -132.053169) (xy 96.564004 -132.122161) (xy 96.508541 -132.18617) (xy 96.447245 -132.244617)
			(xy 96.380671 -132.296974) (xy 96.309421 -132.342765) (xy 96.234142 -132.381576) (xy 96.155514 -132.413056)
			(xy 96.07425 -132.436919) (xy 95.991085 -132.45295) (xy 95.906774 -132.461003) (xy 95.864426 -132.461508)
			(xy 95.818031 -132.460916) (xy 95.725743 -132.451274) (xy 95.634959 -132.43208) (xy 95.546665 -132.403545)
			(xy 95.504 -132.385308) (xy 95.494058 -132.381502) (xy 95.472794 -132.381502) (xy 95.462852 -132.385308)
			(xy 95.420186 -132.403544) (xy 95.331895 -132.43209) (xy 95.241111 -132.451286) (xy 95.148822 -132.460922)
			(xy 95.102426 -132.461508) (xy 95.060076 -132.461021) (xy 94.975759 -132.452972) (xy 94.892589 -132.436945)
			(xy 94.81132 -132.413084) (xy 94.732686 -132.381606) (xy 94.657401 -132.342796) (xy 94.586146 -132.297005)
			(xy 94.519566 -132.244648) (xy 94.458265 -132.186199) (xy 94.402798 -132.122187) (xy 94.353666 -132.053193)
			(xy 94.311315 -131.979841) (xy 94.276129 -131.902796) (xy 94.248426 -131.822754) (xy 94.228457 -131.740442)
			(xy 94.216402 -131.656604) (xy 94.212372 -131.572) (xy 84.562413 -131.572) (xy 84.558383 -131.656599)
			(xy 84.546329 -131.740433) (xy 84.526362 -131.822741) (xy 84.498661 -131.902778) (xy 84.463478 -131.97982)
			(xy 84.421131 -132.053169) (xy 84.372004 -132.122161) (xy 84.316541 -132.18617) (xy 84.255245 -132.244617)
			(xy 84.188671 -132.296974) (xy 84.117421 -132.342765) (xy 84.042142 -132.381576) (xy 83.963514 -132.413056)
			(xy 83.88225 -132.436919) (xy 83.799085 -132.45295) (xy 83.714774 -132.461003) (xy 83.672426 -132.461508)
			(xy 83.626031 -132.460916) (xy 83.533743 -132.451274) (xy 83.442959 -132.43208) (xy 83.354665 -132.403545)
			(xy 83.312 -132.385308) (xy 83.302058 -132.381502) (xy 83.280794 -132.381502) (xy 83.270852 -132.385308)
			(xy 83.228186 -132.403544) (xy 83.139895 -132.43209) (xy 83.049111 -132.451286) (xy 82.956822 -132.460922)
			(xy 82.910426 -132.461508) (xy 82.868076 -132.461021) (xy 82.783759 -132.452972) (xy 82.700589 -132.436945)
			(xy 82.61932 -132.413084) (xy 82.540686 -132.381606) (xy 82.465401 -132.342796) (xy 82.394146 -132.297005)
			(xy 82.327566 -132.244648) (xy 82.266265 -132.186199) (xy 82.210798 -132.122187) (xy 82.161666 -132.053193)
			(xy 82.119315 -131.979841) (xy 82.084129 -131.902796) (xy 82.056426 -131.822754) (xy 82.036457 -131.740442)
			(xy 82.024402 -131.656604) (xy 82.020372 -131.572) (xy 68.946513 -131.572) (xy 68.942482 -131.656601)
			(xy 68.930429 -131.740435) (xy 68.910461 -131.822744) (xy 68.88276 -131.902783) (xy 68.847575 -131.979826)
			(xy 68.805227 -132.053175) (xy 68.756099 -132.122167) (xy 68.700634 -132.186177) (xy 68.639337 -132.244624)
			(xy 68.572761 -132.296981) (xy 68.50151 -132.342771) (xy 68.426229 -132.381582) (xy 68.347599 -132.413061)
			(xy 68.266333 -132.436923) (xy 68.183167 -132.452953) (xy 68.098854 -132.461004) (xy 68.056506 -132.461508)
			(xy 68.01011 -132.460923) (xy 67.917822 -132.451279) (xy 67.827038 -132.432083) (xy 67.738745 -132.403546)
			(xy 67.69608 -132.385308) (xy 67.686138 -132.381502) (xy 67.664874 -132.381502) (xy 67.654932 -132.385308)
			(xy 67.612269 -132.403551) (xy 67.523977 -132.432095) (xy 67.433192 -132.451289) (xy 67.340902 -132.460923)
			(xy 67.294506 -132.461508) (xy 67.252157 -132.46102) (xy 67.167841 -132.45297) (xy 67.084673 -132.436941)
			(xy 67.003405 -132.413079) (xy 66.924773 -132.3816) (xy 66.849489 -132.342789) (xy 66.778236 -132.296998)
			(xy 66.711658 -132.24464) (xy 66.650358 -132.186192) (xy 66.594892 -132.122181) (xy 66.545762 -132.053187)
			(xy 66.503412 -131.979836) (xy 66.468227 -131.902791) (xy 66.440525 -131.822751) (xy 66.420556 -131.74044)
			(xy 66.408502 -131.656603) (xy 66.404472 -131.572) (xy 56.754513 -131.572) (xy 56.750482 -131.656601)
			(xy 56.738429 -131.740435) (xy 56.718461 -131.822744) (xy 56.69076 -131.902783) (xy 56.655575 -131.979826)
			(xy 56.613227 -132.053175) (xy 56.564099 -132.122167) (xy 56.508634 -132.186177) (xy 56.447337 -132.244624)
			(xy 56.380761 -132.296981) (xy 56.30951 -132.342771) (xy 56.234229 -132.381582) (xy 56.155599 -132.413061)
			(xy 56.074333 -132.436923) (xy 55.991167 -132.452953) (xy 55.906854 -132.461004) (xy 55.864506 -132.461508)
			(xy 55.81811 -132.460923) (xy 55.725822 -132.451279) (xy 55.635038 -132.432083) (xy 55.546745 -132.403546)
			(xy 55.50408 -132.385308) (xy 55.494138 -132.381502) (xy 55.472874 -132.381502) (xy 55.462932 -132.385308)
			(xy 55.420269 -132.403551) (xy 55.331977 -132.432095) (xy 55.241192 -132.451289) (xy 55.148902 -132.460923)
			(xy 55.102506 -132.461508) (xy 55.060157 -132.46102) (xy 54.975841 -132.45297) (xy 54.892673 -132.436941)
			(xy 54.811405 -132.413079) (xy 54.732773 -132.3816) (xy 54.657489 -132.342789) (xy 54.586236 -132.296998)
			(xy 54.519658 -132.24464) (xy 54.458358 -132.186192) (xy 54.402892 -132.122181) (xy 54.353762 -132.053187)
			(xy 54.311412 -131.979836) (xy 54.276227 -131.902791) (xy 54.248525 -131.822751) (xy 54.228556 -131.74044)
			(xy 54.216502 -131.656603) (xy 54.212472 -131.572) (xy 44.562513 -131.572) (xy 44.558482 -131.656601)
			(xy 44.546429 -131.740435) (xy 44.526461 -131.822744) (xy 44.49876 -131.902783) (xy 44.463575 -131.979826)
			(xy 44.421227 -132.053175) (xy 44.372099 -132.122167) (xy 44.316634 -132.186177) (xy 44.255337 -132.244624)
			(xy 44.188761 -132.296981) (xy 44.11751 -132.342771) (xy 44.042229 -132.381582) (xy 43.963599 -132.413061)
			(xy 43.882333 -132.436923) (xy 43.799167 -132.452953) (xy 43.714854 -132.461004) (xy 43.672506 -132.461508)
			(xy 43.62611 -132.460923) (xy 43.533822 -132.451279) (xy 43.443038 -132.432083) (xy 43.354745 -132.403546)
			(xy 43.31208 -132.385308) (xy 43.302138 -132.381502) (xy 43.280874 -132.381502) (xy 43.270932 -132.385308)
			(xy 43.228269 -132.403551) (xy 43.139977 -132.432095) (xy 43.049192 -132.451289) (xy 42.956902 -132.460923)
			(xy 42.910506 -132.461508) (xy 42.868157 -132.46102) (xy 42.783841 -132.45297) (xy 42.700673 -132.436941)
			(xy 42.619405 -132.413079) (xy 42.540773 -132.3816) (xy 42.465489 -132.342789) (xy 42.394236 -132.296998)
			(xy 42.327658 -132.24464) (xy 42.266358 -132.186192) (xy 42.210892 -132.122181) (xy 42.161762 -132.053187)
			(xy 42.119412 -131.979836) (xy 42.084227 -131.902791) (xy 42.056525 -131.822751) (xy 42.036556 -131.74044)
			(xy 42.024502 -131.656603) (xy 42.020472 -131.572) (xy 0.514454 -131.572) (xy 0.509506 -131.660112)
			(xy 0.509016 -131.729988) (xy 0.509016 -132.959856) (xy 213.088728 -132.959856) (xy 213.089328 -132.913461)
			(xy 213.098967 -132.821173) (xy 213.118158 -132.730389) (xy 213.146692 -132.642095) (xy 213.164928 -132.59943)
			(xy 213.168758 -132.589495) (xy 213.168741 -132.568225) (xy 213.164928 -132.558282) (xy 213.146671 -132.515625)
			(xy 213.11813 -132.427331) (xy 213.09894 -132.336544) (xy 213.089311 -132.244253) (xy 213.088728 -132.197856)
			(xy 213.089328 -132.151461) (xy 213.098967 -132.059173) (xy 213.118158 -131.968389) (xy 213.146692 -131.880095)
			(xy 213.164928 -131.83743) (xy 213.168758 -131.827495) (xy 213.168741 -131.806225) (xy 213.164928 -131.796282)
			(xy 213.146671 -131.753625) (xy 213.11813 -131.665331) (xy 213.09894 -131.574544) (xy 213.089311 -131.482253)
			(xy 213.088728 -131.435856) (xy 213.089328 -131.389461) (xy 213.098967 -131.297173) (xy 213.118158 -131.206389)
			(xy 213.146692 -131.118095) (xy 213.164928 -131.07543) (xy 213.168758 -131.065495) (xy 213.168741 -131.044225)
			(xy 213.164928 -131.034282) (xy 213.146671 -130.991625) (xy 213.11813 -130.903331) (xy 213.09894 -130.812544)
			(xy 213.089311 -130.720253) (xy 213.088728 -130.673856) (xy 213.089328 -130.627461) (xy 213.098967 -130.535173)
			(xy 213.118158 -130.444389) (xy 213.146692 -130.356095) (xy 213.164928 -130.31343) (xy 213.168758 -130.303495)
			(xy 213.168741 -130.282225) (xy 213.164928 -130.272282) (xy 213.146671 -130.229625) (xy 213.11813 -130.141331)
			(xy 213.09894 -130.050544) (xy 213.089311 -129.958253) (xy 213.088728 -129.911856) (xy 213.089328 -129.865461)
			(xy 213.098967 -129.773173) (xy 213.118158 -129.682389) (xy 213.146692 -129.594095) (xy 213.164928 -129.55143)
			(xy 213.168758 -129.541495) (xy 213.168741 -129.520225) (xy 213.164928 -129.510282) (xy 213.146671 -129.467625)
			(xy 213.11813 -129.379331) (xy 213.09894 -129.288544) (xy 213.089311 -129.196253) (xy 213.088728 -129.149856)
			(xy 213.089328 -129.103461) (xy 213.098967 -129.011173) (xy 213.118158 -128.920389) (xy 213.146692 -128.832095)
			(xy 213.164928 -128.78943) (xy 213.168758 -128.779495) (xy 213.168741 -128.758225) (xy 213.164928 -128.748282)
			(xy 213.146671 -128.705625) (xy 213.11813 -128.617331) (xy 213.09894 -128.526544) (xy 213.089311 -128.434253)
			(xy 213.088728 -128.387856) (xy 213.089328 -128.341461) (xy 213.098967 -128.249173) (xy 213.118158 -128.158389)
			(xy 213.146692 -128.070095) (xy 213.164928 -128.02743) (xy 213.168758 -128.017495) (xy 213.168741 -127.996225)
			(xy 213.164928 -127.986282) (xy 213.146671 -127.943625) (xy 213.11813 -127.855331) (xy 213.09894 -127.764544)
			(xy 213.089311 -127.672253) (xy 213.088728 -127.625856) (xy 213.089125 -127.584752) (xy 213.096714 -127.502894)
			(xy 213.111824 -127.422086) (xy 213.134325 -127.343017) (xy 213.164026 -127.266361) (xy 213.200673 -127.192773)
			(xy 213.243953 -127.12288) (xy 213.293498 -127.057278) (xy 213.348884 -126.996528) (xy 213.40964 -126.941147)
			(xy 213.475246 -126.891608) (xy 213.545143 -126.848334) (xy 213.618734 -126.811693) (xy 213.695393 -126.781999)
			(xy 213.774464 -126.759505) (xy 213.855273 -126.744403) (xy 213.937132 -126.736821) (xy 213.978236 -126.736348)
			(xy 214.019707 -126.736821) (xy 214.102292 -126.744496) (xy 214.183804 -126.759823) (xy 214.263536 -126.782669)
			(xy 214.30234 -126.797308) (xy 214.311828 -126.800522) (xy 214.331839 -126.800112) (xy 214.341202 -126.796546)
			(xy 214.383373 -126.778847) (xy 214.47054 -126.751148) (xy 214.560087 -126.732532) (xy 214.651071 -126.723195)
			(xy 214.696802 -126.722632) (xy 214.743198 -126.723211) (xy 214.835486 -126.732857) (xy 214.92627 -126.752054)
			(xy 215.014563 -126.780593) (xy 215.057228 -126.798832) (xy 215.06717 -126.802638) (xy 215.088434 -126.802638)
			(xy 215.098376 -126.798832) (xy 215.141039 -126.780589) (xy 215.229331 -126.752044) (xy 215.320116 -126.73285)
			(xy 215.412406 -126.723217) (xy 215.458802 -126.722632) (xy 215.502226 -126.723118) (xy 215.588665 -126.731536)
			(xy 215.673869 -126.748349) (xy 215.757026 -126.773398) (xy 215.797384 -126.789434) (xy 215.806818 -126.792777)
			(xy 215.826812 -126.792777) (xy 215.836246 -126.789434) (xy 215.87661 -126.77342) (xy 215.959771 -126.748397)
			(xy 216.044973 -126.731586) (xy 216.131406 -126.723147) (xy 216.174828 -126.722632) (xy 216.221223 -126.723237)
			(xy 216.313511 -126.732875) (xy 216.404295 -126.752064) (xy 216.492589 -126.780597) (xy 216.535254 -126.798832)
			(xy 216.545196 -126.802638) (xy 216.56646 -126.802638) (xy 216.576402 -126.798832) (xy 216.619061 -126.78058)
			(xy 216.707355 -126.752038) (xy 216.798141 -126.732846) (xy 216.890432 -126.723215) (xy 216.936828 -126.722632)
			(xy 216.977933 -126.723025) (xy 217.059791 -126.730613) (xy 217.140601 -126.745722) (xy 217.219671 -126.768223)
			(xy 217.296329 -126.797923) (xy 217.369918 -126.834569) (xy 217.439813 -126.87785) (xy 217.505416 -126.927394)
			(xy 217.566167 -126.982781) (xy 217.621549 -127.043537) (xy 217.671089 -127.109143) (xy 217.714364 -127.179041)
			(xy 217.751005 -127.252634) (xy 217.780699 -127.329293) (xy 217.803193 -127.408365) (xy 217.818296 -127.489176)
			(xy 217.825878 -127.571035) (xy 217.826336 -127.61214) (xy 217.82573 -127.658535) (xy 217.816091 -127.750823)
			(xy 217.796902 -127.841606) (xy 217.76837 -127.929901) (xy 217.750136 -127.972566) (xy 217.746305 -127.982501)
			(xy 217.746321 -128.003772) (xy 217.750136 -128.013714) (xy 217.768396 -128.05637) (xy 217.796935 -128.144665)
			(xy 217.816124 -128.235452) (xy 217.825753 -128.327743) (xy 217.826336 -128.37414) (xy 217.82573 -128.420535)
			(xy 217.816091 -128.512823) (xy 217.796902 -128.603606) (xy 217.76837 -128.691901) (xy 217.750136 -128.734566)
			(xy 217.746305 -128.744501) (xy 217.746321 -128.765772) (xy 217.750136 -128.775714) (xy 217.768396 -128.81837)
			(xy 217.796935 -128.906665) (xy 217.816124 -128.997452) (xy 217.825753 -129.089743) (xy 217.826336 -129.13614)
			(xy 217.82573 -129.182535) (xy 217.816091 -129.274823) (xy 217.796902 -129.365606) (xy 217.76837 -129.453901)
			(xy 217.750136 -129.496566) (xy 217.746305 -129.506501) (xy 217.746321 -129.527772) (xy 217.750136 -129.537714)
			(xy 217.768396 -129.58037) (xy 217.796935 -129.668665) (xy 217.816124 -129.759452) (xy 217.825753 -129.851743)
			(xy 217.826336 -129.89814) (xy 217.82573 -129.944535) (xy 217.816091 -130.036823) (xy 217.796902 -130.127606)
			(xy 217.76837 -130.215901) (xy 217.750136 -130.258566) (xy 217.746305 -130.268501) (xy 217.746321 -130.289772)
			(xy 217.750136 -130.299714) (xy 217.768396 -130.34237) (xy 217.796935 -130.430665) (xy 217.816124 -130.521452)
			(xy 217.825753 -130.613743) (xy 217.826336 -130.66014) (xy 217.82573 -130.706535) (xy 217.816091 -130.798823)
			(xy 217.796902 -130.889606) (xy 217.76837 -130.977901) (xy 217.750136 -131.020566) (xy 217.746305 -131.030501)
			(xy 217.746321 -131.051772) (xy 217.750136 -131.061714) (xy 217.768396 -131.10437) (xy 217.770454 -131.110736)
			(xy 230.701596 -131.110736) (xy 230.702191 -131.064341) (xy 230.711833 -130.972053) (xy 230.731025 -130.881269)
			(xy 230.75956 -130.792975) (xy 230.777796 -130.75031) (xy 230.78158 -130.740361) (xy 230.781594 -130.719104)
			(xy 230.777796 -130.709162) (xy 230.759563 -130.666495) (xy 230.731016 -130.578204) (xy 230.71182 -130.487421)
			(xy 230.702183 -130.395132) (xy 230.701596 -130.348736) (xy 230.702191 -130.302341) (xy 230.711833 -130.210053)
			(xy 230.731025 -130.119269) (xy 230.75956 -130.030975) (xy 230.777796 -129.98831) (xy 230.78158 -129.978361)
			(xy 230.781594 -129.957104) (xy 230.777796 -129.947162) (xy 230.759563 -129.904495) (xy 230.731016 -129.816204)
			(xy 230.71182 -129.725421) (xy 230.702183 -129.633132) (xy 230.701596 -129.586736) (xy 230.702191 -129.540341)
			(xy 230.711833 -129.448053) (xy 230.731025 -129.357269) (xy 230.75956 -129.268975) (xy 230.777796 -129.22631)
			(xy 230.78158 -129.216361) (xy 230.781594 -129.195104) (xy 230.777796 -129.185162) (xy 230.759563 -129.142495)
			(xy 230.731016 -129.054204) (xy 230.71182 -128.963421) (xy 230.702183 -128.871132) (xy 230.701596 -128.824736)
			(xy 230.702191 -128.778341) (xy 230.711833 -128.686053) (xy 230.731025 -128.595269) (xy 230.75956 -128.506975)
			(xy 230.777796 -128.46431) (xy 230.78158 -128.454361) (xy 230.781594 -128.433104) (xy 230.777796 -128.423162)
			(xy 230.759563 -128.380495) (xy 230.731016 -128.292204) (xy 230.71182 -128.201421) (xy 230.702183 -128.109132)
			(xy 230.701596 -128.062736) (xy 230.702191 -128.016341) (xy 230.711833 -127.924053) (xy 230.731025 -127.833269)
			(xy 230.75956 -127.744975) (xy 230.777796 -127.70231) (xy 230.78158 -127.692361) (xy 230.781594 -127.671104)
			(xy 230.777796 -127.661162) (xy 230.759563 -127.618495) (xy 230.731016 -127.530204) (xy 230.71182 -127.439421)
			(xy 230.702183 -127.347132) (xy 230.701596 -127.300736) (xy 230.702147 -127.256691) (xy 230.710849 -127.169033)
			(xy 230.72817 -127.082663) (xy 230.753941 -126.998427) (xy 230.77043 -126.957582) (xy 230.773801 -126.948582)
			(xy 230.774177 -126.92938) (xy 230.771192 -126.920244) (xy 230.757686 -126.882861) (xy 230.736583 -126.806223)
			(xy 230.722406 -126.728008) (xy 230.715266 -126.648839) (xy 230.714804 -126.609094) (xy 230.715307 -126.567981)
			(xy 230.722894 -126.486105) (xy 230.738004 -126.405278) (xy 230.760506 -126.326191) (xy 230.790209 -126.249516)
			(xy 230.82686 -126.17591) (xy 230.870147 -126.105999) (xy 230.919698 -126.04038) (xy 230.975093 -125.979613)
			(xy 231.035859 -125.924216) (xy 231.101476 -125.874662) (xy 231.171385 -125.831374) (xy 231.244991 -125.794721)
			(xy 231.321664 -125.765015) (xy 231.400751 -125.74251) (xy 231.481577 -125.727398) (xy 231.563453 -125.719808)
			(xy 231.604566 -125.719332) (xy 231.650969 -125.719939) (xy 231.743266 -125.729636) (xy 231.834052 -125.748895)
			(xy 231.922336 -125.777508) (xy 231.964992 -125.795786) (xy 231.974934 -125.799592) (xy 231.996198 -125.799592)
			(xy 232.00614 -125.795786) (xy 232.048804 -125.777532) (xy 232.137091 -125.748938) (xy 232.227873 -125.729678)
			(xy 232.320165 -125.719963) (xy 232.366566 -125.719332) (xy 232.409139 -125.719856) (xy 232.493893 -125.728015)
			(xy 232.577478 -125.744243) (xy 232.659128 -125.768389) (xy 232.698798 -125.783848) (xy 232.70805 -125.787101)
			(xy 232.727646 -125.787101) (xy 232.736898 -125.783848) (xy 232.776567 -125.768388) (xy 232.858222 -125.74426)
			(xy 232.941806 -125.728033) (xy 233.026558 -125.719855) (xy 233.06913 -125.719332) (xy 233.115532 -125.719952)
			(xy 233.20783 -125.729645) (xy 233.298615 -125.7489) (xy 233.3869 -125.77751) (xy 233.429556 -125.795786)
			(xy 233.439498 -125.799592) (xy 233.460762 -125.799592) (xy 233.470704 -125.795786) (xy 233.51336 -125.777511)
			(xy 233.60165 -125.748922) (xy 233.692434 -125.729668) (xy 233.784729 -125.719959) (xy 233.83113 -125.719332)
			(xy 233.877532 -125.719952) (xy 233.96983 -125.729645) (xy 234.060615 -125.7489) (xy 234.1489 -125.77751)
			(xy 234.191556 -125.795786) (xy 234.201498 -125.799592) (xy 234.222762 -125.799592) (xy 234.232704 -125.795786)
			(xy 234.27536 -125.777511) (xy 234.36365 -125.748922) (xy 234.454434 -125.729668) (xy 234.546729 -125.719959)
			(xy 234.59313 -125.719332) (xy 234.634245 -125.719784) (xy 234.716123 -125.727374) (xy 234.796951 -125.742486)
			(xy 234.876041 -125.764991) (xy 234.952716 -125.794697) (xy 235.026324 -125.831352) (xy 235.067746 -125.857)
			(xy 268.350492 -125.857) (xy 268.351075 -125.810604) (xy 268.36072 -125.718316) (xy 268.379916 -125.627532)
			(xy 268.408454 -125.539239) (xy 268.426692 -125.496574) (xy 268.430498 -125.486632) (xy 268.430498 -125.465368)
			(xy 268.426692 -125.455426) (xy 268.408447 -125.412764) (xy 268.379903 -125.324471) (xy 268.36071 -125.233686)
			(xy 268.351077 -125.141396) (xy 268.350492 -125.095) (xy 268.351075 -125.048604) (xy 268.36072 -124.956316)
			(xy 268.379916 -124.865532) (xy 268.408454 -124.777239) (xy 268.426692 -124.734574) (xy 268.430498 -124.724632)
			(xy 268.430498 -124.703368) (xy 268.426692 -124.693426) (xy 268.408447 -124.650764) (xy 268.379903 -124.562471)
			(xy 268.36071 -124.471686) (xy 268.351077 -124.379396) (xy 268.350492 -124.333) (xy 268.351075 -124.286604)
			(xy 268.36072 -124.194316) (xy 268.379916 -124.103532) (xy 268.408454 -124.015239) (xy 268.426692 -123.972574)
			(xy 268.430498 -123.962632) (xy 268.430498 -123.941368) (xy 268.426692 -123.931426) (xy 268.408447 -123.888764)
			(xy 268.379903 -123.800471) (xy 268.36071 -123.709686) (xy 268.351077 -123.617396) (xy 268.350492 -123.571)
			(xy 268.351075 -123.524604) (xy 268.36072 -123.432316) (xy 268.379916 -123.341532) (xy 268.408454 -123.253239)
			(xy 268.426692 -123.210574) (xy 268.430498 -123.200632) (xy 268.430498 -123.179368) (xy 268.426692 -123.169426)
			(xy 268.408447 -123.126764) (xy 268.379903 -123.038471) (xy 268.36071 -122.947686) (xy 268.351077 -122.855396)
			(xy 268.350492 -122.809) (xy 268.351075 -122.762604) (xy 268.36072 -122.670316) (xy 268.379916 -122.579532)
			(xy 268.408454 -122.491239) (xy 268.426692 -122.448574) (xy 268.430498 -122.438632) (xy 268.430498 -122.417368)
			(xy 268.426692 -122.407426) (xy 268.408447 -122.364764) (xy 268.379903 -122.276471) (xy 268.36071 -122.185686)
			(xy 268.351077 -122.093396) (xy 268.350492 -122.047) (xy 268.350967 -122.005898) (xy 268.358552 -121.924043)
			(xy 268.373657 -121.843238) (xy 268.396153 -121.764171) (xy 268.425849 -121.687517) (xy 268.462491 -121.61393)
			(xy 268.505766 -121.544038) (xy 268.555306 -121.478437) (xy 268.610687 -121.417687) (xy 268.671437 -121.362306)
			(xy 268.737038 -121.312766) (xy 268.80693 -121.269491) (xy 268.880517 -121.232849) (xy 268.957171 -121.203153)
			(xy 269.036238 -121.180657) (xy 269.117043 -121.165552) (xy 269.198898 -121.157967) (xy 269.24 -121.157492)
			(xy 269.286396 -121.158075) (xy 269.378684 -121.16772) (xy 269.469468 -121.186916) (xy 269.557761 -121.215454)
			(xy 269.600426 -121.233692) (xy 269.610368 -121.237498) (xy 269.631632 -121.237498) (xy 269.641574 -121.233692)
			(xy 269.684236 -121.215447) (xy 269.772529 -121.186903) (xy 269.863314 -121.16771) (xy 269.955604 -121.158077)
			(xy 270.002 -121.157492) (xy 270.048396 -121.158075) (xy 270.140684 -121.16772) (xy 270.231468 -121.186916)
			(xy 270.319761 -121.215454) (xy 270.362426 -121.233692) (xy 270.372368 -121.237498) (xy 270.393632 -121.237498)
			(xy 270.403574 -121.233692) (xy 270.446236 -121.215447) (xy 270.534529 -121.186903) (xy 270.625314 -121.16771)
			(xy 270.717604 -121.158077) (xy 270.764 -121.157492) (xy 270.810396 -121.158075) (xy 270.902684 -121.16772)
			(xy 270.993468 -121.186916) (xy 271.081761 -121.215454) (xy 271.124426 -121.233692) (xy 271.134368 -121.237498)
			(xy 271.155632 -121.237498) (xy 271.165574 -121.233692) (xy 271.208236 -121.215447) (xy 271.296529 -121.186903)
			(xy 271.387314 -121.16771) (xy 271.479604 -121.158077) (xy 271.526 -121.157492) (xy 271.572396 -121.158075)
			(xy 271.664684 -121.16772) (xy 271.755468 -121.186916) (xy 271.843761 -121.215454) (xy 271.886426 -121.233692)
			(xy 271.896368 -121.237498) (xy 271.917632 -121.237498) (xy 271.927574 -121.233692) (xy 271.970236 -121.215447)
			(xy 272.058529 -121.186903) (xy 272.149314 -121.16771) (xy 272.241604 -121.158077) (xy 272.288 -121.157492)
			(xy 272.329102 -121.157967) (xy 272.410957 -121.165552) (xy 272.491762 -121.180657) (xy 272.570829 -121.203153)
			(xy 272.647483 -121.232849) (xy 272.72107 -121.269491) (xy 272.790962 -121.312766) (xy 272.856563 -121.362306)
			(xy 272.917313 -121.417687) (xy 272.972694 -121.478437) (xy 273.022234 -121.544038) (xy 273.065509 -121.61393)
			(xy 273.102151 -121.687517) (xy 273.131847 -121.764171) (xy 273.154343 -121.843238) (xy 273.169448 -121.924043)
			(xy 273.177033 -122.005898) (xy 273.177508 -122.047) (xy 273.176925 -122.093396) (xy 273.16728 -122.185684)
			(xy 273.148084 -122.276468) (xy 273.119546 -122.364761) (xy 273.101308 -122.407426) (xy 273.097502 -122.417368)
			(xy 273.097502 -122.438632) (xy 273.101308 -122.448574) (xy 273.119553 -122.491236) (xy 273.148097 -122.579529)
			(xy 273.16729 -122.670314) (xy 273.176923 -122.762604) (xy 273.177508 -122.809) (xy 273.177033 -122.850102)
			(xy 273.169448 -122.931957) (xy 273.154343 -123.012762) (xy 273.131847 -123.091829) (xy 273.102151 -123.168483)
			(xy 273.065509 -123.24207) (xy 273.022234 -123.311962) (xy 272.972694 -123.377563) (xy 272.917313 -123.438313)
			(xy 272.856563 -123.493694) (xy 272.790962 -123.543234) (xy 272.72107 -123.586509) (xy 272.647483 -123.623151)
			(xy 272.570829 -123.652847) (xy 272.491762 -123.675343) (xy 272.410957 -123.690448) (xy 272.329102 -123.698033)
			(xy 272.288 -123.698508) (xy 272.241604 -123.697925) (xy 272.149316 -123.68828) (xy 272.058532 -123.669084)
			(xy 271.970239 -123.640546) (xy 271.927574 -123.622308) (xy 271.917632 -123.618502) (xy 271.896368 -123.618502)
			(xy 271.886426 -123.622308) (xy 271.853507 -123.636537) (xy 271.785822 -123.660257) (xy 271.716442 -123.678437)
			(xy 271.681194 -123.685046) (xy 271.67107 -123.687344) (xy 271.653749 -123.698749) (xy 271.642344 -123.71607)
			(xy 271.640046 -123.726194) (xy 271.633416 -123.761437) (xy 271.61522 -123.83081) (xy 271.591513 -123.898498)
			(xy 271.577308 -123.931426) (xy 271.573502 -123.941368) (xy 271.573502 -123.962632) (xy 271.577308 -123.972574)
			(xy 271.591537 -124.005493) (xy 271.615257 -124.073178) (xy 271.633437 -124.142558) (xy 271.640046 -124.177806)
			(xy 271.642344 -124.18793) (xy 271.653749 -124.205251) (xy 271.67107 -124.216656) (xy 271.681194 -124.218954)
			(xy 271.716437 -124.225584) (xy 271.78581 -124.24378) (xy 271.853498 -124.267487) (xy 271.886426 -124.281692)
			(xy 271.896368 -124.285498) (xy 271.917632 -124.285498) (xy 271.927574 -124.281692) (xy 271.970236 -124.263447)
			(xy 272.058529 -124.234903) (xy 272.149314 -124.21571) (xy 272.241604 -124.206077) (xy 272.288 -124.205492)
			(xy 272.329102 -124.205967) (xy 272.410957 -124.213552) (xy 272.491762 -124.228657) (xy 272.570829 -124.251153)
			(xy 272.647483 -124.280849) (xy 272.72107 -124.317491) (xy 272.790962 -124.360766) (xy 272.856563 -124.410306)
			(xy 272.917313 -124.465687) (xy 272.972694 -124.526437) (xy 273.022234 -124.592038) (xy 273.065509 -124.66193)
			(xy 273.102151 -124.735517) (xy 273.131847 -124.812171) (xy 273.154343 -124.891238) (xy 273.169448 -124.972043)
			(xy 273.177033 -125.053898) (xy 273.177508 -125.095) (xy 273.176925 -125.141396) (xy 273.16728 -125.233684)
			(xy 273.148084 -125.324468) (xy 273.119546 -125.412761) (xy 273.101308 -125.455426) (xy 273.097502 -125.465368)
			(xy 273.097502 -125.486632) (xy 273.101308 -125.496574) (xy 273.119553 -125.539236) (xy 273.148097 -125.627529)
			(xy 273.16729 -125.718314) (xy 273.176923 -125.810604) (xy 273.177508 -125.857) (xy 273.177033 -125.898102)
			(xy 273.169448 -125.979957) (xy 273.154343 -126.060762) (xy 273.131847 -126.139829) (xy 273.102151 -126.216483)
			(xy 273.065509 -126.29007) (xy 273.022234 -126.359962) (xy 272.972694 -126.425563) (xy 272.917313 -126.486313)
			(xy 272.856563 -126.541694) (xy 272.790962 -126.591234) (xy 272.72107 -126.634509) (xy 272.647483 -126.671151)
			(xy 272.570829 -126.700847) (xy 272.491762 -126.723343) (xy 272.410957 -126.738448) (xy 272.329102 -126.746033)
			(xy 272.288 -126.746508) (xy 272.241604 -126.745925) (xy 272.149316 -126.73628) (xy 272.058532 -126.717084)
			(xy 271.970239 -126.688546) (xy 271.927574 -126.670308) (xy 271.917632 -126.666502) (xy 271.896368 -126.666502)
			(xy 271.886426 -126.670308) (xy 271.843764 -126.688553) (xy 271.755471 -126.717097) (xy 271.664686 -126.73629)
			(xy 271.572396 -126.745923) (xy 271.526 -126.746508) (xy 271.479604 -126.745925) (xy 271.387316 -126.73628)
			(xy 271.296532 -126.717084) (xy 271.208239 -126.688546) (xy 271.165574 -126.670308) (xy 271.155632 -126.666502)
			(xy 271.134368 -126.666502) (xy 271.124426 -126.670308) (xy 271.081764 -126.688553) (xy 270.993471 -126.717097)
			(xy 270.902686 -126.73629) (xy 270.810396 -126.745923) (xy 270.764 -126.746508) (xy 270.717604 -126.745925)
			(xy 270.625316 -126.73628) (xy 270.534532 -126.717084) (xy 270.446239 -126.688546) (xy 270.403574 -126.670308)
			(xy 270.393632 -126.666502) (xy 270.372368 -126.666502) (xy 270.362426 -126.670308) (xy 270.319764 -126.688553)
			(xy 270.231471 -126.717097) (xy 270.140686 -126.73629) (xy 270.048396 -126.745923) (xy 270.002 -126.746508)
			(xy 269.955604 -126.745925) (xy 269.863316 -126.73628) (xy 269.772532 -126.717084) (xy 269.684239 -126.688546)
			(xy 269.641574 -126.670308) (xy 269.631632 -126.666502) (xy 269.610368 -126.666502) (xy 269.600426 -126.670308)
			(xy 269.557764 -126.688553) (xy 269.469471 -126.717097) (xy 269.378686 -126.73629) (xy 269.286396 -126.745923)
			(xy 269.24 -126.746508) (xy 269.198898 -126.746033) (xy 269.117043 -126.738448) (xy 269.036238 -126.723343)
			(xy 268.957171 -126.700847) (xy 268.880517 -126.671151) (xy 268.80693 -126.634509) (xy 268.737038 -126.591234)
			(xy 268.671437 -126.541694) (xy 268.610687 -126.486313) (xy 268.555306 -126.425563) (xy 268.505766 -126.359962)
			(xy 268.462491 -126.29007) (xy 268.425849 -126.216483) (xy 268.396153 -126.139829) (xy 268.373657 -126.060762)
			(xy 268.358552 -125.979957) (xy 268.350967 -125.898102) (xy 268.350492 -125.857) (xy 235.067746 -125.857)
			(xy 235.096236 -125.874641) (xy 235.161855 -125.924196) (xy 235.222622 -125.979595) (xy 235.278019 -126.040363)
			(xy 235.327572 -126.105984) (xy 235.37086 -126.175897) (xy 235.407512 -126.249506) (xy 235.437217 -126.326182)
			(xy 235.45972 -126.405272) (xy 235.474829 -126.486101) (xy 235.482417 -126.567979) (xy 235.482892 -126.609094)
			(xy 235.482318 -126.653145) (xy 235.473542 -126.740808) (xy 235.456153 -126.827177) (xy 235.430321 -126.911407)
			(xy 235.413804 -126.952248) (xy 235.410474 -126.961259) (xy 235.410073 -126.98045) (xy 235.413042 -126.989586)
			(xy 235.426531 -127.026969) (xy 235.447571 -127.103614) (xy 235.461682 -127.181831) (xy 235.46875 -127.260996)
			(xy 235.469176 -127.300736) (xy 235.468573 -127.347131) (xy 235.458934 -127.439419) (xy 235.439744 -127.530203)
			(xy 235.411211 -127.618497) (xy 235.392976 -127.661162) (xy 235.389151 -127.671098) (xy 235.389165 -127.692367)
			(xy 235.392976 -127.70231) (xy 235.411231 -127.744968) (xy 235.439773 -127.833262) (xy 235.458963 -127.924048)
			(xy 235.468593 -128.01634) (xy 235.469176 -128.062736) (xy 235.468573 -128.109131) (xy 235.458934 -128.201419)
			(xy 235.439744 -128.292203) (xy 235.411211 -128.380497) (xy 235.392976 -128.423162) (xy 235.389151 -128.433098)
			(xy 235.389165 -128.454367) (xy 235.392976 -128.46431) (xy 235.411231 -128.506968) (xy 235.439773 -128.595262)
			(xy 235.458963 -128.686048) (xy 235.468593 -128.77834) (xy 235.469176 -128.824736) (xy 235.468573 -128.871131)
			(xy 235.458934 -128.963419) (xy 235.455402 -128.980127) (xy 270.348706 -128.980127) (xy 270.348706 -128.895405)
			(xy 270.356759 -128.811068) (xy 270.372793 -128.727878) (xy 270.396661 -128.646588) (xy 270.428149 -128.567936)
			(xy 270.466971 -128.492633) (xy 270.512774 -128.421361) (xy 270.565145 -128.354765) (xy 270.62361 -128.29345)
			(xy 270.687638 -128.237969) (xy 270.75665 -128.188826) (xy 270.83002 -128.146466) (xy 270.907085 -128.111271)
			(xy 270.987147 -128.083562) (xy 271.06948 -128.063588) (xy 271.153339 -128.051531) (xy 271.237964 -128.0475)
			(xy 271.322589 -128.051531) (xy 271.406448 -128.063588) (xy 271.488781 -128.083562) (xy 271.568843 -128.111271)
			(xy 271.645908 -128.146466) (xy 271.719278 -128.188826) (xy 271.78829 -128.237969) (xy 271.852318 -128.29345)
			(xy 271.910783 -128.354765) (xy 271.963154 -128.421361) (xy 272.008957 -128.492633) (xy 272.047779 -128.567936)
			(xy 272.079267 -128.646588) (xy 272.103135 -128.727878) (xy 272.119169 -128.811068) (xy 272.127222 -128.895405)
			(xy 272.127726 -128.937766) (xy 272.127222 -128.980127) (xy 272.119169 -129.064464) (xy 272.103135 -129.147654)
			(xy 272.079267 -129.228944) (xy 272.047779 -129.307596) (xy 272.008957 -129.382899) (xy 271.963154 -129.454171)
			(xy 271.910783 -129.520767) (xy 271.852318 -129.582082) (xy 271.78829 -129.637563) (xy 271.719278 -129.686706)
			(xy 271.645908 -129.729066) (xy 271.568843 -129.764261) (xy 271.488781 -129.79197) (xy 271.406448 -129.811944)
			(xy 271.322589 -129.824001) (xy 271.237964 -129.828033) (xy 271.153339 -129.824001) (xy 271.06948 -129.811944)
			(xy 270.987147 -129.79197) (xy 270.907085 -129.764261) (xy 270.83002 -129.729066) (xy 270.75665 -129.686706)
			(xy 270.687638 -129.637563) (xy 270.62361 -129.582082) (xy 270.565145 -129.520767) (xy 270.512774 -129.454171)
			(xy 270.466971 -129.382899) (xy 270.428149 -129.307596) (xy 270.396661 -129.228944) (xy 270.372793 -129.147654)
			(xy 270.356759 -129.064464) (xy 270.348706 -128.980127) (xy 235.455402 -128.980127) (xy 235.439744 -129.054203)
			(xy 235.411211 -129.142497) (xy 235.392976 -129.185162) (xy 235.389151 -129.195098) (xy 235.389165 -129.216367)
			(xy 235.392976 -129.22631) (xy 235.411231 -129.268968) (xy 235.439773 -129.357262) (xy 235.458963 -129.448048)
			(xy 235.468593 -129.54034) (xy 235.469176 -129.586736) (xy 235.468573 -129.633131) (xy 235.458934 -129.725419)
			(xy 235.439744 -129.816203) (xy 235.411211 -129.904497) (xy 235.392976 -129.947162) (xy 235.389151 -129.957098)
			(xy 235.389165 -129.978367) (xy 235.392976 -129.98831) (xy 235.411231 -130.030968) (xy 235.439773 -130.119262)
			(xy 235.458963 -130.210048) (xy 235.468593 -130.30234) (xy 235.469176 -130.348736) (xy 235.468573 -130.395131)
			(xy 235.458934 -130.487419) (xy 235.449335 -130.532829) (xy 268.757142 -130.532829) (xy 268.757142 -130.448107)
			(xy 268.765195 -130.36377) (xy 268.781229 -130.28058) (xy 268.805097 -130.19929) (xy 268.836585 -130.120638)
			(xy 268.875407 -130.045335) (xy 268.92121 -129.974063) (xy 268.973581 -129.907467) (xy 269.032046 -129.846152)
			(xy 269.096074 -129.790671) (xy 269.165086 -129.741528) (xy 269.238456 -129.699168) (xy 269.315521 -129.663973)
			(xy 269.395583 -129.636264) (xy 269.477916 -129.61629) (xy 269.561775 -129.604233) (xy 269.6464 -129.600202)
			(xy 269.731025 -129.604233) (xy 269.814884 -129.61629) (xy 269.897217 -129.636264) (xy 269.977279 -129.663973)
			(xy 270.054344 -129.699168) (xy 270.127714 -129.741528) (xy 270.196726 -129.790671) (xy 270.260754 -129.846152)
			(xy 270.319219 -129.907467) (xy 270.37159 -129.974063) (xy 270.417393 -130.045335) (xy 270.456215 -130.120638)
			(xy 270.487703 -130.19929) (xy 270.511571 -130.28058) (xy 270.527605 -130.36377) (xy 270.535658 -130.448107)
			(xy 270.536162 -130.490468) (xy 270.535658 -130.532829) (xy 270.527605 -130.617166) (xy 270.511571 -130.700356)
			(xy 270.487703 -130.781646) (xy 270.456215 -130.860298) (xy 270.417393 -130.935601) (xy 270.37159 -131.006873)
			(xy 270.319219 -131.073469) (xy 270.260754 -131.134784) (xy 270.196726 -131.190265) (xy 270.127714 -131.239408)
			(xy 270.054344 -131.281768) (xy 269.977279 -131.316963) (xy 269.897217 -131.344672) (xy 269.814884 -131.364646)
			(xy 269.731025 -131.376703) (xy 269.6464 -131.380735) (xy 269.561775 -131.376703) (xy 269.477916 -131.364646)
			(xy 269.395583 -131.344672) (xy 269.315521 -131.316963) (xy 269.238456 -131.281768) (xy 269.165086 -131.239408)
			(xy 269.096074 -131.190265) (xy 269.032046 -131.134784) (xy 268.973581 -131.073469) (xy 268.92121 -131.006873)
			(xy 268.875407 -130.935601) (xy 268.836585 -130.860298) (xy 268.805097 -130.781646) (xy 268.781229 -130.700356)
			(xy 268.765195 -130.617166) (xy 268.757142 -130.532829) (xy 235.449335 -130.532829) (xy 235.439744 -130.578203)
			(xy 235.411211 -130.666497) (xy 235.392976 -130.709162) (xy 235.389151 -130.719098) (xy 235.389165 -130.740367)
			(xy 235.392976 -130.75031) (xy 235.411231 -130.792968) (xy 235.439773 -130.881262) (xy 235.458963 -130.972048)
			(xy 235.468593 -131.06434) (xy 235.469176 -131.110736) (xy 235.4687 -131.152245) (xy 235.460981 -131.234903)
			(xy 235.445588 -131.316482) (xy 235.422653 -131.396269) (xy 235.407962 -131.435094) (xy 235.404787 -131.444591)
			(xy 235.405179 -131.464591) (xy 235.408724 -131.473956) (xy 235.42646 -131.51612) (xy 235.451388 -131.594352)
			(xy 277.69185 -131.594352) (xy 277.69185 -52.12715) (xy 277.692343 -52.093889) (xy 277.701036 -52.027937)
			(xy 277.718266 -51.963685) (xy 277.743739 -51.902233) (xy 277.777018 -51.844633) (xy 277.817533 -51.791872)
			(xy 277.840694 -51.767994) (xy 281.072844 -48.535844) (xy 281.096729 -48.512692) (xy 281.149489 -48.472179)
			(xy 281.207088 -48.438903) (xy 281.268539 -48.413434) (xy 281.33279 -48.396209) (xy 281.39874 -48.387521)
			(xy 281.432 -48.387) (xy 281.432254 -48.387) (xy 281.465814 -48.387539) (xy 281.532347 -48.396394)
			(xy 281.597132 -48.413941) (xy 281.659039 -48.439875) (xy 281.688286 -48.456342) (xy 281.694148 -48.459525)
			(xy 281.707019 -48.463004) (xy 281.713686 -48.4632) (xy 295.775634 -48.4632) (xy 295.785644 -48.46274)
			(xy 295.804136 -48.455069) (xy 295.818288 -48.440908) (xy 295.825947 -48.42241) (xy 295.826434 -48.4124)
			(xy 295.826434 -47.710598) (xy 295.826902 -47.694875) (xy 295.834601 -47.664385) (xy 295.849508 -47.636695)
			(xy 295.870721 -47.613481) (xy 295.883584 -47.604426) (xy 295.892982 -47.59833) (xy 295.904666 -47.579788)
			(xy 295.91762 -47.48149) (xy 295.91127 -47.460662) (xy 295.903904 -47.45228) (xy 295.877568 -47.421825)
			(xy 295.829911 -47.356921) (xy 295.788317 -47.287975) (xy 295.753126 -47.215551) (xy 295.724627 -47.140242)
			(xy 295.703053 -47.062664) (xy 295.688581 -46.983455) (xy 295.681328 -46.903261) (xy 295.680892 -46.863)
			(xy 295.681389 -46.820692) (xy 295.689392 -46.736456) (xy 295.705353 -46.65336) (xy 295.72913 -46.572154)
			(xy 295.760506 -46.493571) (xy 295.799199 -46.418321) (xy 295.821608 -46.382432) (xy 295.826488 -46.374042)
			(xy 295.830156 -46.355) (xy 295.826488 -46.335958) (xy 295.821608 -46.327568) (xy 295.799176 -46.291691)
			(xy 295.760465 -46.216446) (xy 295.729079 -46.137863) (xy 295.705303 -46.056653) (xy 295.68935 -45.973551)
			(xy 295.681366 -45.88931) (xy 295.680892 -45.847) (xy 295.681417 -45.801657) (xy 295.690578 -45.711437)
			(xy 295.69918 -45.666914) (xy 295.701974 -45.653706) (xy 295.693846 -45.628306) (xy 295.61028 -45.55109)
			(xy 295.584626 -45.544994) (xy 295.571672 -45.54855) (xy 295.531633 -45.559591) (xy 295.450025 -45.575055)
			(xy 295.36733 -45.582845) (xy 295.3258 -45.583348) (xy 295.275639 -45.58264) (xy 295.175958 -45.571313)
			(xy 295.126918 -45.560742) (xy 295.116758 -45.558456) (xy 295.096438 -45.562012) (xy 295.017952 -45.612812)
			(xy 295.006522 -45.62983) (xy 295.00449 -45.639736) (xy 294.995423 -45.682457) (xy 294.970051 -45.766028)
			(xy 294.936612 -45.84671) (xy 294.895425 -45.923726) (xy 294.846889 -45.996335) (xy 294.79147 -46.063838)
			(xy 294.729702 -46.125584) (xy 294.66218 -46.180979) (xy 294.589554 -46.229489) (xy 294.512523 -46.270648)
			(xy 294.431829 -46.304058) (xy 294.348248 -46.3294) (xy 294.262587 -46.346427) (xy 294.175669 -46.354977)
			(xy 294.132 -46.355508) (xy 294.090898 -46.355033) (xy 294.009043 -46.347448) (xy 293.928238 -46.332343)
			(xy 293.849171 -46.309847) (xy 293.772517 -46.280151) (xy 293.69893 -46.243509) (xy 293.629038 -46.200234)
			(xy 293.563437 -46.150694) (xy 293.502687 -46.095313) (xy 293.447306 -46.034563) (xy 293.397766 -45.968962)
			(xy 293.354491 -45.89907) (xy 293.317849 -45.825483) (xy 293.288153 -45.748829) (xy 293.265657 -45.669762)
			(xy 293.250552 -45.588957) (xy 293.242967 -45.507102) (xy 293.242492 -45.466) (xy 293.242987 -45.423046)
			(xy 293.251252 -45.337536) (xy 293.267725 -45.253222) (xy 293.292251 -45.170889) (xy 293.324602 -45.091305)
			(xy 293.364476 -45.015211) (xy 293.411503 -44.943317) (xy 293.465243 -44.876293) (xy 293.525197 -44.814764)
			(xy 293.590803 -44.759303) (xy 293.661453 -44.710426) (xy 293.736486 -44.668591) (xy 293.775638 -44.650914)
			(xy 293.783674 -44.646948) (xy 293.796551 -44.634501) (xy 293.804365 -44.618386) (xy 293.80561 -44.609512)
			(xy 293.810549 -44.566203) (xy 293.827823 -44.48076) (xy 293.853371 -44.397415) (xy 293.886947 -44.316968)
			(xy 293.928229 -44.240191) (xy 293.976821 -44.167818) (xy 294.032259 -44.100545) (xy 294.094009 -44.039015)
			(xy 294.161481 -43.98382) (xy 294.234027 -43.935487) (xy 294.310952 -43.89448) (xy 294.391519 -43.861193)
			(xy 294.474954 -43.835944) (xy 294.560459 -43.818976) (xy 294.647214 -43.810451) (xy 294.6908 -43.80992)
			(xy 294.72807 -43.810301) (xy 294.802353 -43.816489) (xy 294.875858 -43.828865) (xy 294.948072 -43.84734)
			(xy 294.983408 -43.859196) (xy 294.991804 -43.861751) (xy 295.009341 -43.861622) (xy 295.017698 -43.858942)
			(xy 295.054748 -43.845723) (xy 295.130664 -43.825091) (xy 295.208104 -43.811237) (xy 295.286465 -43.80427)
			(xy 295.3258 -43.803824) (xy 295.366912 -43.804252) (xy 295.448784 -43.811841) (xy 295.529606 -43.826952)
			(xy 295.608689 -43.849458) (xy 295.685358 -43.879166) (xy 295.758958 -43.915823) (xy 295.82886 -43.959116)
			(xy 295.894469 -44.008675) (xy 295.955224 -44.064078) (xy 296.010607 -44.124851) (xy 296.060146 -44.190476)
			(xy 296.103416 -44.260392) (xy 296.140049 -44.334004) (xy 296.169733 -44.410682) (xy 296.192213 -44.489772)
			(xy 296.207299 -44.5706) (xy 296.214861 -44.652474) (xy 296.215308 -44.693586) (xy 296.214781 -44.738929)
			(xy 296.205621 -44.829149) (xy 296.19702 -44.873672) (xy 296.194226 -44.88688) (xy 296.202354 -44.91228)
			(xy 296.28592 -44.989496) (xy 296.311574 -44.995592) (xy 296.324528 -44.992036) (xy 296.364572 -44.981036)
			(xy 296.446183 -44.965647) (xy 296.528875 -44.957947) (xy 296.5704 -44.957492) (xy 296.611502 -44.957967)
			(xy 296.693357 -44.965552) (xy 296.774162 -44.980657) (xy 296.853229 -45.003153) (xy 296.929883 -45.032849)
			(xy 297.00347 -45.069491) (xy 297.073362 -45.112766) (xy 297.138963 -45.162306) (xy 297.199713 -45.217687)
			(xy 297.255094 -45.278437) (xy 297.304634 -45.344038) (xy 297.347909 -45.41393) (xy 297.384551 -45.487517)
			(xy 297.414247 -45.564171) (xy 297.436743 -45.643238) (xy 297.451848 -45.724043) (xy 297.459433 -45.805898)
			(xy 297.459908 -45.847) (xy 297.459411 -45.889308) (xy 297.451408 -45.973544) (xy 297.435447 -46.05664)
			(xy 297.41167 -46.137846) (xy 297.380294 -46.216429) (xy 297.341601 -46.291679) (xy 297.319192 -46.327568)
			(xy 297.314312 -46.335958) (xy 297.310644 -46.355) (xy 297.314312 -46.374042) (xy 297.319192 -46.382432)
			(xy 297.341624 -46.418309) (xy 297.380335 -46.493554) (xy 297.411721 -46.572137) (xy 297.421175 -46.604428)
			(xy 297.75277 -46.604428) (xy 297.75277 -38.218364) (xy 297.753266 -38.185103) (xy 297.761957 -38.119151)
			(xy 297.779187 -38.054899) (xy 297.804659 -37.993446) (xy 297.837938 -37.935847) (xy 297.878453 -37.883086)
			(xy 297.901614 -37.859208) (xy 298.15155 -37.609272) (xy 298.17542 -37.586104) (xy 298.228185 -37.545595)
			(xy 298.285787 -37.512323) (xy 298.347241 -37.486857) (xy 298.411494 -37.469634) (xy 298.477445 -37.460949)
			(xy 298.510706 -37.460428) (xy 302.50257 -37.460428) (xy 302.535829 -37.460978) (xy 302.601778 -37.469661)
			(xy 302.666029 -37.48688) (xy 302.727481 -37.512342) (xy 302.785082 -37.545611) (xy 302.837846 -37.586116)
			(xy 302.861726 -37.609272) (xy 303.217326 -37.964872) (xy 303.240504 -37.988733) (xy 303.281012 -38.041499)
			(xy 303.314283 -38.099104) (xy 303.339747 -38.160559) (xy 303.356968 -38.224814) (xy 303.365651 -38.290767)
			(xy 303.36617 -38.324028) (xy 303.36617 -44.390144) (xy 307.777633 -44.390144) (xy 307.777633 -44.219788)
			(xy 307.785618 -44.04962) (xy 307.80157 -43.880013) (xy 307.825455 -43.711341) (xy 307.857219 -43.543973)
			(xy 307.896794 -43.378278) (xy 307.944091 -43.21462) (xy 307.999008 -43.053359) (xy 308.061423 -42.894849)
			(xy 308.131199 -42.739439) (xy 308.208182 -42.587471) (xy 308.292204 -42.439277) (xy 308.38308 -42.295185)
			(xy 308.48061 -42.155511) (xy 308.58458 -42.020562) (xy 308.694761 -41.890634) (xy 308.81091 -41.766014)
			(xy 308.932774 -41.646975) (xy 309.060082 -41.533779) (xy 309.192557 -41.426674) (xy 309.329907 -41.325897)
			(xy 309.471829 -41.231668) (xy 309.618011 -41.144195) (xy 309.768134 -41.06367) (xy 309.921865 -40.99027)
			(xy 310.078868 -40.924156) (xy 310.238798 -40.865474) (xy 310.401302 -40.814353) (xy 310.566023 -40.770905)
			(xy 310.732601 -40.735226) (xy 310.900667 -40.707394) (xy 311.069853 -40.68747) (xy 311.239787 -40.675498)
			(xy 311.410096 -40.671505) (xy 311.580405 -40.675498) (xy 311.750339 -40.68747) (xy 311.919525 -40.707394)
			(xy 312.087591 -40.735226) (xy 312.254169 -40.770905) (xy 312.41889 -40.814353) (xy 312.581394 -40.865474)
			(xy 312.741324 -40.924156) (xy 312.898327 -40.99027) (xy 313.052058 -41.06367) (xy 313.202181 -41.144195)
			(xy 313.348363 -41.231668) (xy 313.490285 -41.325897) (xy 313.627635 -41.426674) (xy 313.76011 -41.533779)
			(xy 313.887418 -41.646975) (xy 314.009282 -41.766014) (xy 314.125431 -41.890634) (xy 314.235612 -42.020562)
			(xy 314.339582 -42.155511) (xy 314.437112 -42.295185) (xy 314.527988 -42.439277) (xy 314.61201 -42.587471)
			(xy 314.688993 -42.739439) (xy 314.758769 -42.894849) (xy 314.821184 -43.053359) (xy 314.876101 -43.21462)
			(xy 314.923398 -43.378278) (xy 314.962973 -43.543973) (xy 314.994737 -43.711341) (xy 315.018622 -43.880013)
			(xy 315.034574 -44.04962) (xy 315.042559 -44.219788) (xy 315.043058 -44.304966) (xy 315.042559 -44.390144)
			(xy 315.034574 -44.560312) (xy 315.018622 -44.729919) (xy 314.994737 -44.898591) (xy 314.962973 -45.065959)
			(xy 314.923398 -45.231654) (xy 314.876101 -45.395312) (xy 314.821184 -45.556573) (xy 314.758769 -45.715083)
			(xy 314.688993 -45.870493) (xy 314.61201 -46.022461) (xy 314.527988 -46.170655) (xy 314.437112 -46.314747)
			(xy 314.339582 -46.454421) (xy 314.235612 -46.58937) (xy 314.125431 -46.719298) (xy 314.009282 -46.843918)
			(xy 313.887418 -46.962957) (xy 313.76011 -47.076153) (xy 313.627635 -47.183258) (xy 313.490285 -47.284035)
			(xy 313.348363 -47.378264) (xy 313.202181 -47.465737) (xy 313.052058 -47.546262) (xy 312.898327 -47.619662)
			(xy 312.741324 -47.685776) (xy 312.581394 -47.744458) (xy 312.41889 -47.795579) (xy 312.254169 -47.839027)
			(xy 312.087591 -47.874706) (xy 311.919525 -47.902538) (xy 311.750339 -47.922462) (xy 311.580405 -47.934434)
			(xy 311.410096 -47.938428) (xy 311.239787 -47.934434) (xy 311.069853 -47.922462) (xy 310.900667 -47.902538)
			(xy 310.732601 -47.874706) (xy 310.566023 -47.839027) (xy 310.401302 -47.795579) (xy 310.238798 -47.744458)
			(xy 310.078868 -47.685776) (xy 309.921865 -47.619662) (xy 309.768134 -47.546262) (xy 309.618011 -47.465737)
			(xy 309.471829 -47.378264) (xy 309.329907 -47.284035) (xy 309.192557 -47.183258) (xy 309.060082 -47.076153)
			(xy 308.932774 -46.962957) (xy 308.81091 -46.843918) (xy 308.694761 -46.719298) (xy 308.58458 -46.58937)
			(xy 308.48061 -46.454421) (xy 308.38308 -46.314747) (xy 308.292204 -46.170655) (xy 308.208182 -46.022461)
			(xy 308.131199 -45.870493) (xy 308.061423 -45.715083) (xy 307.999008 -45.556573) (xy 307.944091 -45.395312)
			(xy 307.896794 -45.231654) (xy 307.857219 -45.065959) (xy 307.825455 -44.898591) (xy 307.80157 -44.729919)
			(xy 307.785618 -44.560312) (xy 307.777633 -44.390144) (xy 303.36617 -44.390144) (xy 303.36617 -46.579028)
			(xy 303.365657 -46.612288) (xy 303.356968 -46.678239) (xy 303.339741 -46.742491) (xy 303.314272 -46.803943)
			(xy 303.280996 -46.861543) (xy 303.240485 -46.914305) (xy 303.217326 -46.938184) (xy 302.810926 -47.344584)
			(xy 302.787059 -47.367755) (xy 302.734295 -47.408265) (xy 302.676692 -47.441538) (xy 302.615237 -47.467003)
			(xy 302.550984 -47.484225) (xy 302.485031 -47.492909) (xy 302.45177 -47.493428) (xy 298.64177 -47.493428)
			(xy 298.608509 -47.492929) (xy 298.542557 -47.484238) (xy 298.478305 -47.467009) (xy 298.416853 -47.441538)
			(xy 298.359253 -47.40826) (xy 298.306492 -47.367744) (xy 298.282614 -47.344584) (xy 297.901614 -46.963584)
			(xy 297.87847 -46.939691) (xy 297.837957 -46.886933) (xy 297.804681 -46.829335) (xy 297.779211 -46.767886)
			(xy 297.761983 -46.703636) (xy 297.753293 -46.637687) (xy 297.75277 -46.604428) (xy 297.421175 -46.604428)
			(xy 297.435497 -46.653347) (xy 297.45145 -46.736449) (xy 297.459434 -46.82069) (xy 297.459908 -46.863)
			(xy 297.459446 -46.903899) (xy 297.451939 -46.985353) (xy 297.436989 -47.065774) (xy 297.414721 -47.144483)
			(xy 297.385324 -47.220817) (xy 297.349046 -47.29413) (xy 297.306193 -47.363806) (xy 297.257126 -47.429254)
			(xy 297.230038 -47.4599) (xy 297.222926 -47.467774) (xy 297.216068 -47.488094) (xy 297.225212 -47.584106)
			(xy 297.235626 -47.602648) (xy 297.244262 -47.609252) (xy 297.255779 -47.618387) (xy 297.274571 -47.640984)
			(xy 297.287678 -47.667291) (xy 297.294399 -47.695902) (xy 297.294808 -47.710598) (xy 297.294808 -48.4124)
			(xy 297.29522 -48.422422) (xy 297.302891 -48.440941) (xy 297.317066 -48.455113) (xy 297.335586 -48.462782)
			(xy 297.345608 -48.4632) (xy 298.831 -48.4632) (xy 298.864259 -48.463739) (xy 298.930209 -48.472425)
			(xy 298.99446 -48.489647) (xy 299.055911 -48.515111) (xy 299.113512 -48.548382) (xy 299.166276 -48.588888)
			(xy 299.190156 -48.612044) (xy 306.810156 -56.232044) (xy 306.833308 -56.255929) (xy 306.873821 -56.308689)
			(xy 306.907097 -56.366288) (xy 306.932566 -56.427739) (xy 306.949791 -56.49199) (xy 306.958479 -56.55794)
			(xy 306.959 -56.5912) (xy 306.959 -72.879966) (xy 310.009801 -72.879966) (xy 310.013811 -72.774063)
			(xy 310.025819 -72.668767) (xy 310.045756 -72.564681) (xy 310.073508 -72.462401) (xy 310.108916 -72.362512)
			(xy 310.151777 -72.265588) (xy 310.201845 -72.172182) (xy 310.258835 -72.082831) (xy 310.322418 -71.998045)
			(xy 310.392232 -71.918311) (xy 310.467876 -71.844086) (xy 310.548916 -71.775793) (xy 310.63489 -71.713826)
			(xy 310.725304 -71.658538) (xy 310.81964 -71.610246) (xy 310.917359 -71.569227) (xy 311.017899 -71.535716)
			(xy 311.120687 -71.509904) (xy 311.225131 -71.49194) (xy 311.330636 -71.481927) (xy 311.436595 -71.479921)
			(xy 311.542403 -71.485935) (xy 311.647453 -71.499934) (xy 311.751143 -71.521837) (xy 311.85288 -71.55152)
			(xy 311.952081 -71.588811) (xy 312.048177 -71.633499) (xy 312.140618 -71.685326) (xy 312.228875 -71.743996)
			(xy 312.312442 -71.809173) (xy 312.390841 -71.880483) (xy 312.463622 -71.957517) (xy 312.530368 -72.039836)
			(xy 312.590698 -72.126967) (xy 312.644265 -72.218411) (xy 312.690763 -72.313644) (xy 312.729925 -72.412121)
			(xy 312.761528 -72.513278) (xy 312.785389 -72.616536) (xy 312.801374 -72.721302) (xy 312.809389 -72.826977)
			(xy 312.80989 -72.879966) (xy 312.809389 -72.932955) (xy 312.801374 -73.03863) (xy 312.785389 -73.143396)
			(xy 312.761528 -73.246654) (xy 312.729925 -73.347811) (xy 312.690763 -73.446288) (xy 312.644265 -73.541521)
			(xy 312.590698 -73.632965) (xy 312.530368 -73.720096) (xy 312.463622 -73.802415) (xy 312.390841 -73.879449)
			(xy 312.312442 -73.950759) (xy 312.228875 -74.015936) (xy 312.140618 -74.074606) (xy 312.048177 -74.126433)
			(xy 311.952081 -74.171121) (xy 311.85288 -74.208412) (xy 311.751143 -74.238095) (xy 311.647453 -74.259998)
			(xy 311.542403 -74.273997) (xy 311.436595 -74.280011) (xy 311.330636 -74.278005) (xy 311.225131 -74.267992)
			(xy 311.120687 -74.250028) (xy 311.017899 -74.224216) (xy 310.917359 -74.190705) (xy 310.81964 -74.149686)
			(xy 310.725304 -74.101394) (xy 310.63489 -74.046106) (xy 310.548916 -73.984139) (xy 310.467876 -73.915846)
			(xy 310.392232 -73.841621) (xy 310.322418 -73.761887) (xy 310.258835 -73.677101) (xy 310.201845 -73.58775)
			(xy 310.151777 -73.494344) (xy 310.108916 -73.39742) (xy 310.073508 -73.297531) (xy 310.045756 -73.195251)
			(xy 310.025819 -73.091165) (xy 310.013811 -72.985869) (xy 310.009801 -72.879966) (xy 306.959 -72.879966)
			(xy 306.959 -73.377806) (xy 306.959396 -73.387879) (xy 306.967134 -73.406478) (xy 306.973986 -73.413874)
			(xy 308.856126 -75.296014) (xy 308.863521 -75.30286) (xy 308.882124 -75.310576) (xy 308.892194 -75.311)
			(xy 319.8876 -75.311) (xy 319.920859 -75.311539) (xy 319.986809 -75.320225) (xy 320.05106 -75.337447)
			(xy 320.112511 -75.362911) (xy 320.170112 -75.396182) (xy 320.222876 -75.436688) (xy 320.246756 -75.459844)
			(xy 321.288156 -76.501244) (xy 321.311308 -76.525129) (xy 321.351821 -76.577889) (xy 321.385097 -76.635488)
			(xy 321.410566 -76.696939) (xy 321.427791 -76.76119) (xy 321.436479 -76.82714) (xy 321.437 -76.8604)
			(xy 321.437 -120.904) (xy 321.436461 -120.937259) (xy 321.427775 -121.003209) (xy 321.410553 -121.06746)
			(xy 321.385089 -121.128911) (xy 321.351818 -121.186512) (xy 321.311312 -121.239276) (xy 321.288156 -121.263156)
			(xy 319.992756 -122.558556) (xy 319.968871 -122.581708) (xy 319.916111 -122.622221) (xy 319.858512 -122.655497)
			(xy 319.797061 -122.680966) (xy 319.73281 -122.698191) (xy 319.66686 -122.706879) (xy 319.6336 -122.7074)
			(xy 304.015394 -122.7074) (xy 304.005321 -122.707796) (xy 303.986722 -122.715534) (xy 303.979326 -122.722386)
			(xy 300.28642 -126.415292) (xy 300.279594 -126.422703) (xy 300.271865 -126.441294) (xy 300.271434 -126.45136)
			(xy 300.271434 -131.730496) (xy 300.270911 -131.763756) (xy 300.262225 -131.829707) (xy 300.245001 -131.893959)
			(xy 300.219534 -131.955411) (xy 300.18626 -132.013011) (xy 300.145749 -132.065773) (xy 300.12259 -132.089652)
			(xy 298.892722 -133.31952) (xy 298.868863 -133.3427) (xy 298.816096 -133.383208) (xy 298.758492 -133.416478)
			(xy 298.697036 -133.441942) (xy 298.632781 -133.459163) (xy 298.566827 -133.467845) (xy 298.533566 -133.468364)
			(xy 279.565862 -133.468364) (xy 279.532601 -133.46786) (xy 279.46665 -133.459168) (xy 279.402398 -133.44194)
			(xy 279.340946 -133.416469) (xy 279.283346 -133.383193) (xy 279.230585 -133.342679) (xy 279.206706 -133.31952)
			(xy 277.840694 -131.953508) (xy 277.81751 -131.929653) (xy 277.777002 -131.876886) (xy 277.743731 -131.81928)
			(xy 277.718269 -131.757823) (xy 277.701049 -131.693568) (xy 277.692368 -131.627614) (xy 277.69185 -131.594352)
			(xy 235.451388 -131.594352) (xy 235.454232 -131.603278) (xy 235.472912 -131.692826) (xy 235.482304 -131.783818)
			(xy 235.482892 -131.829556) (xy 235.482406 -131.870659) (xy 235.474825 -131.952514) (xy 235.459723 -132.033321)
			(xy 235.437229 -132.11239) (xy 235.407535 -132.189045) (xy 235.370895 -132.262634) (xy 235.327621 -132.332528)
			(xy 235.278083 -132.39813) (xy 235.222702 -132.458882) (xy 235.161952 -132.514265) (xy 235.096351 -132.563805)
			(xy 235.026458 -132.607082) (xy 234.952871 -132.643724) (xy 234.876216 -132.67342) (xy 234.797148 -132.695916)
			(xy 234.716342 -132.711021) (xy 234.634487 -132.718605) (xy 234.593384 -132.719064) (xy 234.546988 -132.718491)
			(xy 234.454699 -132.708843) (xy 234.363916 -132.689645) (xy 234.275622 -132.661103) (xy 234.232958 -132.642864)
			(xy 234.223016 -132.639058) (xy 234.201752 -132.639058) (xy 234.19181 -132.642864) (xy 234.149149 -132.661111)
			(xy 234.060856 -132.689655) (xy 233.970071 -132.708848) (xy 233.87778 -132.71848) (xy 233.831384 -132.719064)
			(xy 233.784988 -132.718491) (xy 233.692699 -132.708843) (xy 233.601916 -132.689645) (xy 233.513622 -132.661103)
			(xy 233.470958 -132.642864) (xy 233.461016 -132.639058) (xy 233.439752 -132.639058) (xy 233.42981 -132.642864)
			(xy 233.387149 -132.661111) (xy 233.298856 -132.689655) (xy 233.208071 -132.708848) (xy 233.11578 -132.71848)
			(xy 233.069384 -132.719064) (xy 233.026817 -132.718594) (xy 232.942069 -132.710485) (xy 232.858485 -132.694314)
			(xy 232.776829 -132.670229) (xy 232.737152 -132.654802) (xy 232.7279 -132.651549) (xy 232.708304 -132.651549)
			(xy 232.699052 -132.654802) (xy 232.65938 -132.670239) (xy 232.57772 -132.694311) (xy 232.494134 -132.710474)
			(xy 232.409387 -132.718579) (xy 232.36682 -132.719064) (xy 232.320424 -132.718478) (xy 232.228136 -132.708834)
			(xy 232.137352 -132.689639) (xy 232.049059 -132.661102) (xy 232.006394 -132.642864) (xy 231.996452 -132.639058)
			(xy 231.975188 -132.639058) (xy 231.965246 -132.642864) (xy 231.92258 -132.661099) (xy 231.834289 -132.689647)
			(xy 231.743505 -132.708842) (xy 231.651216 -132.718478) (xy 231.60482 -132.719064) (xy 231.563716 -132.718629)
			(xy 231.481858 -132.711045) (xy 231.401049 -132.69594) (xy 231.321979 -132.673444) (xy 231.245322 -132.643747)
			(xy 231.171732 -132.607104) (xy 231.101838 -132.563827) (xy 231.036234 -132.514285) (xy 230.975482 -132.458901)
			(xy 230.9201 -132.398147) (xy 230.87056 -132.332543) (xy 230.827284 -132.262647) (xy 230.790643 -132.189056)
			(xy 230.760949 -132.112398) (xy 230.738454 -132.033327) (xy 230.723352 -131.952518) (xy 230.71577 -131.87066)
			(xy 230.715312 -131.829556) (xy 230.715787 -131.788047) (xy 230.723505 -131.705388) (xy 230.7389 -131.62381)
			(xy 230.761835 -131.544023) (xy 230.776526 -131.505198) (xy 230.779706 -131.495702) (xy 230.779312 -131.475701)
			(xy 230.775764 -131.466336) (xy 230.758025 -131.424174) (xy 230.730254 -131.337015) (xy 230.711574 -131.247467)
			(xy 230.702183 -131.156474) (xy 230.701596 -131.110736) (xy 217.770454 -131.110736) (xy 217.796935 -131.192665)
			(xy 217.816124 -131.283452) (xy 217.825753 -131.375743) (xy 217.826336 -131.42214) (xy 217.82573 -131.468535)
			(xy 217.816091 -131.560823) (xy 217.796902 -131.651606) (xy 217.76837 -131.739901) (xy 217.750136 -131.782566)
			(xy 217.746305 -131.792501) (xy 217.746321 -131.813772) (xy 217.750136 -131.823714) (xy 217.768396 -131.86637)
			(xy 217.796935 -131.954665) (xy 217.816124 -132.045452) (xy 217.825753 -132.137743) (xy 217.826336 -132.18414)
			(xy 217.82573 -132.230535) (xy 217.816091 -132.322823) (xy 217.796902 -132.413606) (xy 217.76837 -132.501901)
			(xy 217.750136 -132.544566) (xy 217.746305 -132.554501) (xy 217.746321 -132.575772) (xy 217.750136 -132.585714)
			(xy 217.768396 -132.62837) (xy 217.796935 -132.716665) (xy 217.816124 -132.807452) (xy 217.825753 -132.899743)
			(xy 217.826336 -132.94614) (xy 217.825872 -132.987242) (xy 217.818283 -133.069096) (xy 217.803175 -133.1499)
			(xy 217.780677 -133.228966) (xy 217.750979 -133.305619) (xy 217.714335 -133.379205) (xy 217.671059 -133.449096)
			(xy 217.621519 -133.514696) (xy 217.566137 -133.575446) (xy 217.505387 -133.630826) (xy 217.439786 -133.680366)
			(xy 217.369894 -133.723641) (xy 217.296308 -133.760284) (xy 217.219655 -133.78998) (xy 217.140589 -133.812478)
			(xy 217.059784 -133.827585) (xy 216.97793 -133.835172) (xy 216.936828 -133.835648) (xy 216.890433 -133.83506)
			(xy 216.798144 -133.825417) (xy 216.70736 -133.806223) (xy 216.619067 -133.777686) (xy 216.576402 -133.759448)
			(xy 216.56646 -133.755642) (xy 216.545196 -133.755642) (xy 216.535254 -133.759448) (xy 216.492589 -133.777686)
			(xy 216.404298 -133.806231) (xy 216.313513 -133.825426) (xy 216.221224 -133.835062) (xy 216.174828 -133.835648)
			(xy 216.131404 -133.835154) (xy 216.044966 -133.826739) (xy 215.959761 -133.809928) (xy 215.876604 -133.784881)
			(xy 215.836246 -133.768846) (xy 215.826836 -133.765374) (xy 215.806794 -133.765374) (xy 215.797384 -133.768846)
			(xy 215.757016 -133.78485) (xy 215.673856 -133.809876) (xy 215.588656 -133.826689) (xy 215.502224 -133.835131)
			(xy 215.458802 -133.835648) (xy 215.412406 -133.835069) (xy 215.320118 -133.825424) (xy 215.229334 -133.806227)
			(xy 215.141041 -133.777687) (xy 215.098376 -133.759448) (xy 215.088434 -133.755642) (xy 215.06717 -133.755642)
			(xy 215.057228 -133.759448) (xy 215.014567 -133.777695) (xy 214.926274 -133.806238) (xy 214.835489 -133.82543)
			(xy 214.743198 -133.835063) (xy 214.696802 -133.835648) (xy 214.655331 -133.835195) (xy 214.572745 -133.827514)
			(xy 214.491233 -133.812181) (xy 214.411501 -133.78933) (xy 214.372698 -133.774688) (xy 214.363204 -133.771495)
			(xy 214.343199 -133.771892) (xy 214.333836 -133.77545) (xy 214.291673 -133.793169) (xy 214.204503 -133.820863)
			(xy 214.114954 -133.839474) (xy 214.023968 -133.848804) (xy 213.978236 -133.849364) (xy 213.937132 -133.848913)
			(xy 213.855275 -133.841331) (xy 213.774466 -133.826228) (xy 213.695396 -133.803733) (xy 213.618739 -133.774037)
			(xy 213.54515 -133.737395) (xy 213.475255 -133.694119) (xy 213.409651 -133.644578) (xy 213.348899 -133.589195)
			(xy 213.293517 -133.528442) (xy 213.243976 -133.462839) (xy 213.200701 -133.392943) (xy 213.164059 -133.319353)
			(xy 213.134365 -133.242696) (xy 213.11187 -133.163626) (xy 213.096768 -133.082817) (xy 213.089186 -133.00096)
			(xy 213.088728 -132.959856) (xy 0.509016 -132.959856) (xy 0.509016 -136.959232) (xy 40.624242 -136.959232)
			(xy 40.624242 -136.852768) (xy 40.632198 -136.746601) (xy 40.648065 -136.641325) (xy 40.671756 -136.53753)
			(xy 40.703137 -136.435795) (xy 40.742033 -136.33669) (xy 40.788226 -136.240768) (xy 40.841459 -136.148567)
			(xy 40.901432 -136.060602) (xy 40.967812 -135.977365) (xy 41.040226 -135.89932) (xy 41.118271 -135.826906)
			(xy 41.201508 -135.760526) (xy 41.289473 -135.700553) (xy 41.381674 -135.64732) (xy 41.477596 -135.601127)
			(xy 41.576701 -135.562231) (xy 41.678436 -135.53085) (xy 41.782231 -135.507159) (xy 41.887507 -135.491292)
			(xy 41.993674 -135.483336) (xy 42.100138 -135.483336) (xy 42.206305 -135.491292) (xy 42.311581 -135.507159)
			(xy 42.415376 -135.53085) (xy 42.517111 -135.562231) (xy 42.616216 -135.601127) (xy 42.712138 -135.64732)
			(xy 42.804339 -135.700553) (xy 42.892304 -135.760526) (xy 42.975541 -135.826906) (xy 43.053586 -135.89932)
			(xy 43.126 -135.977365) (xy 43.19238 -136.060602) (xy 43.252353 -136.148567) (xy 43.305586 -136.240768)
			(xy 43.351779 -136.33669) (xy 43.390675 -136.435795) (xy 43.422056 -136.53753) (xy 43.445747 -136.641325)
			(xy 43.461614 -136.746601) (xy 43.46957 -136.852768) (xy 43.470068 -136.906) (xy 43.46957 -136.959232)
			(xy 52.816242 -136.959232) (xy 52.816242 -136.852768) (xy 52.824198 -136.746601) (xy 52.840065 -136.641325)
			(xy 52.863756 -136.53753) (xy 52.895137 -136.435795) (xy 52.934033 -136.33669) (xy 52.980226 -136.240768)
			(xy 53.033459 -136.148567) (xy 53.093432 -136.060602) (xy 53.159812 -135.977365) (xy 53.232226 -135.89932)
			(xy 53.310271 -135.826906) (xy 53.393508 -135.760526) (xy 53.481473 -135.700553) (xy 53.573674 -135.64732)
			(xy 53.669596 -135.601127) (xy 53.768701 -135.562231) (xy 53.870436 -135.53085) (xy 53.974231 -135.507159)
			(xy 54.079507 -135.491292) (xy 54.185674 -135.483336) (xy 54.292138 -135.483336) (xy 54.398305 -135.491292)
			(xy 54.503581 -135.507159) (xy 54.607376 -135.53085) (xy 54.709111 -135.562231) (xy 54.808216 -135.601127)
			(xy 54.904138 -135.64732) (xy 54.996339 -135.700553) (xy 55.084304 -135.760526) (xy 55.167541 -135.826906)
			(xy 55.245586 -135.89932) (xy 55.318 -135.977365) (xy 55.38438 -136.060602) (xy 55.444353 -136.148567)
			(xy 55.497586 -136.240768) (xy 55.543779 -136.33669) (xy 55.582675 -136.435795) (xy 55.614056 -136.53753)
			(xy 55.637747 -136.641325) (xy 55.653614 -136.746601) (xy 55.66157 -136.852768) (xy 55.662068 -136.906)
			(xy 55.66157 -136.959232) (xy 65.008242 -136.959232) (xy 65.008242 -136.852768) (xy 65.016198 -136.746601)
			(xy 65.032065 -136.641325) (xy 65.055756 -136.53753) (xy 65.087137 -136.435795) (xy 65.126033 -136.33669)
			(xy 65.172226 -136.240768) (xy 65.225459 -136.148567) (xy 65.285432 -136.060602) (xy 65.351812 -135.977365)
			(xy 65.424226 -135.89932) (xy 65.502271 -135.826906) (xy 65.585508 -135.760526) (xy 65.673473 -135.700553)
			(xy 65.765674 -135.64732) (xy 65.861596 -135.601127) (xy 65.960701 -135.562231) (xy 66.062436 -135.53085)
			(xy 66.166231 -135.507159) (xy 66.271507 -135.491292) (xy 66.377674 -135.483336) (xy 66.484138 -135.483336)
			(xy 66.590305 -135.491292) (xy 66.695581 -135.507159) (xy 66.799376 -135.53085) (xy 66.901111 -135.562231)
			(xy 67.000216 -135.601127) (xy 67.096138 -135.64732) (xy 67.188339 -135.700553) (xy 67.276304 -135.760526)
			(xy 67.359541 -135.826906) (xy 67.437586 -135.89932) (xy 67.51 -135.977365) (xy 67.57638 -136.060602)
			(xy 67.636353 -136.148567) (xy 67.689586 -136.240768) (xy 67.735779 -136.33669) (xy 67.774675 -136.435795)
			(xy 67.806056 -136.53753) (xy 67.829747 -136.641325) (xy 67.845614 -136.746601) (xy 67.85357 -136.852768)
			(xy 67.854068 -136.906) (xy 67.85357 -136.959232) (xy 80.624162 -136.959232) (xy 80.624162 -136.852768)
			(xy 80.632118 -136.746601) (xy 80.647985 -136.641325) (xy 80.671676 -136.53753) (xy 80.703057 -136.435795)
			(xy 80.741953 -136.33669) (xy 80.788146 -136.240768) (xy 80.841379 -136.148567) (xy 80.901352 -136.060602)
			(xy 80.967732 -135.977365) (xy 81.040146 -135.89932) (xy 81.118191 -135.826906) (xy 81.201428 -135.760526)
			(xy 81.289393 -135.700553) (xy 81.381594 -135.64732) (xy 81.477516 -135.601127) (xy 81.576621 -135.562231)
			(xy 81.678356 -135.53085) (xy 81.782151 -135.507159) (xy 81.887427 -135.491292) (xy 81.993594 -135.483336)
			(xy 82.100058 -135.483336) (xy 82.206225 -135.491292) (xy 82.311501 -135.507159) (xy 82.415296 -135.53085)
			(xy 82.517031 -135.562231) (xy 82.616136 -135.601127) (xy 82.712058 -135.64732) (xy 82.804259 -135.700553)
			(xy 82.892224 -135.760526) (xy 82.975461 -135.826906) (xy 83.053506 -135.89932) (xy 83.12592 -135.977365)
			(xy 83.1923 -136.060602) (xy 83.252273 -136.148567) (xy 83.305506 -136.240768) (xy 83.351699 -136.33669)
			(xy 83.390595 -136.435795) (xy 83.421976 -136.53753) (xy 83.445667 -136.641325) (xy 83.461534 -136.746601)
			(xy 83.46949 -136.852768) (xy 83.469988 -136.906) (xy 83.46949 -136.959232) (xy 92.816162 -136.959232)
			(xy 92.816162 -136.852768) (xy 92.824118 -136.746601) (xy 92.839985 -136.641325) (xy 92.863676 -136.53753)
			(xy 92.895057 -136.435795) (xy 92.933953 -136.33669) (xy 92.980146 -136.240768) (xy 93.033379 -136.148567)
			(xy 93.093352 -136.060602) (xy 93.159732 -135.977365) (xy 93.232146 -135.89932) (xy 93.310191 -135.826906)
			(xy 93.393428 -135.760526) (xy 93.481393 -135.700553) (xy 93.573594 -135.64732) (xy 93.669516 -135.601127)
			(xy 93.768621 -135.562231) (xy 93.870356 -135.53085) (xy 93.974151 -135.507159) (xy 94.079427 -135.491292)
			(xy 94.185594 -135.483336) (xy 94.292058 -135.483336) (xy 94.398225 -135.491292) (xy 94.503501 -135.507159)
			(xy 94.607296 -135.53085) (xy 94.709031 -135.562231) (xy 94.808136 -135.601127) (xy 94.904058 -135.64732)
			(xy 94.996259 -135.700553) (xy 95.084224 -135.760526) (xy 95.167461 -135.826906) (xy 95.245506 -135.89932)
			(xy 95.31792 -135.977365) (xy 95.3843 -136.060602) (xy 95.444273 -136.148567) (xy 95.497506 -136.240768)
			(xy 95.543699 -136.33669) (xy 95.582595 -136.435795) (xy 95.613976 -136.53753) (xy 95.637667 -136.641325)
			(xy 95.653534 -136.746601) (xy 95.66149 -136.852768) (xy 95.661988 -136.906) (xy 95.66149 -136.959232)
			(xy 105.008162 -136.959232) (xy 105.008162 -136.852768) (xy 105.016118 -136.746601) (xy 105.031985 -136.641325)
			(xy 105.055676 -136.53753) (xy 105.087057 -136.435795) (xy 105.125953 -136.33669) (xy 105.172146 -136.240768)
			(xy 105.225379 -136.148567) (xy 105.285352 -136.060602) (xy 105.351732 -135.977365) (xy 105.424146 -135.89932)
			(xy 105.502191 -135.826906) (xy 105.585428 -135.760526) (xy 105.673393 -135.700553) (xy 105.765594 -135.64732)
			(xy 105.861516 -135.601127) (xy 105.960621 -135.562231) (xy 106.062356 -135.53085) (xy 106.166151 -135.507159)
			(xy 106.271427 -135.491292) (xy 106.377594 -135.483336) (xy 106.484058 -135.483336) (xy 106.590225 -135.491292)
			(xy 106.695501 -135.507159) (xy 106.799296 -135.53085) (xy 106.901031 -135.562231) (xy 107.000136 -135.601127)
			(xy 107.096058 -135.64732) (xy 107.188259 -135.700553) (xy 107.276224 -135.760526) (xy 107.359461 -135.826906)
			(xy 107.437506 -135.89932) (xy 107.50992 -135.977365) (xy 107.5763 -136.060602) (xy 107.636273 -136.148567)
			(xy 107.689506 -136.240768) (xy 107.735699 -136.33669) (xy 107.774595 -136.435795) (xy 107.805976 -136.53753)
			(xy 107.829667 -136.641325) (xy 107.845534 -136.746601) (xy 107.85349 -136.852768) (xy 107.853988 -136.906)
			(xy 107.85349 -136.959232) (xy 120.624336 -136.959232) (xy 120.624336 -136.852768) (xy 120.632292 -136.746601)
			(xy 120.648159 -136.641325) (xy 120.67185 -136.53753) (xy 120.703231 -136.435795) (xy 120.742127 -136.33669)
			(xy 120.78832 -136.240768) (xy 120.841553 -136.148567) (xy 120.901526 -136.060602) (xy 120.967906 -135.977365)
			(xy 121.04032 -135.89932) (xy 121.118365 -135.826906) (xy 121.201602 -135.760526) (xy 121.289567 -135.700553)
			(xy 121.381768 -135.64732) (xy 121.47769 -135.601127) (xy 121.576795 -135.562231) (xy 121.67853 -135.53085)
			(xy 121.782325 -135.507159) (xy 121.887601 -135.491292) (xy 121.993768 -135.483336) (xy 122.100232 -135.483336)
			(xy 122.206399 -135.491292) (xy 122.311675 -135.507159) (xy 122.41547 -135.53085) (xy 122.517205 -135.562231)
			(xy 122.61631 -135.601127) (xy 122.712232 -135.64732) (xy 122.804433 -135.700553) (xy 122.892398 -135.760526)
			(xy 122.975635 -135.826906) (xy 123.05368 -135.89932) (xy 123.126094 -135.977365) (xy 123.192474 -136.060602)
			(xy 123.252447 -136.148567) (xy 123.30568 -136.240768) (xy 123.351873 -136.33669) (xy 123.390769 -136.435795)
			(xy 123.42215 -136.53753) (xy 123.445841 -136.641325) (xy 123.461708 -136.746601) (xy 123.469664 -136.852768)
			(xy 123.470162 -136.906) (xy 123.469664 -136.959232) (xy 132.816336 -136.959232) (xy 132.816336 -136.852768)
			(xy 132.824292 -136.746601) (xy 132.840159 -136.641325) (xy 132.86385 -136.53753) (xy 132.895231 -136.435795)
			(xy 132.934127 -136.33669) (xy 132.98032 -136.240768) (xy 133.033553 -136.148567) (xy 133.093526 -136.060602)
			(xy 133.159906 -135.977365) (xy 133.23232 -135.89932) (xy 133.310365 -135.826906) (xy 133.393602 -135.760526)
			(xy 133.481567 -135.700553) (xy 133.573768 -135.64732) (xy 133.66969 -135.601127) (xy 133.768795 -135.562231)
			(xy 133.87053 -135.53085) (xy 133.974325 -135.507159) (xy 134.079601 -135.491292) (xy 134.185768 -135.483336)
			(xy 134.292232 -135.483336) (xy 134.398399 -135.491292) (xy 134.503675 -135.507159) (xy 134.60747 -135.53085)
			(xy 134.709205 -135.562231) (xy 134.80831 -135.601127) (xy 134.904232 -135.64732) (xy 134.996433 -135.700553)
			(xy 135.084398 -135.760526) (xy 135.167635 -135.826906) (xy 135.24568 -135.89932) (xy 135.318094 -135.977365)
			(xy 135.384474 -136.060602) (xy 135.444447 -136.148567) (xy 135.49768 -136.240768) (xy 135.543873 -136.33669)
			(xy 135.582769 -136.435795) (xy 135.61415 -136.53753) (xy 135.637841 -136.641325) (xy 135.653708 -136.746601)
			(xy 135.661664 -136.852768) (xy 135.662162 -136.906) (xy 135.661664 -136.959232) (xy 145.008336 -136.959232)
			(xy 145.008336 -136.852768) (xy 145.016292 -136.746601) (xy 145.032159 -136.641325) (xy 145.05585 -136.53753)
			(xy 145.087231 -136.435795) (xy 145.126127 -136.33669) (xy 145.17232 -136.240768) (xy 145.225553 -136.148567)
			(xy 145.285526 -136.060602) (xy 145.351906 -135.977365) (xy 145.42432 -135.89932) (xy 145.502365 -135.826906)
			(xy 145.585602 -135.760526) (xy 145.673567 -135.700553) (xy 145.765768 -135.64732) (xy 145.86169 -135.601127)
			(xy 145.960795 -135.562231) (xy 146.06253 -135.53085) (xy 146.166325 -135.507159) (xy 146.271601 -135.491292)
			(xy 146.377768 -135.483336) (xy 146.484232 -135.483336) (xy 146.590399 -135.491292) (xy 146.695675 -135.507159)
			(xy 146.79947 -135.53085) (xy 146.901205 -135.562231) (xy 147.00031 -135.601127) (xy 147.096232 -135.64732)
			(xy 147.188433 -135.700553) (xy 147.276398 -135.760526) (xy 147.359635 -135.826906) (xy 147.43768 -135.89932)
			(xy 147.510094 -135.977365) (xy 147.576474 -136.060602) (xy 147.636447 -136.148567) (xy 147.68968 -136.240768)
			(xy 147.735873 -136.33669) (xy 147.774769 -136.435795) (xy 147.80615 -136.53753) (xy 147.829841 -136.641325)
			(xy 147.845708 -136.746601) (xy 147.853664 -136.852768) (xy 147.854162 -136.906) (xy 147.853664 -136.959232)
			(xy 160.62451 -136.959232) (xy 160.62451 -136.852768) (xy 160.632466 -136.746601) (xy 160.648333 -136.641325)
			(xy 160.672024 -136.53753) (xy 160.703405 -136.435795) (xy 160.742301 -136.33669) (xy 160.788494 -136.240768)
			(xy 160.841727 -136.148567) (xy 160.9017 -136.060602) (xy 160.96808 -135.977365) (xy 161.040494 -135.89932)
			(xy 161.118539 -135.826906) (xy 161.201776 -135.760526) (xy 161.289741 -135.700553) (xy 161.381942 -135.64732)
			(xy 161.477864 -135.601127) (xy 161.576969 -135.562231) (xy 161.678704 -135.53085) (xy 161.782499 -135.507159)
			(xy 161.887775 -135.491292) (xy 161.993942 -135.483336) (xy 162.100406 -135.483336) (xy 162.206573 -135.491292)
			(xy 162.311849 -135.507159) (xy 162.415644 -135.53085) (xy 162.517379 -135.562231) (xy 162.616484 -135.601127)
			(xy 162.712406 -135.64732) (xy 162.804607 -135.700553) (xy 162.892572 -135.760526) (xy 162.975809 -135.826906)
			(xy 163.053854 -135.89932) (xy 163.126268 -135.977365) (xy 163.192648 -136.060602) (xy 163.252621 -136.148567)
			(xy 163.305854 -136.240768) (xy 163.352047 -136.33669) (xy 163.390943 -136.435795) (xy 163.422324 -136.53753)
			(xy 163.446015 -136.641325) (xy 163.461882 -136.746601) (xy 163.469838 -136.852768) (xy 163.470336 -136.906)
			(xy 163.469838 -136.959232) (xy 172.81651 -136.959232) (xy 172.81651 -136.852768) (xy 172.824466 -136.746601)
			(xy 172.840333 -136.641325) (xy 172.864024 -136.53753) (xy 172.895405 -136.435795) (xy 172.934301 -136.33669)
			(xy 172.980494 -136.240768) (xy 173.033727 -136.148567) (xy 173.0937 -136.060602) (xy 173.16008 -135.977365)
			(xy 173.232494 -135.89932) (xy 173.310539 -135.826906) (xy 173.393776 -135.760526) (xy 173.481741 -135.700553)
			(xy 173.573942 -135.64732) (xy 173.669864 -135.601127) (xy 173.768969 -135.562231) (xy 173.870704 -135.53085)
			(xy 173.974499 -135.507159) (xy 174.079775 -135.491292) (xy 174.185942 -135.483336) (xy 174.292406 -135.483336)
			(xy 174.398573 -135.491292) (xy 174.503849 -135.507159) (xy 174.607644 -135.53085) (xy 174.709379 -135.562231)
			(xy 174.808484 -135.601127) (xy 174.904406 -135.64732) (xy 174.996607 -135.700553) (xy 175.084572 -135.760526)
			(xy 175.167809 -135.826906) (xy 175.245854 -135.89932) (xy 175.318268 -135.977365) (xy 175.384648 -136.060602)
			(xy 175.444621 -136.148567) (xy 175.497854 -136.240768) (xy 175.544047 -136.33669) (xy 175.582943 -136.435795)
			(xy 175.614324 -136.53753) (xy 175.638015 -136.641325) (xy 175.653882 -136.746601) (xy 175.661838 -136.852768)
			(xy 175.662336 -136.906) (xy 175.661838 -136.959232) (xy 185.00851 -136.959232) (xy 185.00851 -136.852768)
			(xy 185.016466 -136.746601) (xy 185.032333 -136.641325) (xy 185.056024 -136.53753) (xy 185.087405 -136.435795)
			(xy 185.126301 -136.33669) (xy 185.172494 -136.240768) (xy 185.225727 -136.148567) (xy 185.2857 -136.060602)
			(xy 185.35208 -135.977365) (xy 185.424494 -135.89932) (xy 185.502539 -135.826906) (xy 185.585776 -135.760526)
			(xy 185.673741 -135.700553) (xy 185.765942 -135.64732) (xy 185.861864 -135.601127) (xy 185.960969 -135.562231)
			(xy 186.062704 -135.53085) (xy 186.166499 -135.507159) (xy 186.271775 -135.491292) (xy 186.377942 -135.483336)
			(xy 186.484406 -135.483336) (xy 186.590573 -135.491292) (xy 186.695849 -135.507159) (xy 186.799644 -135.53085)
			(xy 186.901379 -135.562231) (xy 187.000484 -135.601127) (xy 187.096406 -135.64732) (xy 187.188607 -135.700553)
			(xy 187.276572 -135.760526) (xy 187.359809 -135.826906) (xy 187.437854 -135.89932) (xy 187.510268 -135.977365)
			(xy 187.576648 -136.060602) (xy 187.636621 -136.148567) (xy 187.689854 -136.240768) (xy 187.736047 -136.33669)
			(xy 187.774943 -136.435795) (xy 187.806324 -136.53753) (xy 187.830015 -136.641325) (xy 187.845882 -136.746601)
			(xy 187.853838 -136.852768) (xy 187.854336 -136.906) (xy 187.853838 -136.959232) (xy 187.845882 -137.065399)
			(xy 187.830015 -137.170675) (xy 187.806324 -137.27447) (xy 187.774943 -137.376205) (xy 187.736047 -137.47531)
			(xy 187.689854 -137.571232) (xy 187.636621 -137.663433) (xy 187.576648 -137.751398) (xy 187.510268 -137.834635)
			(xy 187.437854 -137.91268) (xy 187.359809 -137.985094) (xy 187.276572 -138.051474) (xy 187.188607 -138.111447)
			(xy 187.096406 -138.16468) (xy 187.000484 -138.210873) (xy 186.901379 -138.249769) (xy 186.799644 -138.28115)
			(xy 186.695849 -138.304841) (xy 186.590573 -138.320708) (xy 186.484406 -138.328664) (xy 186.377942 -138.328664)
			(xy 186.271775 -138.320708) (xy 186.166499 -138.304841) (xy 186.062704 -138.28115) (xy 185.960969 -138.249769)
			(xy 185.861864 -138.210873) (xy 185.765942 -138.16468) (xy 185.673741 -138.111447) (xy 185.585776 -138.051474)
			(xy 185.502539 -137.985094) (xy 185.424494 -137.91268) (xy 185.35208 -137.834635) (xy 185.2857 -137.751398)
			(xy 185.225727 -137.663433) (xy 185.172494 -137.571232) (xy 185.126301 -137.47531) (xy 185.087405 -137.376205)
			(xy 185.056024 -137.27447) (xy 185.032333 -137.170675) (xy 185.016466 -137.065399) (xy 185.00851 -136.959232)
			(xy 175.661838 -136.959232) (xy 175.653882 -137.065399) (xy 175.638015 -137.170675) (xy 175.614324 -137.27447)
			(xy 175.582943 -137.376205) (xy 175.544047 -137.47531) (xy 175.497854 -137.571232) (xy 175.444621 -137.663433)
			(xy 175.384648 -137.751398) (xy 175.318268 -137.834635) (xy 175.245854 -137.91268) (xy 175.167809 -137.985094)
			(xy 175.084572 -138.051474) (xy 174.996607 -138.111447) (xy 174.904406 -138.16468) (xy 174.808484 -138.210873)
			(xy 174.709379 -138.249769) (xy 174.607644 -138.28115) (xy 174.503849 -138.304841) (xy 174.398573 -138.320708)
			(xy 174.292406 -138.328664) (xy 174.185942 -138.328664) (xy 174.079775 -138.320708) (xy 173.974499 -138.304841)
			(xy 173.870704 -138.28115) (xy 173.768969 -138.249769) (xy 173.669864 -138.210873) (xy 173.573942 -138.16468)
			(xy 173.481741 -138.111447) (xy 173.393776 -138.051474) (xy 173.310539 -137.985094) (xy 173.232494 -137.91268)
			(xy 173.16008 -137.834635) (xy 173.0937 -137.751398) (xy 173.033727 -137.663433) (xy 172.980494 -137.571232)
			(xy 172.934301 -137.47531) (xy 172.895405 -137.376205) (xy 172.864024 -137.27447) (xy 172.840333 -137.170675)
			(xy 172.824466 -137.065399) (xy 172.81651 -136.959232) (xy 163.469838 -136.959232) (xy 163.461882 -137.065399)
			(xy 163.446015 -137.170675) (xy 163.422324 -137.27447) (xy 163.390943 -137.376205) (xy 163.352047 -137.47531)
			(xy 163.305854 -137.571232) (xy 163.252621 -137.663433) (xy 163.192648 -137.751398) (xy 163.126268 -137.834635)
			(xy 163.053854 -137.91268) (xy 162.975809 -137.985094) (xy 162.892572 -138.051474) (xy 162.804607 -138.111447)
			(xy 162.712406 -138.16468) (xy 162.616484 -138.210873) (xy 162.517379 -138.249769) (xy 162.415644 -138.28115)
			(xy 162.311849 -138.304841) (xy 162.206573 -138.320708) (xy 162.100406 -138.328664) (xy 161.993942 -138.328664)
			(xy 161.887775 -138.320708) (xy 161.782499 -138.304841) (xy 161.678704 -138.28115) (xy 161.576969 -138.249769)
			(xy 161.477864 -138.210873) (xy 161.381942 -138.16468) (xy 161.289741 -138.111447) (xy 161.201776 -138.051474)
			(xy 161.118539 -137.985094) (xy 161.040494 -137.91268) (xy 160.96808 -137.834635) (xy 160.9017 -137.751398)
			(xy 160.841727 -137.663433) (xy 160.788494 -137.571232) (xy 160.742301 -137.47531) (xy 160.703405 -137.376205)
			(xy 160.672024 -137.27447) (xy 160.648333 -137.170675) (xy 160.632466 -137.065399) (xy 160.62451 -136.959232)
			(xy 147.853664 -136.959232) (xy 147.845708 -137.065399) (xy 147.829841 -137.170675) (xy 147.80615 -137.27447)
			(xy 147.774769 -137.376205) (xy 147.735873 -137.47531) (xy 147.68968 -137.571232) (xy 147.636447 -137.663433)
			(xy 147.576474 -137.751398) (xy 147.510094 -137.834635) (xy 147.43768 -137.91268) (xy 147.359635 -137.985094)
			(xy 147.276398 -138.051474) (xy 147.188433 -138.111447) (xy 147.096232 -138.16468) (xy 147.00031 -138.210873)
			(xy 146.901205 -138.249769) (xy 146.79947 -138.28115) (xy 146.695675 -138.304841) (xy 146.590399 -138.320708)
			(xy 146.484232 -138.328664) (xy 146.377768 -138.328664) (xy 146.271601 -138.320708) (xy 146.166325 -138.304841)
			(xy 146.06253 -138.28115) (xy 145.960795 -138.249769) (xy 145.86169 -138.210873) (xy 145.765768 -138.16468)
			(xy 145.673567 -138.111447) (xy 145.585602 -138.051474) (xy 145.502365 -137.985094) (xy 145.42432 -137.91268)
			(xy 145.351906 -137.834635) (xy 145.285526 -137.751398) (xy 145.225553 -137.663433) (xy 145.17232 -137.571232)
			(xy 145.126127 -137.47531) (xy 145.087231 -137.376205) (xy 145.05585 -137.27447) (xy 145.032159 -137.170675)
			(xy 145.016292 -137.065399) (xy 145.008336 -136.959232) (xy 135.661664 -136.959232) (xy 135.653708 -137.065399)
			(xy 135.637841 -137.170675) (xy 135.61415 -137.27447) (xy 135.582769 -137.376205) (xy 135.543873 -137.47531)
			(xy 135.49768 -137.571232) (xy 135.444447 -137.663433) (xy 135.384474 -137.751398) (xy 135.318094 -137.834635)
			(xy 135.24568 -137.91268) (xy 135.167635 -137.985094) (xy 135.084398 -138.051474) (xy 134.996433 -138.111447)
			(xy 134.904232 -138.16468) (xy 134.80831 -138.210873) (xy 134.709205 -138.249769) (xy 134.60747 -138.28115)
			(xy 134.503675 -138.304841) (xy 134.398399 -138.320708) (xy 134.292232 -138.328664) (xy 134.185768 -138.328664)
			(xy 134.079601 -138.320708) (xy 133.974325 -138.304841) (xy 133.87053 -138.28115) (xy 133.768795 -138.249769)
			(xy 133.66969 -138.210873) (xy 133.573768 -138.16468) (xy 133.481567 -138.111447) (xy 133.393602 -138.051474)
			(xy 133.310365 -137.985094) (xy 133.23232 -137.91268) (xy 133.159906 -137.834635) (xy 133.093526 -137.751398)
			(xy 133.033553 -137.663433) (xy 132.98032 -137.571232) (xy 132.934127 -137.47531) (xy 132.895231 -137.376205)
			(xy 132.86385 -137.27447) (xy 132.840159 -137.170675) (xy 132.824292 -137.065399) (xy 132.816336 -136.959232)
			(xy 123.469664 -136.959232) (xy 123.461708 -137.065399) (xy 123.445841 -137.170675) (xy 123.42215 -137.27447)
			(xy 123.390769 -137.376205) (xy 123.351873 -137.47531) (xy 123.30568 -137.571232) (xy 123.252447 -137.663433)
			(xy 123.192474 -137.751398) (xy 123.126094 -137.834635) (xy 123.05368 -137.91268) (xy 122.975635 -137.985094)
			(xy 122.892398 -138.051474) (xy 122.804433 -138.111447) (xy 122.712232 -138.16468) (xy 122.61631 -138.210873)
			(xy 122.517205 -138.249769) (xy 122.41547 -138.28115) (xy 122.311675 -138.304841) (xy 122.206399 -138.320708)
			(xy 122.100232 -138.328664) (xy 121.993768 -138.328664) (xy 121.887601 -138.320708) (xy 121.782325 -138.304841)
			(xy 121.67853 -138.28115) (xy 121.576795 -138.249769) (xy 121.47769 -138.210873) (xy 121.381768 -138.16468)
			(xy 121.289567 -138.111447) (xy 121.201602 -138.051474) (xy 121.118365 -137.985094) (xy 121.04032 -137.91268)
			(xy 120.967906 -137.834635) (xy 120.901526 -137.751398) (xy 120.841553 -137.663433) (xy 120.78832 -137.571232)
			(xy 120.742127 -137.47531) (xy 120.703231 -137.376205) (xy 120.67185 -137.27447) (xy 120.648159 -137.170675)
			(xy 120.632292 -137.065399) (xy 120.624336 -136.959232) (xy 107.85349 -136.959232) (xy 107.845534 -137.065399)
			(xy 107.829667 -137.170675) (xy 107.805976 -137.27447) (xy 107.774595 -137.376205) (xy 107.735699 -137.47531)
			(xy 107.689506 -137.571232) (xy 107.636273 -137.663433) (xy 107.5763 -137.751398) (xy 107.50992 -137.834635)
			(xy 107.437506 -137.91268) (xy 107.359461 -137.985094) (xy 107.276224 -138.051474) (xy 107.188259 -138.111447)
			(xy 107.096058 -138.16468) (xy 107.000136 -138.210873) (xy 106.901031 -138.249769) (xy 106.799296 -138.28115)
			(xy 106.695501 -138.304841) (xy 106.590225 -138.320708) (xy 106.484058 -138.328664) (xy 106.377594 -138.328664)
			(xy 106.271427 -138.320708) (xy 106.166151 -138.304841) (xy 106.062356 -138.28115) (xy 105.960621 -138.249769)
			(xy 105.861516 -138.210873) (xy 105.765594 -138.16468) (xy 105.673393 -138.111447) (xy 105.585428 -138.051474)
			(xy 105.502191 -137.985094) (xy 105.424146 -137.91268) (xy 105.351732 -137.834635) (xy 105.285352 -137.751398)
			(xy 105.225379 -137.663433) (xy 105.172146 -137.571232) (xy 105.125953 -137.47531) (xy 105.087057 -137.376205)
			(xy 105.055676 -137.27447) (xy 105.031985 -137.170675) (xy 105.016118 -137.065399) (xy 105.008162 -136.959232)
			(xy 95.66149 -136.959232) (xy 95.653534 -137.065399) (xy 95.637667 -137.170675) (xy 95.613976 -137.27447)
			(xy 95.582595 -137.376205) (xy 95.543699 -137.47531) (xy 95.497506 -137.571232) (xy 95.444273 -137.663433)
			(xy 95.3843 -137.751398) (xy 95.31792 -137.834635) (xy 95.245506 -137.91268) (xy 95.167461 -137.985094)
			(xy 95.084224 -138.051474) (xy 94.996259 -138.111447) (xy 94.904058 -138.16468) (xy 94.808136 -138.210873)
			(xy 94.709031 -138.249769) (xy 94.607296 -138.28115) (xy 94.503501 -138.304841) (xy 94.398225 -138.320708)
			(xy 94.292058 -138.328664) (xy 94.185594 -138.328664) (xy 94.079427 -138.320708) (xy 93.974151 -138.304841)
			(xy 93.870356 -138.28115) (xy 93.768621 -138.249769) (xy 93.669516 -138.210873) (xy 93.573594 -138.16468)
			(xy 93.481393 -138.111447) (xy 93.393428 -138.051474) (xy 93.310191 -137.985094) (xy 93.232146 -137.91268)
			(xy 93.159732 -137.834635) (xy 93.093352 -137.751398) (xy 93.033379 -137.663433) (xy 92.980146 -137.571232)
			(xy 92.933953 -137.47531) (xy 92.895057 -137.376205) (xy 92.863676 -137.27447) (xy 92.839985 -137.170675)
			(xy 92.824118 -137.065399) (xy 92.816162 -136.959232) (xy 83.46949 -136.959232) (xy 83.461534 -137.065399)
			(xy 83.445667 -137.170675) (xy 83.421976 -137.27447) (xy 83.390595 -137.376205) (xy 83.351699 -137.47531)
			(xy 83.305506 -137.571232) (xy 83.252273 -137.663433) (xy 83.1923 -137.751398) (xy 83.12592 -137.834635)
			(xy 83.053506 -137.91268) (xy 82.975461 -137.985094) (xy 82.892224 -138.051474) (xy 82.804259 -138.111447)
			(xy 82.712058 -138.16468) (xy 82.616136 -138.210873) (xy 82.517031 -138.249769) (xy 82.415296 -138.28115)
			(xy 82.311501 -138.304841) (xy 82.206225 -138.320708) (xy 82.100058 -138.328664) (xy 81.993594 -138.328664)
			(xy 81.887427 -138.320708) (xy 81.782151 -138.304841) (xy 81.678356 -138.28115) (xy 81.576621 -138.249769)
			(xy 81.477516 -138.210873) (xy 81.381594 -138.16468) (xy 81.289393 -138.111447) (xy 81.201428 -138.051474)
			(xy 81.118191 -137.985094) (xy 81.040146 -137.91268) (xy 80.967732 -137.834635) (xy 80.901352 -137.751398)
			(xy 80.841379 -137.663433) (xy 80.788146 -137.571232) (xy 80.741953 -137.47531) (xy 80.703057 -137.376205)
			(xy 80.671676 -137.27447) (xy 80.647985 -137.170675) (xy 80.632118 -137.065399) (xy 80.624162 -136.959232)
			(xy 67.85357 -136.959232) (xy 67.845614 -137.065399) (xy 67.829747 -137.170675) (xy 67.806056 -137.27447)
			(xy 67.774675 -137.376205) (xy 67.735779 -137.47531) (xy 67.689586 -137.571232) (xy 67.636353 -137.663433)
			(xy 67.57638 -137.751398) (xy 67.51 -137.834635) (xy 67.437586 -137.91268) (xy 67.359541 -137.985094)
			(xy 67.276304 -138.051474) (xy 67.188339 -138.111447) (xy 67.096138 -138.16468) (xy 67.000216 -138.210873)
			(xy 66.901111 -138.249769) (xy 66.799376 -138.28115) (xy 66.695581 -138.304841) (xy 66.590305 -138.320708)
			(xy 66.484138 -138.328664) (xy 66.377674 -138.328664) (xy 66.271507 -138.320708) (xy 66.166231 -138.304841)
			(xy 66.062436 -138.28115) (xy 65.960701 -138.249769) (xy 65.861596 -138.210873) (xy 65.765674 -138.16468)
			(xy 65.673473 -138.111447) (xy 65.585508 -138.051474) (xy 65.502271 -137.985094) (xy 65.424226 -137.91268)
			(xy 65.351812 -137.834635) (xy 65.285432 -137.751398) (xy 65.225459 -137.663433) (xy 65.172226 -137.571232)
			(xy 65.126033 -137.47531) (xy 65.087137 -137.376205) (xy 65.055756 -137.27447) (xy 65.032065 -137.170675)
			(xy 65.016198 -137.065399) (xy 65.008242 -136.959232) (xy 55.66157 -136.959232) (xy 55.653614 -137.065399)
			(xy 55.637747 -137.170675) (xy 55.614056 -137.27447) (xy 55.582675 -137.376205) (xy 55.543779 -137.47531)
			(xy 55.497586 -137.571232) (xy 55.444353 -137.663433) (xy 55.38438 -137.751398) (xy 55.318 -137.834635)
			(xy 55.245586 -137.91268) (xy 55.167541 -137.985094) (xy 55.084304 -138.051474) (xy 54.996339 -138.111447)
			(xy 54.904138 -138.16468) (xy 54.808216 -138.210873) (xy 54.709111 -138.249769) (xy 54.607376 -138.28115)
			(xy 54.503581 -138.304841) (xy 54.398305 -138.320708) (xy 54.292138 -138.328664) (xy 54.185674 -138.328664)
			(xy 54.079507 -138.320708) (xy 53.974231 -138.304841) (xy 53.870436 -138.28115) (xy 53.768701 -138.249769)
			(xy 53.669596 -138.210873) (xy 53.573674 -138.16468) (xy 53.481473 -138.111447) (xy 53.393508 -138.051474)
			(xy 53.310271 -137.985094) (xy 53.232226 -137.91268) (xy 53.159812 -137.834635) (xy 53.093432 -137.751398)
			(xy 53.033459 -137.663433) (xy 52.980226 -137.571232) (xy 52.934033 -137.47531) (xy 52.895137 -137.376205)
			(xy 52.863756 -137.27447) (xy 52.840065 -137.170675) (xy 52.824198 -137.065399) (xy 52.816242 -136.959232)
			(xy 43.46957 -136.959232) (xy 43.461614 -137.065399) (xy 43.445747 -137.170675) (xy 43.422056 -137.27447)
			(xy 43.390675 -137.376205) (xy 43.351779 -137.47531) (xy 43.305586 -137.571232) (xy 43.252353 -137.663433)
			(xy 43.19238 -137.751398) (xy 43.126 -137.834635) (xy 43.053586 -137.91268) (xy 42.975541 -137.985094)
			(xy 42.892304 -138.051474) (xy 42.804339 -138.111447) (xy 42.712138 -138.16468) (xy 42.616216 -138.210873)
			(xy 42.517111 -138.249769) (xy 42.415376 -138.28115) (xy 42.311581 -138.304841) (xy 42.206305 -138.320708)
			(xy 42.100138 -138.328664) (xy 41.993674 -138.328664) (xy 41.887507 -138.320708) (xy 41.782231 -138.304841)
			(xy 41.678436 -138.28115) (xy 41.576701 -138.249769) (xy 41.477596 -138.210873) (xy 41.381674 -138.16468)
			(xy 41.289473 -138.111447) (xy 41.201508 -138.051474) (xy 41.118271 -137.985094) (xy 41.040226 -137.91268)
			(xy 40.967812 -137.834635) (xy 40.901432 -137.751398) (xy 40.841459 -137.663433) (xy 40.788226 -137.571232)
			(xy 40.742033 -137.47531) (xy 40.703137 -137.376205) (xy 40.671756 -137.27447) (xy 40.648065 -137.170675)
			(xy 40.632198 -137.065399) (xy 40.624242 -136.959232) (xy 0.509016 -136.959232) (xy 0.509016 -141.95405)
			(xy 220.791775 -141.95405) (xy 220.791775 -141.82491) (xy 220.799725 -141.696015) (xy 220.815595 -141.567855)
			(xy 220.839324 -141.440914) (xy 220.870823 -141.315675) (xy 220.909972 -141.192612) (xy 220.956623 -141.072193)
			(xy 221.010598 -140.954874) (xy 221.071693 -140.8411) (xy 221.139676 -140.731303) (xy 221.21429 -140.6259)
			(xy 221.295251 -140.52529) (xy 221.382251 -140.429855) (xy 221.474962 -140.339956) (xy 221.573032 -140.255935)
			(xy 221.676087 -140.178111) (xy 221.783738 -140.106779) (xy 221.895577 -140.042209) (xy 222.011178 -139.984647)
			(xy 222.130103 -139.93431) (xy 222.251902 -139.89139) (xy 222.376112 -139.856049) (xy 222.502261 -139.828422)
			(xy 222.629873 -139.808613) (xy 222.758462 -139.796697) (xy 222.88754 -139.792721) (xy 223.016618 -139.796697)
			(xy 223.145207 -139.808613) (xy 223.272819 -139.828422) (xy 223.398968 -139.856049) (xy 223.523178 -139.89139)
			(xy 223.644977 -139.93431) (xy 223.763902 -139.984647) (xy 223.879503 -140.042209) (xy 223.991342 -140.106779)
			(xy 224.098993 -140.178111) (xy 224.202048 -140.255935) (xy 224.300118 -140.339956) (xy 224.392829 -140.429855)
			(xy 224.422133 -140.462) (xy 270.001492 -140.462) (xy 270.002075 -140.415604) (xy 270.01172 -140.323316)
			(xy 270.030916 -140.232532) (xy 270.059454 -140.144239) (xy 270.077692 -140.101574) (xy 270.081498 -140.091632)
			(xy 270.081498 -140.070368) (xy 270.077692 -140.060426) (xy 270.059447 -140.017764) (xy 270.030903 -139.929471)
			(xy 270.01171 -139.838686) (xy 270.002077 -139.746396) (xy 270.001492 -139.7) (xy 270.002075 -139.653604)
			(xy 270.01172 -139.561316) (xy 270.030916 -139.470532) (xy 270.059454 -139.382239) (xy 270.077692 -139.339574)
			(xy 270.081498 -139.329632) (xy 270.081498 -139.308368) (xy 270.077692 -139.298426) (xy 270.059447 -139.255764)
			(xy 270.030903 -139.167471) (xy 270.01171 -139.076686) (xy 270.002077 -138.984396) (xy 270.001492 -138.938)
			(xy 270.002075 -138.891604) (xy 270.01172 -138.799316) (xy 270.030916 -138.708532) (xy 270.059454 -138.620239)
			(xy 270.077692 -138.577574) (xy 270.081498 -138.567632) (xy 270.081498 -138.546368) (xy 270.077692 -138.536426)
			(xy 270.059447 -138.493764) (xy 270.030903 -138.405471) (xy 270.01171 -138.314686) (xy 270.002077 -138.222396)
			(xy 270.001492 -138.176) (xy 270.002075 -138.129604) (xy 270.01172 -138.037316) (xy 270.030916 -137.946532)
			(xy 270.059454 -137.858239) (xy 270.077692 -137.815574) (xy 270.081498 -137.805632) (xy 270.081498 -137.784368)
			(xy 270.077692 -137.774426) (xy 270.059447 -137.731764) (xy 270.030903 -137.643471) (xy 270.01171 -137.552686)
			(xy 270.002077 -137.460396) (xy 270.001492 -137.414) (xy 270.002075 -137.367604) (xy 270.01172 -137.275316)
			(xy 270.030916 -137.184532) (xy 270.059454 -137.096239) (xy 270.077692 -137.053574) (xy 270.081498 -137.043632)
			(xy 270.081498 -137.022368) (xy 270.077692 -137.012426) (xy 270.059447 -136.969764) (xy 270.030903 -136.881471)
			(xy 270.01171 -136.790686) (xy 270.002077 -136.698396) (xy 270.001492 -136.652) (xy 270.001967 -136.610898)
			(xy 270.009552 -136.529043) (xy 270.024657 -136.448238) (xy 270.047153 -136.369171) (xy 270.076849 -136.292517)
			(xy 270.113491 -136.21893) (xy 270.156766 -136.149038) (xy 270.206306 -136.083437) (xy 270.261687 -136.022687)
			(xy 270.322437 -135.967306) (xy 270.388038 -135.917766) (xy 270.45793 -135.874491) (xy 270.531517 -135.837849)
			(xy 270.608171 -135.808153) (xy 270.687238 -135.785657) (xy 270.768043 -135.770552) (xy 270.849898 -135.762967)
			(xy 270.891 -135.762492) (xy 270.937396 -135.763075) (xy 271.029684 -135.77272) (xy 271.120468 -135.791916)
			(xy 271.208761 -135.820454) (xy 271.251426 -135.838692) (xy 271.261368 -135.842498) (xy 271.282632 -135.842498)
			(xy 271.292574 -135.838692) (xy 271.335236 -135.820447) (xy 271.423529 -135.791903) (xy 271.514314 -135.77271)
			(xy 271.606604 -135.763077) (xy 271.653 -135.762492) (xy 271.694102 -135.762967) (xy 271.775957 -135.770552)
			(xy 271.856762 -135.785657) (xy 271.935829 -135.808153) (xy 272.012483 -135.837849) (xy 272.08607 -135.874491)
			(xy 272.155962 -135.917766) (xy 272.221563 -135.967306) (xy 272.282313 -136.022687) (xy 272.337694 -136.083437)
			(xy 272.387234 -136.149038) (xy 272.430509 -136.21893) (xy 272.467151 -136.292517) (xy 272.496847 -136.369171)
			(xy 272.519343 -136.448238) (xy 272.534448 -136.529043) (xy 272.542033 -136.610898) (xy 272.542508 -136.652)
			(xy 272.541925 -136.698396) (xy 272.53228 -136.790684) (xy 272.513084 -136.881468) (xy 272.484546 -136.969761)
			(xy 272.466308 -137.012426) (xy 272.462502 -137.022368) (xy 272.462502 -137.043632) (xy 272.466308 -137.053574)
			(xy 272.484553 -137.096236) (xy 272.513097 -137.184529) (xy 272.53229 -137.275314) (xy 272.541923 -137.367604)
			(xy 272.542508 -137.414) (xy 272.541925 -137.460396) (xy 272.53228 -137.552684) (xy 272.513084 -137.643468)
			(xy 272.484546 -137.731761) (xy 272.466308 -137.774426) (xy 272.462502 -137.784368) (xy 272.462502 -137.805632)
			(xy 272.466308 -137.815574) (xy 272.484553 -137.858236) (xy 272.513097 -137.946529) (xy 272.53229 -138.037314)
			(xy 272.541923 -138.129604) (xy 272.542508 -138.176) (xy 272.541925 -138.222396) (xy 272.53228 -138.314684)
			(xy 272.513084 -138.405468) (xy 272.484546 -138.493761) (xy 272.466308 -138.536426) (xy 272.462502 -138.546368)
			(xy 272.462502 -138.567632) (xy 272.466308 -138.577574) (xy 272.484553 -138.620236) (xy 272.513097 -138.708529)
			(xy 272.53229 -138.799314) (xy 272.541923 -138.891604) (xy 272.542508 -138.938) (xy 272.541925 -138.984396)
			(xy 272.53228 -139.076684) (xy 272.513084 -139.167468) (xy 272.484546 -139.255761) (xy 272.466308 -139.298426)
			(xy 272.462502 -139.308368) (xy 272.462502 -139.329632) (xy 272.466308 -139.339574) (xy 272.484553 -139.382236)
			(xy 272.513097 -139.470529) (xy 272.53229 -139.561314) (xy 272.541923 -139.653604) (xy 272.542508 -139.7)
			(xy 272.541925 -139.746396) (xy 272.53228 -139.838684) (xy 272.513084 -139.929468) (xy 272.484546 -140.017761)
			(xy 272.466308 -140.060426) (xy 272.462502 -140.070368) (xy 272.462502 -140.091632) (xy 272.466308 -140.101574)
			(xy 272.484553 -140.144236) (xy 272.513097 -140.232529) (xy 272.53229 -140.323314) (xy 272.541923 -140.415604)
			(xy 272.542508 -140.462) (xy 272.542033 -140.503102) (xy 272.534448 -140.584957) (xy 272.519343 -140.665762)
			(xy 272.496847 -140.744829) (xy 272.467151 -140.821483) (xy 272.430509 -140.89507) (xy 272.387234 -140.964962)
			(xy 272.337694 -141.030563) (xy 272.282313 -141.091313) (xy 272.221563 -141.146694) (xy 272.155962 -141.196234)
			(xy 272.08607 -141.239509) (xy 272.012483 -141.276151) (xy 271.935829 -141.305847) (xy 271.856762 -141.328343)
			(xy 271.775957 -141.343448) (xy 271.694102 -141.351033) (xy 271.653 -141.351508) (xy 271.606604 -141.350925)
			(xy 271.514316 -141.34128) (xy 271.423532 -141.322084) (xy 271.335239 -141.293546) (xy 271.292574 -141.275308)
			(xy 271.282632 -141.271502) (xy 271.261368 -141.271502) (xy 271.251426 -141.275308) (xy 271.208764 -141.293553)
			(xy 271.120471 -141.322097) (xy 271.029686 -141.34129) (xy 270.937396 -141.350923) (xy 270.891 -141.351508)
			(xy 270.849898 -141.351033) (xy 270.768043 -141.343448) (xy 270.687238 -141.328343) (xy 270.608171 -141.305847)
			(xy 270.531517 -141.276151) (xy 270.45793 -141.239509) (xy 270.388038 -141.196234) (xy 270.322437 -141.146694)
			(xy 270.261687 -141.091313) (xy 270.206306 -141.030563) (xy 270.156766 -140.964962) (xy 270.113491 -140.89507)
			(xy 270.076849 -140.821483) (xy 270.047153 -140.744829) (xy 270.024657 -140.665762) (xy 270.009552 -140.584957)
			(xy 270.001967 -140.503102) (xy 270.001492 -140.462) (xy 224.422133 -140.462) (xy 224.479829 -140.52529)
			(xy 224.56079 -140.6259) (xy 224.635404 -140.731303) (xy 224.703387 -140.8411) (xy 224.764482 -140.954874)
			(xy 224.818457 -141.072193) (xy 224.865108 -141.192612) (xy 224.904257 -141.315675) (xy 224.935756 -141.440914)
			(xy 224.959485 -141.567855) (xy 224.975355 -141.696015) (xy 224.983305 -141.82491) (xy 224.983802 -141.88948)
			(xy 224.983305 -141.95405) (xy 224.975355 -142.082945) (xy 224.959485 -142.211105) (xy 224.935756 -142.338046)
			(xy 224.904257 -142.463285) (xy 224.865108 -142.586348) (xy 224.818457 -142.706767) (xy 224.764482 -142.824086)
			(xy 224.703387 -142.93786) (xy 224.635404 -143.047657) (xy 224.56079 -143.15306) (xy 224.479829 -143.25367)
			(xy 224.392829 -143.349105) (xy 224.300118 -143.439004) (xy 224.202048 -143.523025) (xy 224.098993 -143.600849)
			(xy 223.991342 -143.672181) (xy 223.879503 -143.736751) (xy 223.763902 -143.794313) (xy 223.644977 -143.84465)
			(xy 223.523178 -143.88757) (xy 223.398968 -143.922911) (xy 223.272819 -143.950538) (xy 223.145207 -143.970347)
			(xy 223.016618 -143.982263) (xy 222.88754 -143.98624) (xy 222.758462 -143.982263) (xy 222.629873 -143.970347)
			(xy 222.502261 -143.950538) (xy 222.376112 -143.922911) (xy 222.251902 -143.88757) (xy 222.130103 -143.84465)
			(xy 222.011178 -143.794313) (xy 221.895577 -143.736751) (xy 221.783738 -143.672181) (xy 221.676087 -143.600849)
			(xy 221.573032 -143.523025) (xy 221.474962 -143.439004) (xy 221.382251 -143.349105) (xy 221.295251 -143.25367)
			(xy 221.21429 -143.15306) (xy 221.139676 -143.047657) (xy 221.071693 -142.93786) (xy 221.010598 -142.824086)
			(xy 220.956623 -142.706767) (xy 220.909972 -142.586348) (xy 220.870823 -142.463285) (xy 220.839324 -142.338046)
			(xy 220.815595 -142.211105) (xy 220.799725 -142.082945) (xy 220.791775 -141.95405) (xy 0.509016 -141.95405)
			(xy 0.509016 -141.99997) (xy 0.509522 -142.095303) (xy 0.517614 -142.285798) (xy 0.533784 -142.475778)
			(xy 0.558002 -142.664901) (xy 0.590225 -142.852825) (xy 0.630394 -143.039212) (xy 0.678438 -143.223727)
			(xy 0.73427 -143.406036) (xy 0.797788 -143.585811) (xy 0.86888 -143.762729) (xy 0.947415 -143.93647)
			(xy 1.033254 -144.106721) (xy 1.126242 -144.273176) (xy 1.22621 -144.435534) (xy 1.332978 -144.593504)
			(xy 1.446355 -144.746799) (xy 1.566136 -144.895145) (xy 1.692104 -145.038273) (xy 1.824034 -145.175926)
			(xy 1.961687 -145.307856) (xy 2.104815 -145.433824) (xy 2.253161 -145.553605) (xy 2.406456 -145.666982)
			(xy 2.564426 -145.77375) (xy 2.726784 -145.873718) (xy 2.893239 -145.966706) (xy 3.06349 -146.052545)
			(xy 3.237231 -146.13108) (xy 3.414149 -146.202172) (xy 3.593924 -146.26569) (xy 3.776233 -146.321522)
			(xy 3.960748 -146.369566) (xy 4.147135 -146.409735) (xy 4.335059 -146.441958) (xy 4.524182 -146.466176)
			(xy 4.714162 -146.482346) (xy 4.904657 -146.490438) (xy 4.99999 -146.490944) (xy 266.33297 -146.490944)
			(xy 266.33297 -146.49196) (xy 266.666472 -146.49196)
		)
		(stroke
			(width 0)
			(type solid)
		)
		(fill yes)
		(layer "In8.Cu")
		(net "GND")
	)
	(gr_circle
		(center 9.85012 -76.019914)
		(end 11.22172 -76.019914)
		(stroke
			(width 0.2)
			(type default)
		)
		(fill no)
		(layer "In8.Cu")
	)
	(gr_circle
		(center 9.85012 -74.319892)
		(end 11.22172 -74.319892)
		(stroke
			(width 0.2)
			(type default)
		)
		(fill no)
		(layer "In8.Cu")
	)
	(gr_circle
		(center 9.85012 -70.939914)
		(end 11.22172 -70.939914)
		(stroke
			(width 0.2)
			(type default)
		)
		(fill no)
		(layer "In8.Cu")
	)
	(gr_circle
		(center 9.85012 -69.239892)
		(end 11.22172 -69.239892)
		(stroke
			(width 0.2)
			(type default)
		)
		(fill no)
		(layer "In8.Cu")
	)
	(gr_circle
		(center 11.147552 -75.13574)
		(end 12.519152 -75.13574)
		(stroke
			(width 0.2)
			(type default)
		)
		(fill no)
		(layer "In8.Cu")
	)
	(gr_circle
		(center 11.217148 -70.108572)
		(end 12.588748 -70.108572)
		(stroke
			(width 0.2)
			(type default)
		)
		(fill no)
		(layer "In8.Cu")
	)
	(gr_circle
		(center 12.39012 -76.019914)
		(end 13.76172 -76.019914)
		(stroke
			(width 0.2)
			(type default)
		)
		(fill no)
		(layer "In8.Cu")
	)
	(gr_circle
		(center 12.39012 -74.319892)
		(end 13.76172 -74.319892)
		(stroke
			(width 0.2)
			(type default)
		)
		(fill no)
		(layer "In8.Cu")
	)
	(gr_circle
		(center 12.39012 -70.939914)
		(end 13.76172 -70.939914)
		(stroke
			(width 0.2)
			(type default)
		)
		(fill no)
		(layer "In8.Cu")
	)
	(gr_circle
		(center 12.39012 -69.239892)
		(end 13.76172 -69.239892)
		(stroke
			(width 0.2)
			(type default)
		)
		(fill no)
		(layer "In8.Cu")
	)
	(gr_circle
		(center 27.5844 -66.43624)
		(end 28.4734 -66.43624)
		(stroke
			(width 0.2)
			(type default)
		)
		(fill no)
		(layer "In8.Cu")
	)
	(gr_circle
		(center 27.5844 -65.67424)
		(end 28.4734 -65.67424)
		(stroke
			(width 0.2)
			(type default)
		)
		(fill no)
		(layer "In8.Cu")
	)
	(gr_circle
		(center 27.5844 -64.91224)
		(end 28.4734 -64.91224)
		(stroke
			(width 0.2)
			(type default)
		)
		(fill no)
		(layer "In8.Cu")
	)
	(gr_circle
		(center 28.3464 -66.43624)
		(end 29.2354 -66.43624)
		(stroke
			(width 0.2)
			(type default)
		)
		(fill no)
		(layer "In8.Cu")
	)
	(gr_circle
		(center 28.3464 -65.67424)
		(end 29.2354 -65.67424)
		(stroke
			(width 0.2)
			(type default)
		)
		(fill no)
		(layer "In8.Cu")
	)
	(gr_circle
		(center 28.3464 -64.91224)
		(end 29.2354 -64.91224)
		(stroke
			(width 0.2)
			(type default)
		)
		(fill no)
		(layer "In8.Cu")
	)
	(gr_circle
		(center 29.3878 -108.3818)
		(end 30.2768 -108.3818)
		(stroke
			(width 0.2)
			(type default)
		)
		(fill no)
		(layer "In8.Cu")
	)
	(gr_circle
		(center 29.3878 -107.6198)
		(end 30.2768 -107.6198)
		(stroke
			(width 0.2)
			(type default)
		)
		(fill no)
		(layer "In8.Cu")
	)
	(gr_circle
		(center 29.3878 -106.8324)
		(end 30.2768 -106.8324)
		(stroke
			(width 0.2)
			(type default)
		)
		(fill no)
		(layer "In8.Cu")
	)
	(gr_circle
		(center 29.3878 -106.0704)
		(end 30.2768 -106.0704)
		(stroke
			(width 0.2)
			(type default)
		)
		(fill no)
		(layer "In8.Cu")
	)
	(gr_circle
		(center 29.3878 -105.3084)
		(end 30.2768 -105.3084)
		(stroke
			(width 0.2)
			(type default)
		)
		(fill no)
		(layer "In8.Cu")
	)
	(gr_circle
		(center 29.3878 -104.5464)
		(end 30.2768 -104.5464)
		(stroke
			(width 0.2)
			(type default)
		)
		(fill no)
		(layer "In8.Cu")
	)
	(gr_circle
		(center 29.3878 -103.7844)
		(end 30.2768 -103.7844)
		(stroke
			(width 0.2)
			(type default)
		)
		(fill no)
		(layer "In8.Cu")
	)
	(gr_circle
		(center 30.353 -108.3564)
		(end 31.242 -108.3564)
		(stroke
			(width 0.2)
			(type default)
		)
		(fill no)
		(layer "In8.Cu")
	)
	(gr_circle
		(center 30.353 -107.5944)
		(end 31.242 -107.5944)
		(stroke
			(width 0.2)
			(type default)
		)
		(fill no)
		(layer "In8.Cu")
	)
	(gr_circle
		(center 30.353 -106.807)
		(end 31.242 -106.807)
		(stroke
			(width 0.2)
			(type default)
		)
		(fill no)
		(layer "In8.Cu")
	)
	(gr_circle
		(center 30.353 -106.045)
		(end 31.242 -106.045)
		(stroke
			(width 0.2)
			(type default)
		)
		(fill no)
		(layer "In8.Cu")
	)
	(gr_circle
		(center 30.353 -105.283)
		(end 31.242 -105.283)
		(stroke
			(width 0.2)
			(type default)
		)
		(fill no)
		(layer "In8.Cu")
	)
	(gr_circle
		(center 30.353 -104.521)
		(end 31.242 -104.521)
		(stroke
			(width 0.2)
			(type default)
		)
		(fill no)
		(layer "In8.Cu")
	)
	(gr_circle
		(center 30.353 -103.759)
		(end 31.242 -103.759)
		(stroke
			(width 0.2)
			(type default)
		)
		(fill no)
		(layer "In8.Cu")
	)
	(gr_circle
		(center 31.242 -108.3564)
		(end 32.131 -108.3564)
		(stroke
			(width 0.2)
			(type default)
		)
		(fill no)
		(layer "In8.Cu")
	)
	(gr_circle
		(center 31.242 -107.5944)
		(end 32.131 -107.5944)
		(stroke
			(width 0.2)
			(type default)
		)
		(fill no)
		(layer "In8.Cu")
	)
	(gr_circle
		(center 31.242 -106.807)
		(end 32.131 -106.807)
		(stroke
			(width 0.2)
			(type default)
		)
		(fill no)
		(layer "In8.Cu")
	)
	(gr_circle
		(center 31.242 -106.045)
		(end 32.131 -106.045)
		(stroke
			(width 0.2)
			(type default)
		)
		(fill no)
		(layer "In8.Cu")
	)
	(gr_circle
		(center 31.242 -105.283)
		(end 32.131 -105.283)
		(stroke
			(width 0.2)
			(type default)
		)
		(fill no)
		(layer "In8.Cu")
	)
	(gr_circle
		(center 31.242 -104.521)
		(end 32.131 -104.521)
		(stroke
			(width 0.2)
			(type default)
		)
		(fill no)
		(layer "In8.Cu")
	)
	(gr_circle
		(center 31.242 -103.759)
		(end 32.131 -103.759)
		(stroke
			(width 0.2)
			(type default)
		)
		(fill no)
		(layer "In8.Cu")
	)
	(gr_circle
		(center 38.261036 -55.642002)
		(end 39.150036 -55.642002)
		(stroke
			(width 0.2)
			(type default)
		)
		(fill no)
		(layer "In8.Cu")
	)
	(gr_circle
		(center 38.692836 -58.436002)
		(end 39.581836 -58.436002)
		(stroke
			(width 0.2)
			(type default)
		)
		(fill no)
		(layer "In8.Cu")
	)
	(gr_circle
		(center 38.692836 -57.547002)
		(end 39.581836 -57.547002)
		(stroke
			(width 0.2)
			(type default)
		)
		(fill no)
		(layer "In8.Cu")
	)
	(gr_circle
		(center 38.692836 -56.658002)
		(end 39.581836 -56.658002)
		(stroke
			(width 0.2)
			(type default)
		)
		(fill no)
		(layer "In8.Cu")
	)
	(gr_circle
		(center 39.378636 -58.817002)
		(end 40.267636 -58.817002)
		(stroke
			(width 0.2)
			(type default)
		)
		(fill no)
		(layer "In8.Cu")
	)
	(gr_circle
		(center 39.378636 -57.928002)
		(end 40.267636 -57.928002)
		(stroke
			(width 0.2)
			(type default)
		)
		(fill no)
		(layer "In8.Cu")
	)
	(gr_circle
		(center 39.378636 -57.039002)
		(end 40.267636 -57.039002)
		(stroke
			(width 0.2)
			(type default)
		)
		(fill no)
		(layer "In8.Cu")
	)
	(gr_circle
		(center 39.8272 -108.3564)
		(end 40.7162 -108.3564)
		(stroke
			(width 0.2)
			(type default)
		)
		(fill no)
		(layer "In8.Cu")
	)
	(gr_circle
		(center 39.8272 -107.5944)
		(end 40.7162 -107.5944)
		(stroke
			(width 0.2)
			(type default)
		)
		(fill no)
		(layer "In8.Cu")
	)
	(gr_circle
		(center 39.878 -106.807)
		(end 40.767 -106.807)
		(stroke
			(width 0.2)
			(type default)
		)
		(fill no)
		(layer "In8.Cu")
	)
	(gr_circle
		(center 39.878 -106.045)
		(end 40.767 -106.045)
		(stroke
			(width 0.2)
			(type default)
		)
		(fill no)
		(layer "In8.Cu")
	)
	(gr_circle
		(center 39.878 -105.283)
		(end 40.767 -105.283)
		(stroke
			(width 0.2)
			(type default)
		)
		(fill no)
		(layer "In8.Cu")
	)
	(gr_circle
		(center 39.878 -104.521)
		(end 40.767 -104.521)
		(stroke
			(width 0.2)
			(type default)
		)
		(fill no)
		(layer "In8.Cu")
	)
	(gr_circle
		(center 39.878 -103.759)
		(end 40.767 -103.759)
		(stroke
			(width 0.2)
			(type default)
		)
		(fill no)
		(layer "In8.Cu")
	)
	(gr_circle
		(center 40.7162 -108.3564)
		(end 41.6052 -108.3564)
		(stroke
			(width 0.2)
			(type default)
		)
		(fill no)
		(layer "In8.Cu")
	)
	(gr_circle
		(center 40.7162 -107.5944)
		(end 41.6052 -107.5944)
		(stroke
			(width 0.2)
			(type default)
		)
		(fill no)
		(layer "In8.Cu")
	)
	(gr_circle
		(center 40.767 -106.807)
		(end 41.656 -106.807)
		(stroke
			(width 0.2)
			(type default)
		)
		(fill no)
		(layer "In8.Cu")
	)
	(gr_circle
		(center 40.767 -106.045)
		(end 41.656 -106.045)
		(stroke
			(width 0.2)
			(type default)
		)
		(fill no)
		(layer "In8.Cu")
	)
	(gr_circle
		(center 40.767 -105.283)
		(end 41.656 -105.283)
		(stroke
			(width 0.2)
			(type default)
		)
		(fill no)
		(layer "In8.Cu")
	)
	(gr_circle
		(center 40.767 -104.521)
		(end 41.656 -104.521)
		(stroke
			(width 0.2)
			(type default)
		)
		(fill no)
		(layer "In8.Cu")
	)
	(gr_circle
		(center 40.767 -103.759)
		(end 41.656 -103.759)
		(stroke
			(width 0.2)
			(type default)
		)
		(fill no)
		(layer "In8.Cu")
	)
	(gr_circle
		(center 41.3639 -58.604912)
		(end 42.2529 -58.604912)
		(stroke
			(width 0.2)
			(type default)
		)
		(fill no)
		(layer "In8.Cu")
	)
	(gr_circle
		(center 41.3639 -57.70499)
		(end 42.2529 -57.70499)
		(stroke
			(width 0.2)
			(type default)
		)
		(fill no)
		(layer "In8.Cu")
	)
	(gr_circle
		(center 41.3639 -56.805068)
		(end 42.2529 -56.805068)
		(stroke
			(width 0.2)
			(type default)
		)
		(fill no)
		(layer "In8.Cu")
	)
	(gr_circle
		(center 41.3639 -55.904892)
		(end 42.2529 -55.904892)
		(stroke
			(width 0.2)
			(type default)
		)
		(fill no)
		(layer "In8.Cu")
	)
	(gr_circle
		(center 41.6052 -108.3818)
		(end 42.4942 -108.3818)
		(stroke
			(width 0.2)
			(type default)
		)
		(fill no)
		(layer "In8.Cu")
	)
	(gr_circle
		(center 41.6052 -107.6198)
		(end 42.4942 -107.6198)
		(stroke
			(width 0.2)
			(type default)
		)
		(fill no)
		(layer "In8.Cu")
	)
	(gr_circle
		(center 41.656 -106.8324)
		(end 42.545 -106.8324)
		(stroke
			(width 0.2)
			(type default)
		)
		(fill no)
		(layer "In8.Cu")
	)
	(gr_circle
		(center 41.656 -106.0704)
		(end 42.545 -106.0704)
		(stroke
			(width 0.2)
			(type default)
		)
		(fill no)
		(layer "In8.Cu")
	)
	(gr_circle
		(center 41.656 -105.3084)
		(end 42.545 -105.3084)
		(stroke
			(width 0.2)
			(type default)
		)
		(fill no)
		(layer "In8.Cu")
	)
	(gr_circle
		(center 41.656 -104.5464)
		(end 42.545 -104.5464)
		(stroke
			(width 0.2)
			(type default)
		)
		(fill no)
		(layer "In8.Cu")
	)
	(gr_circle
		(center 41.656 -103.7844)
		(end 42.545 -103.7844)
		(stroke
			(width 0.2)
			(type default)
		)
		(fill no)
		(layer "In8.Cu")
	)
	(gr_circle
		(center 41.84904 -54.1147)
		(end 42.73804 -54.1147)
		(stroke
			(width 0.2)
			(type default)
		)
		(fill no)
		(layer "In8.Cu")
	)
	(gr_circle
		(center 41.84904 -53.3019)
		(end 42.73804 -53.3019)
		(stroke
			(width 0.2)
			(type default)
		)
		(fill no)
		(layer "In8.Cu")
	)
	(gr_circle
		(center 41.9989 -58.604912)
		(end 42.8879 -58.604912)
		(stroke
			(width 0.2)
			(type default)
		)
		(fill no)
		(layer "In8.Cu")
	)
	(gr_circle
		(center 41.9989 -57.70499)
		(end 42.8879 -57.70499)
		(stroke
			(width 0.2)
			(type default)
		)
		(fill no)
		(layer "In8.Cu")
	)
	(gr_circle
		(center 41.9989 -56.805068)
		(end 42.8879 -56.805068)
		(stroke
			(width 0.2)
			(type default)
		)
		(fill no)
		(layer "In8.Cu")
	)
	(gr_circle
		(center 41.9989 -55.904892)
		(end 42.8879 -55.904892)
		(stroke
			(width 0.2)
			(type default)
		)
		(fill no)
		(layer "In8.Cu")
	)
	(gr_circle
		(center 42.046906 -136.906)
		(end 43.469306 -136.906)
		(stroke
			(width 0.2)
			(type default)
		)
		(fill no)
		(layer "In8.Cu")
	)
	(gr_circle
		(center 42.58564 -54.1147)
		(end 43.47464 -54.1147)
		(stroke
			(width 0.2)
			(type default)
		)
		(fill no)
		(layer "In8.Cu")
	)
	(gr_circle
		(center 42.58564 -53.3019)
		(end 43.47464 -53.3019)
		(stroke
			(width 0.2)
			(type default)
		)
		(fill no)
		(layer "In8.Cu")
	)
	(gr_circle
		(center 42.910506 -131.572)
		(end 43.799506 -131.572)
		(stroke
			(width 0.2)
			(type default)
		)
		(fill no)
		(layer "In8.Cu")
	)
	(gr_circle
		(center 42.910506 -126.492)
		(end 43.799506 -126.492)
		(stroke
			(width 0.2)
			(type default)
		)
		(fill no)
		(layer "In8.Cu")
	)
	(gr_circle
		(center 43.672506 -131.572)
		(end 44.561506 -131.572)
		(stroke
			(width 0.2)
			(type default)
		)
		(fill no)
		(layer "In8.Cu")
	)
	(gr_circle
		(center 43.672506 -126.492)
		(end 44.561506 -126.492)
		(stroke
			(width 0.2)
			(type default)
		)
		(fill no)
		(layer "In8.Cu")
	)
	(gr_circle
		(center 44.36364 -52.2859)
		(end 45.25264 -52.2859)
		(stroke
			(width 0.2)
			(type default)
		)
		(fill no)
		(layer "In8.Cu")
	)
	(gr_circle
		(center 44.36364 -51.4731)
		(end 45.25264 -51.4731)
		(stroke
			(width 0.2)
			(type default)
		)
		(fill no)
		(layer "In8.Cu")
	)
	(gr_circle
		(center 44.84624 -50.0507)
		(end 45.73524 -50.0507)
		(stroke
			(width 0.2)
			(type default)
		)
		(fill no)
		(layer "In8.Cu")
	)
	(gr_circle
		(center 45.58284 -50.0507)
		(end 46.47184 -50.0507)
		(stroke
			(width 0.2)
			(type default)
		)
		(fill no)
		(layer "In8.Cu")
	)
	(gr_circle
		(center 46.29404 -50.0507)
		(end 47.18304 -50.0507)
		(stroke
			(width 0.2)
			(type default)
		)
		(fill no)
		(layer "In8.Cu")
	)
	(gr_circle
		(center 47.05604 -52.9209)
		(end 47.94504 -52.9209)
		(stroke
			(width 0.2)
			(type default)
		)
		(fill no)
		(layer "In8.Cu")
	)
	(gr_circle
		(center 47.05604 -52.1589)
		(end 47.94504 -52.1589)
		(stroke
			(width 0.2)
			(type default)
		)
		(fill no)
		(layer "In8.Cu")
	)
	(gr_circle
		(center 49.31664 -52.8828)
		(end 50.20564 -52.8828)
		(stroke
			(width 0.2)
			(type default)
		)
		(fill no)
		(layer "In8.Cu")
	)
	(gr_circle
		(center 49.31664 -52.1208)
		(end 50.20564 -52.1208)
		(stroke
			(width 0.2)
			(type default)
		)
		(fill no)
		(layer "In8.Cu")
	)
	(gr_circle
		(center 50.07864 -52.8828)
		(end 50.96764 -52.8828)
		(stroke
			(width 0.2)
			(type default)
		)
		(fill no)
		(layer "In8.Cu")
	)
	(gr_circle
		(center 50.07864 -52.1208)
		(end 50.96764 -52.1208)
		(stroke
			(width 0.2)
			(type default)
		)
		(fill no)
		(layer "In8.Cu")
	)
	(gr_circle
		(center 50.84064 -52.8828)
		(end 51.72964 -52.8828)
		(stroke
			(width 0.2)
			(type default)
		)
		(fill no)
		(layer "In8.Cu")
	)
	(gr_circle
		(center 50.84064 -52.1208)
		(end 51.72964 -52.1208)
		(stroke
			(width 0.2)
			(type default)
		)
		(fill no)
		(layer "In8.Cu")
	)
	(gr_circle
		(center 54.238906 -136.906)
		(end 55.661306 -136.906)
		(stroke
			(width 0.2)
			(type default)
		)
		(fill no)
		(layer "In8.Cu")
	)
	(gr_circle
		(center 55.102506 -131.572)
		(end 55.991506 -131.572)
		(stroke
			(width 0.2)
			(type default)
		)
		(fill no)
		(layer "In8.Cu")
	)
	(gr_circle
		(center 55.102506 -126.492)
		(end 55.991506 -126.492)
		(stroke
			(width 0.2)
			(type default)
		)
		(fill no)
		(layer "In8.Cu")
	)
	(gr_circle
		(center 55.864506 -131.572)
		(end 56.753506 -131.572)
		(stroke
			(width 0.2)
			(type default)
		)
		(fill no)
		(layer "In8.Cu")
	)
	(gr_circle
		(center 55.864506 -126.492)
		(end 56.753506 -126.492)
		(stroke
			(width 0.2)
			(type default)
		)
		(fill no)
		(layer "In8.Cu")
	)
	(gr_circle
		(center 62.850014 -77.71765)
		(end 63.739014 -77.71765)
		(stroke
			(width 0.2)
			(type default)
		)
		(fill no)
		(layer "In8.Cu")
	)
	(gr_circle
		(center 64.470026 -121.209816)
		(end 66.286126 -121.209816)
		(stroke
			(width 0.2)
			(type default)
		)
		(fill no)
		(layer "In8.Cu")
	)
	(gr_circle
		(center 64.470026 -70.409816)
		(end 66.667126 -70.409816)
		(stroke
			(width 0.2)
			(type default)
		)
		(fill no)
		(layer "In8.Cu")
	)
	(gr_circle
		(center 66.430906 -136.906)
		(end 67.853306 -136.906)
		(stroke
			(width 0.2)
			(type default)
		)
		(fill no)
		(layer "In8.Cu")
	)
	(gr_circle
		(center 67.294506 -131.572)
		(end 68.183506 -131.572)
		(stroke
			(width 0.2)
			(type default)
		)
		(fill no)
		(layer "In8.Cu")
	)
	(gr_circle
		(center 67.294506 -126.492)
		(end 68.183506 -126.492)
		(stroke
			(width 0.2)
			(type default)
		)
		(fill no)
		(layer "In8.Cu")
	)
	(gr_circle
		(center 68.056506 -131.572)
		(end 68.945506 -131.572)
		(stroke
			(width 0.2)
			(type default)
		)
		(fill no)
		(layer "In8.Cu")
	)
	(gr_circle
		(center 68.056506 -126.492)
		(end 68.945506 -126.492)
		(stroke
			(width 0.2)
			(type default)
		)
		(fill no)
		(layer "In8.Cu")
	)
	(gr_circle
		(center 68.072 -60.96)
		(end 69.469 -60.96)
		(stroke
			(width 0.2)
			(type default)
		)
		(fill no)
		(layer "In8.Cu")
	)
	(gr_circle
		(center 68.280026 -70.409816)
		(end 70.477126 -70.409816)
		(stroke
			(width 0.2)
			(type default)
		)
		(fill no)
		(layer "In8.Cu")
	)
	(gr_circle
		(center 70.413626 -71.901812)
		(end 71.302626 -71.901812)
		(stroke
			(width 0.2)
			(type default)
		)
		(fill no)
		(layer "In8.Cu")
	)
	(gr_circle
		(center 70.413626 -70.885812)
		(end 71.302626 -70.885812)
		(stroke
			(width 0.2)
			(type default)
		)
		(fill no)
		(layer "In8.Cu")
	)
	(gr_circle
		(center 70.413626 -69.869812)
		(end 71.302626 -69.869812)
		(stroke
			(width 0.2)
			(type default)
		)
		(fill no)
		(layer "In8.Cu")
	)
	(gr_circle
		(center 70.413626 -68.853812)
		(end 71.302626 -68.853812)
		(stroke
			(width 0.2)
			(type default)
		)
		(fill no)
		(layer "In8.Cu")
	)
	(gr_circle
		(center 71.429626 -71.901812)
		(end 72.318626 -71.901812)
		(stroke
			(width 0.2)
			(type default)
		)
		(fill no)
		(layer "In8.Cu")
	)
	(gr_circle
		(center 71.429626 -70.885812)
		(end 72.318626 -70.885812)
		(stroke
			(width 0.2)
			(type default)
		)
		(fill no)
		(layer "In8.Cu")
	)
	(gr_circle
		(center 71.429626 -69.869812)
		(end 72.318626 -69.869812)
		(stroke
			(width 0.2)
			(type default)
		)
		(fill no)
		(layer "In8.Cu")
	)
	(gr_circle
		(center 71.429626 -68.853812)
		(end 72.318626 -68.853812)
		(stroke
			(width 0.2)
			(type default)
		)
		(fill no)
		(layer "In8.Cu")
	)
	(gr_circle
		(center 71.882 -52.324)
		(end 72.771 -52.324)
		(stroke
			(width 0.2)
			(type default)
		)
		(fill no)
		(layer "In8.Cu")
	)
	(gr_circle
		(center 71.882 -51.689)
		(end 72.771 -51.689)
		(stroke
			(width 0.2)
			(type default)
		)
		(fill no)
		(layer "In8.Cu")
	)
	(gr_circle
		(center 71.882 -50.419)
		(end 72.771 -50.419)
		(stroke
			(width 0.2)
			(type default)
		)
		(fill no)
		(layer "In8.Cu")
	)
	(gr_circle
		(center 71.882 -49.784)
		(end 72.771 -49.784)
		(stroke
			(width 0.2)
			(type default)
		)
		(fill no)
		(layer "In8.Cu")
	)
	(gr_circle
		(center 72.445626 -71.901812)
		(end 73.334626 -71.901812)
		(stroke
			(width 0.2)
			(type default)
		)
		(fill no)
		(layer "In8.Cu")
	)
	(gr_circle
		(center 72.445626 -70.885812)
		(end 73.334626 -70.885812)
		(stroke
			(width 0.2)
			(type default)
		)
		(fill no)
		(layer "In8.Cu")
	)
	(gr_circle
		(center 72.445626 -69.869812)
		(end 73.334626 -69.869812)
		(stroke
			(width 0.2)
			(type default)
		)
		(fill no)
		(layer "In8.Cu")
	)
	(gr_circle
		(center 72.445626 -68.853812)
		(end 73.334626 -68.853812)
		(stroke
			(width 0.2)
			(type default)
		)
		(fill no)
		(layer "In8.Cu")
	)
	(gr_circle
		(center 77.343 -52.324)
		(end 78.232 -52.324)
		(stroke
			(width 0.2)
			(type default)
		)
		(fill no)
		(layer "In8.Cu")
	)
	(gr_circle
		(center 77.343 -51.689)
		(end 78.232 -51.689)
		(stroke
			(width 0.2)
			(type default)
		)
		(fill no)
		(layer "In8.Cu")
	)
	(gr_circle
		(center 77.343 -50.419)
		(end 78.232 -50.419)
		(stroke
			(width 0.2)
			(type default)
		)
		(fill no)
		(layer "In8.Cu")
	)
	(gr_circle
		(center 77.343 -49.784)
		(end 78.232 -49.784)
		(stroke
			(width 0.2)
			(type default)
		)
		(fill no)
		(layer "In8.Cu")
	)
	(gr_circle
		(center 79.375 -60.96)
		(end 80.772 -60.96)
		(stroke
			(width 0.2)
			(type default)
		)
		(fill no)
		(layer "In8.Cu")
	)
	(gr_circle
		(center 82.046826 -136.906)
		(end 83.469226 -136.906)
		(stroke
			(width 0.2)
			(type default)
		)
		(fill no)
		(layer "In8.Cu")
	)
	(gr_circle
		(center 82.804 -52.324)
		(end 83.693 -52.324)
		(stroke
			(width 0.2)
			(type default)
		)
		(fill no)
		(layer "In8.Cu")
	)
	(gr_circle
		(center 82.804 -51.689)
		(end 83.693 -51.689)
		(stroke
			(width 0.2)
			(type default)
		)
		(fill no)
		(layer "In8.Cu")
	)
	(gr_circle
		(center 82.804 -50.419)
		(end 83.693 -50.419)
		(stroke
			(width 0.2)
			(type default)
		)
		(fill no)
		(layer "In8.Cu")
	)
	(gr_circle
		(center 82.804 -49.784)
		(end 83.693 -49.784)
		(stroke
			(width 0.2)
			(type default)
		)
		(fill no)
		(layer "In8.Cu")
	)
	(gr_circle
		(center 82.910426 -131.572)
		(end 83.799426 -131.572)
		(stroke
			(width 0.2)
			(type default)
		)
		(fill no)
		(layer "In8.Cu")
	)
	(gr_circle
		(center 82.910426 -126.492)
		(end 83.799426 -126.492)
		(stroke
			(width 0.2)
			(type default)
		)
		(fill no)
		(layer "In8.Cu")
	)
	(gr_circle
		(center 83.672426 -131.572)
		(end 84.561426 -131.572)
		(stroke
			(width 0.2)
			(type default)
		)
		(fill no)
		(layer "In8.Cu")
	)
	(gr_circle
		(center 83.672426 -126.492)
		(end 84.561426 -126.492)
		(stroke
			(width 0.2)
			(type default)
		)
		(fill no)
		(layer "In8.Cu")
	)
	(gr_circle
		(center 88.265 -52.324)
		(end 89.154 -52.324)
		(stroke
			(width 0.2)
			(type default)
		)
		(fill no)
		(layer "In8.Cu")
	)
	(gr_circle
		(center 88.265 -51.689)
		(end 89.154 -51.689)
		(stroke
			(width 0.2)
			(type default)
		)
		(fill no)
		(layer "In8.Cu")
	)
	(gr_circle
		(center 88.265 -50.419)
		(end 89.154 -50.419)
		(stroke
			(width 0.2)
			(type default)
		)
		(fill no)
		(layer "In8.Cu")
	)
	(gr_circle
		(center 88.265 -49.784)
		(end 89.154 -49.784)
		(stroke
			(width 0.2)
			(type default)
		)
		(fill no)
		(layer "In8.Cu")
	)
	(gr_circle
		(center 90.678 -60.96)
		(end 92.075 -60.96)
		(stroke
			(width 0.2)
			(type default)
		)
		(fill no)
		(layer "In8.Cu")
	)
	(gr_circle
		(center 93.726 -52.324)
		(end 94.615 -52.324)
		(stroke
			(width 0.2)
			(type default)
		)
		(fill no)
		(layer "In8.Cu")
	)
	(gr_circle
		(center 93.726 -51.689)
		(end 94.615 -51.689)
		(stroke
			(width 0.2)
			(type default)
		)
		(fill no)
		(layer "In8.Cu")
	)
	(gr_circle
		(center 93.726 -50.419)
		(end 94.615 -50.419)
		(stroke
			(width 0.2)
			(type default)
		)
		(fill no)
		(layer "In8.Cu")
	)
	(gr_circle
		(center 93.726 -49.784)
		(end 94.615 -49.784)
		(stroke
			(width 0.2)
			(type default)
		)
		(fill no)
		(layer "In8.Cu")
	)
	(gr_circle
		(center 94.238826 -136.906)
		(end 95.661226 -136.906)
		(stroke
			(width 0.2)
			(type default)
		)
		(fill no)
		(layer "In8.Cu")
	)
	(gr_circle
		(center 95.102426 -131.572)
		(end 95.991426 -131.572)
		(stroke
			(width 0.2)
			(type default)
		)
		(fill no)
		(layer "In8.Cu")
	)
	(gr_circle
		(center 95.102426 -126.492)
		(end 95.991426 -126.492)
		(stroke
			(width 0.2)
			(type default)
		)
		(fill no)
		(layer "In8.Cu")
	)
	(gr_circle
		(center 95.864426 -131.572)
		(end 96.753426 -131.572)
		(stroke
			(width 0.2)
			(type default)
		)
		(fill no)
		(layer "In8.Cu")
	)
	(gr_circle
		(center 95.864426 -126.492)
		(end 96.753426 -126.492)
		(stroke
			(width 0.2)
			(type default)
		)
		(fill no)
		(layer "In8.Cu")
	)
	(gr_circle
		(center 99.187 -52.324)
		(end 100.076 -52.324)
		(stroke
			(width 0.2)
			(type default)
		)
		(fill no)
		(layer "In8.Cu")
	)
	(gr_circle
		(center 99.187 -51.689)
		(end 100.076 -51.689)
		(stroke
			(width 0.2)
			(type default)
		)
		(fill no)
		(layer "In8.Cu")
	)
	(gr_circle
		(center 99.187 -50.419)
		(end 100.076 -50.419)
		(stroke
			(width 0.2)
			(type default)
		)
		(fill no)
		(layer "In8.Cu")
	)
	(gr_circle
		(center 99.187 -49.784)
		(end 100.076 -49.784)
		(stroke
			(width 0.2)
			(type default)
		)
		(fill no)
		(layer "In8.Cu")
	)
	(gr_circle
		(center 102.045008 -40.55999)
		(end 103.44404 -40.55999)
		(stroke
			(width 0.2)
			(type default)
		)
		(fill no)
		(layer "In8.Cu")
	)
	(gr_circle
		(center 102.045008 -38.01999)
		(end 103.44404 -38.01999)
		(stroke
			(width 0.2)
			(type default)
		)
		(fill no)
		(layer "In8.Cu")
	)
	(gr_circle
		(center 102.045008 -35.47999)
		(end 103.44404 -35.47999)
		(stroke
			(width 0.2)
			(type default)
		)
		(fill no)
		(layer "In8.Cu")
	)
	(gr_circle
		(center 102.045008 -32.93999)
		(end 103.44404 -32.93999)
		(stroke
			(width 0.2)
			(type default)
		)
		(fill no)
		(layer "In8.Cu")
	)
	(gr_circle
		(center 102.849934 -77.71765)
		(end 103.738934 -77.71765)
		(stroke
			(width 0.2)
			(type default)
		)
		(fill no)
		(layer "In8.Cu")
	)
	(gr_circle
		(center 103.315008 -39.34079)
		(end 104.71404 -39.34079)
		(stroke
			(width 0.2)
			(type default)
		)
		(fill no)
		(layer "In8.Cu")
	)
	(gr_circle
		(center 103.315008 -36.80079)
		(end 104.71404 -36.80079)
		(stroke
			(width 0.2)
			(type default)
		)
		(fill no)
		(layer "In8.Cu")
	)
	(gr_circle
		(center 103.315008 -34.26079)
		(end 104.71404 -34.26079)
		(stroke
			(width 0.2)
			(type default)
		)
		(fill no)
		(layer "In8.Cu")
	)
	(gr_circle
		(center 104.469946 -121.209816)
		(end 106.286046 -121.209816)
		(stroke
			(width 0.2)
			(type default)
		)
		(fill no)
		(layer "In8.Cu")
	)
	(gr_circle
		(center 104.469946 -70.409816)
		(end 106.667046 -70.409816)
		(stroke
			(width 0.2)
			(type default)
		)
		(fill no)
		(layer "In8.Cu")
	)
	(gr_circle
		(center 104.585008 -40.55999)
		(end 105.98404 -40.55999)
		(stroke
			(width 0.2)
			(type default)
		)
		(fill no)
		(layer "In8.Cu")
	)
	(gr_circle
		(center 104.585008 -38.01999)
		(end 105.98404 -38.01999)
		(stroke
			(width 0.2)
			(type default)
		)
		(fill no)
		(layer "In8.Cu")
	)
	(gr_circle
		(center 104.585008 -35.47999)
		(end 105.98404 -35.47999)
		(stroke
			(width 0.2)
			(type default)
		)
		(fill no)
		(layer "In8.Cu")
	)
	(gr_circle
		(center 104.585008 -32.93999)
		(end 105.98404 -32.93999)
		(stroke
			(width 0.2)
			(type default)
		)
		(fill no)
		(layer "In8.Cu")
	)
	(gr_circle
		(center 104.648 -52.324)
		(end 105.537 -52.324)
		(stroke
			(width 0.2)
			(type default)
		)
		(fill no)
		(layer "In8.Cu")
	)
	(gr_circle
		(center 104.648 -51.689)
		(end 105.537 -51.689)
		(stroke
			(width 0.2)
			(type default)
		)
		(fill no)
		(layer "In8.Cu")
	)
	(gr_circle
		(center 104.648 -50.419)
		(end 105.537 -50.419)
		(stroke
			(width 0.2)
			(type default)
		)
		(fill no)
		(layer "In8.Cu")
	)
	(gr_circle
		(center 104.648 -49.784)
		(end 105.537 -49.784)
		(stroke
			(width 0.2)
			(type default)
		)
		(fill no)
		(layer "In8.Cu")
	)
	(gr_circle
		(center 106.430826 -136.906)
		(end 107.853226 -136.906)
		(stroke
			(width 0.2)
			(type default)
		)
		(fill no)
		(layer "In8.Cu")
	)
	(gr_circle
		(center 107.294426 -131.572)
		(end 108.183426 -131.572)
		(stroke
			(width 0.2)
			(type default)
		)
		(fill no)
		(layer "In8.Cu")
	)
	(gr_circle
		(center 107.294426 -126.492)
		(end 108.183426 -126.492)
		(stroke
			(width 0.2)
			(type default)
		)
		(fill no)
		(layer "In8.Cu")
	)
	(gr_circle
		(center 108.056426 -131.572)
		(end 108.945426 -131.572)
		(stroke
			(width 0.2)
			(type default)
		)
		(fill no)
		(layer "In8.Cu")
	)
	(gr_circle
		(center 108.056426 -126.492)
		(end 108.945426 -126.492)
		(stroke
			(width 0.2)
			(type default)
		)
		(fill no)
		(layer "In8.Cu")
	)
	(gr_circle
		(center 108.279946 -70.409816)
		(end 110.477046 -70.409816)
		(stroke
			(width 0.2)
			(type default)
		)
		(fill no)
		(layer "In8.Cu")
	)
	(gr_circle
		(center 108.839 -60.96)
		(end 110.236 -60.96)
		(stroke
			(width 0.2)
			(type default)
		)
		(fill no)
		(layer "In8.Cu")
	)
	(gr_circle
		(center 110.362746 -71.929244)
		(end 111.251746 -71.929244)
		(stroke
			(width 0.2)
			(type default)
		)
		(fill no)
		(layer "In8.Cu")
	)
	(gr_circle
		(center 110.362746 -70.913244)
		(end 111.251746 -70.913244)
		(stroke
			(width 0.2)
			(type default)
		)
		(fill no)
		(layer "In8.Cu")
	)
	(gr_circle
		(center 110.362746 -69.897244)
		(end 111.251746 -69.897244)
		(stroke
			(width 0.2)
			(type default)
		)
		(fill no)
		(layer "In8.Cu")
	)
	(gr_circle
		(center 110.362746 -68.881244)
		(end 111.251746 -68.881244)
		(stroke
			(width 0.2)
			(type default)
		)
		(fill no)
		(layer "In8.Cu")
	)
	(gr_circle
		(center 110.935008 -40.55999)
		(end 112.33404 -40.55999)
		(stroke
			(width 0.2)
			(type default)
		)
		(fill no)
		(layer "In8.Cu")
	)
	(gr_circle
		(center 110.935008 -38.01999)
		(end 112.33404 -38.01999)
		(stroke
			(width 0.2)
			(type default)
		)
		(fill no)
		(layer "In8.Cu")
	)
	(gr_circle
		(center 110.935008 -35.47999)
		(end 112.33404 -35.47999)
		(stroke
			(width 0.2)
			(type default)
		)
		(fill no)
		(layer "In8.Cu")
	)
	(gr_circle
		(center 110.935008 -32.93999)
		(end 112.33404 -32.93999)
		(stroke
			(width 0.2)
			(type default)
		)
		(fill no)
		(layer "In8.Cu")
	)
	(gr_circle
		(center 111.378746 -71.929244)
		(end 112.267746 -71.929244)
		(stroke
			(width 0.2)
			(type default)
		)
		(fill no)
		(layer "In8.Cu")
	)
	(gr_circle
		(center 111.378746 -70.913244)
		(end 112.267746 -70.913244)
		(stroke
			(width 0.2)
			(type default)
		)
		(fill no)
		(layer "In8.Cu")
	)
	(gr_circle
		(center 111.378746 -69.897244)
		(end 112.267746 -69.897244)
		(stroke
			(width 0.2)
			(type default)
		)
		(fill no)
		(layer "In8.Cu")
	)
	(gr_circle
		(center 111.378746 -68.881244)
		(end 112.267746 -68.881244)
		(stroke
			(width 0.2)
			(type default)
		)
		(fill no)
		(layer "In8.Cu")
	)
	(gr_circle
		(center 112.281208 -39.44239)
		(end 113.68024 -39.44239)
		(stroke
			(width 0.2)
			(type default)
		)
		(fill no)
		(layer "In8.Cu")
	)
	(gr_circle
		(center 112.281208 -36.90239)
		(end 113.68024 -36.90239)
		(stroke
			(width 0.2)
			(type default)
		)
		(fill no)
		(layer "In8.Cu")
	)
	(gr_circle
		(center 112.281208 -34.36239)
		(end 113.68024 -34.36239)
		(stroke
			(width 0.2)
			(type default)
		)
		(fill no)
		(layer "In8.Cu")
	)
	(gr_circle
		(center 112.394746 -71.929244)
		(end 113.283746 -71.929244)
		(stroke
			(width 0.2)
			(type default)
		)
		(fill no)
		(layer "In8.Cu")
	)
	(gr_circle
		(center 112.394746 -70.913244)
		(end 113.283746 -70.913244)
		(stroke
			(width 0.2)
			(type default)
		)
		(fill no)
		(layer "In8.Cu")
	)
	(gr_circle
		(center 112.394746 -69.897244)
		(end 113.283746 -69.897244)
		(stroke
			(width 0.2)
			(type default)
		)
		(fill no)
		(layer "In8.Cu")
	)
	(gr_circle
		(center 112.394746 -68.881244)
		(end 113.283746 -68.881244)
		(stroke
			(width 0.2)
			(type default)
		)
		(fill no)
		(layer "In8.Cu")
	)
	(gr_circle
		(center 113.475008 -40.55999)
		(end 114.87404 -40.55999)
		(stroke
			(width 0.2)
			(type default)
		)
		(fill no)
		(layer "In8.Cu")
	)
	(gr_circle
		(center 113.475008 -38.01999)
		(end 114.87404 -38.01999)
		(stroke
			(width 0.2)
			(type default)
		)
		(fill no)
		(layer "In8.Cu")
	)
	(gr_circle
		(center 113.475008 -35.47999)
		(end 114.87404 -35.47999)
		(stroke
			(width 0.2)
			(type default)
		)
		(fill no)
		(layer "In8.Cu")
	)
	(gr_circle
		(center 113.475008 -32.93999)
		(end 114.87404 -32.93999)
		(stroke
			(width 0.2)
			(type default)
		)
		(fill no)
		(layer "In8.Cu")
	)
	(gr_circle
		(center 119.825008 -40.55999)
		(end 121.22404 -40.55999)
		(stroke
			(width 0.2)
			(type default)
		)
		(fill no)
		(layer "In8.Cu")
	)
	(gr_circle
		(center 119.825008 -38.01999)
		(end 121.22404 -38.01999)
		(stroke
			(width 0.2)
			(type default)
		)
		(fill no)
		(layer "In8.Cu")
	)
	(gr_circle
		(center 119.825008 -35.47999)
		(end 121.22404 -35.47999)
		(stroke
			(width 0.2)
			(type default)
		)
		(fill no)
		(layer "In8.Cu")
	)
	(gr_circle
		(center 119.825008 -32.93999)
		(end 121.22404 -32.93999)
		(stroke
			(width 0.2)
			(type default)
		)
		(fill no)
		(layer "In8.Cu")
	)
	(gr_circle
		(center 120.015 -60.96)
		(end 121.412 -60.96)
		(stroke
			(width 0.2)
			(type default)
		)
		(fill no)
		(layer "In8.Cu")
	)
	(gr_circle
		(center 121.095008 -39.39159)
		(end 122.49404 -39.39159)
		(stroke
			(width 0.2)
			(type default)
		)
		(fill no)
		(layer "In8.Cu")
	)
	(gr_circle
		(center 121.095008 -36.85159)
		(end 122.49404 -36.85159)
		(stroke
			(width 0.2)
			(type default)
		)
		(fill no)
		(layer "In8.Cu")
	)
	(gr_circle
		(center 121.095008 -34.31159)
		(end 122.49404 -34.31159)
		(stroke
			(width 0.2)
			(type default)
		)
		(fill no)
		(layer "In8.Cu")
	)
	(gr_circle
		(center 122.047 -136.906)
		(end 123.4694 -136.906)
		(stroke
			(width 0.2)
			(type default)
		)
		(fill no)
		(layer "In8.Cu")
	)
	(gr_circle
		(center 122.365008 -40.55999)
		(end 123.76404 -40.55999)
		(stroke
			(width 0.2)
			(type default)
		)
		(fill no)
		(layer "In8.Cu")
	)
	(gr_circle
		(center 122.365008 -38.01999)
		(end 123.76404 -38.01999)
		(stroke
			(width 0.2)
			(type default)
		)
		(fill no)
		(layer "In8.Cu")
	)
	(gr_circle
		(center 122.365008 -35.47999)
		(end 123.76404 -35.47999)
		(stroke
			(width 0.2)
			(type default)
		)
		(fill no)
		(layer "In8.Cu")
	)
	(gr_circle
		(center 122.365008 -32.93999)
		(end 123.76404 -32.93999)
		(stroke
			(width 0.2)
			(type default)
		)
		(fill no)
		(layer "In8.Cu")
	)
	(gr_circle
		(center 122.9106 -131.572)
		(end 123.7996 -131.572)
		(stroke
			(width 0.2)
			(type default)
		)
		(fill no)
		(layer "In8.Cu")
	)
	(gr_circle
		(center 122.9106 -126.492)
		(end 123.7996 -126.492)
		(stroke
			(width 0.2)
			(type default)
		)
		(fill no)
		(layer "In8.Cu")
	)
	(gr_circle
		(center 123.6726 -131.572)
		(end 124.5616 -131.572)
		(stroke
			(width 0.2)
			(type default)
		)
		(fill no)
		(layer "In8.Cu")
	)
	(gr_circle
		(center 123.6726 -126.492)
		(end 124.5616 -126.492)
		(stroke
			(width 0.2)
			(type default)
		)
		(fill no)
		(layer "In8.Cu")
	)
	(gr_circle
		(center 131.191 -60.96)
		(end 132.588 -60.96)
		(stroke
			(width 0.2)
			(type default)
		)
		(fill no)
		(layer "In8.Cu")
	)
	(gr_circle
		(center 134.239 -136.906)
		(end 135.6614 -136.906)
		(stroke
			(width 0.2)
			(type default)
		)
		(fill no)
		(layer "In8.Cu")
	)
	(gr_circle
		(center 135.1026 -131.572)
		(end 135.9916 -131.572)
		(stroke
			(width 0.2)
			(type default)
		)
		(fill no)
		(layer "In8.Cu")
	)
	(gr_circle
		(center 135.1026 -126.492)
		(end 135.9916 -126.492)
		(stroke
			(width 0.2)
			(type default)
		)
		(fill no)
		(layer "In8.Cu")
	)
	(gr_circle
		(center 135.8646 -131.572)
		(end 136.7536 -131.572)
		(stroke
			(width 0.2)
			(type default)
		)
		(fill no)
		(layer "In8.Cu")
	)
	(gr_circle
		(center 135.8646 -126.492)
		(end 136.7536 -126.492)
		(stroke
			(width 0.2)
			(type default)
		)
		(fill no)
		(layer "In8.Cu")
	)
	(gr_circle
		(center 142.748 -112.268)
		(end 143.637 -112.268)
		(stroke
			(width 0.2)
			(type default)
		)
		(fill no)
		(layer "In8.Cu")
	)
	(gr_circle
		(center 142.850108 -77.71765)
		(end 143.739108 -77.71765)
		(stroke
			(width 0.2)
			(type default)
		)
		(fill no)
		(layer "In8.Cu")
	)
	(gr_circle
		(center 143.383 -112.268)
		(end 144.272 -112.268)
		(stroke
			(width 0.2)
			(type default)
		)
		(fill no)
		(layer "In8.Cu")
	)
	(gr_circle
		(center 144.47012 -121.209816)
		(end 146.28622 -121.209816)
		(stroke
			(width 0.2)
			(type default)
		)
		(fill no)
		(layer "In8.Cu")
	)
	(gr_circle
		(center 144.47012 -70.409816)
		(end 146.66722 -70.409816)
		(stroke
			(width 0.2)
			(type default)
		)
		(fill no)
		(layer "In8.Cu")
	)
	(gr_circle
		(center 146.431 -136.906)
		(end 147.8534 -136.906)
		(stroke
			(width 0.2)
			(type default)
		)
		(fill no)
		(layer "In8.Cu")
	)
	(gr_circle
		(center 146.939 -60.96)
		(end 148.336 -60.96)
		(stroke
			(width 0.2)
			(type default)
		)
		(fill no)
		(layer "In8.Cu")
	)
	(gr_circle
		(center 147.2946 -131.572)
		(end 148.1836 -131.572)
		(stroke
			(width 0.2)
			(type default)
		)
		(fill no)
		(layer "In8.Cu")
	)
	(gr_circle
		(center 147.2946 -126.492)
		(end 148.1836 -126.492)
		(stroke
			(width 0.2)
			(type default)
		)
		(fill no)
		(layer "In8.Cu")
	)
	(gr_circle
		(center 148.0566 -131.572)
		(end 148.9456 -131.572)
		(stroke
			(width 0.2)
			(type default)
		)
		(fill no)
		(layer "In8.Cu")
	)
	(gr_circle
		(center 148.0566 -126.492)
		(end 148.9456 -126.492)
		(stroke
			(width 0.2)
			(type default)
		)
		(fill no)
		(layer "In8.Cu")
	)
	(gr_circle
		(center 148.28012 -70.409816)
		(end 150.47722 -70.409816)
		(stroke
			(width 0.2)
			(type default)
		)
		(fill no)
		(layer "In8.Cu")
	)
	(gr_circle
		(center 149.987 -52.197)
		(end 150.876 -52.197)
		(stroke
			(width 0.2)
			(type default)
		)
		(fill no)
		(layer "In8.Cu")
	)
	(gr_circle
		(center 149.987 -51.562)
		(end 150.876 -51.562)
		(stroke
			(width 0.2)
			(type default)
		)
		(fill no)
		(layer "In8.Cu")
	)
	(gr_circle
		(center 149.987 -50.292)
		(end 150.876 -50.292)
		(stroke
			(width 0.2)
			(type default)
		)
		(fill no)
		(layer "In8.Cu")
	)
	(gr_circle
		(center 149.987 -49.657)
		(end 150.876 -49.657)
		(stroke
			(width 0.2)
			(type default)
		)
		(fill no)
		(layer "In8.Cu")
	)
	(gr_circle
		(center 155.448 -52.197)
		(end 156.337 -52.197)
		(stroke
			(width 0.2)
			(type default)
		)
		(fill no)
		(layer "In8.Cu")
	)
	(gr_circle
		(center 155.448 -51.562)
		(end 156.337 -51.562)
		(stroke
			(width 0.2)
			(type default)
		)
		(fill no)
		(layer "In8.Cu")
	)
	(gr_circle
		(center 155.448 -50.292)
		(end 156.337 -50.292)
		(stroke
			(width 0.2)
			(type default)
		)
		(fill no)
		(layer "In8.Cu")
	)
	(gr_circle
		(center 155.448 -49.657)
		(end 156.337 -49.657)
		(stroke
			(width 0.2)
			(type default)
		)
		(fill no)
		(layer "In8.Cu")
	)
	(gr_circle
		(center 158.115 -60.96)
		(end 159.512 -60.96)
		(stroke
			(width 0.2)
			(type default)
		)
		(fill no)
		(layer "In8.Cu")
	)
	(gr_circle
		(center 160.909 -52.197)
		(end 161.798 -52.197)
		(stroke
			(width 0.2)
			(type default)
		)
		(fill no)
		(layer "In8.Cu")
	)
	(gr_circle
		(center 160.909 -51.562)
		(end 161.798 -51.562)
		(stroke
			(width 0.2)
			(type default)
		)
		(fill no)
		(layer "In8.Cu")
	)
	(gr_circle
		(center 160.909 -50.292)
		(end 161.798 -50.292)
		(stroke
			(width 0.2)
			(type default)
		)
		(fill no)
		(layer "In8.Cu")
	)
	(gr_circle
		(center 160.909 -49.657)
		(end 161.798 -49.657)
		(stroke
			(width 0.2)
			(type default)
		)
		(fill no)
		(layer "In8.Cu")
	)
	(gr_circle
		(center 162.047174 -136.906)
		(end 163.469574 -136.906)
		(stroke
			(width 0.2)
			(type default)
		)
		(fill no)
		(layer "In8.Cu")
	)
	(gr_circle
		(center 162.1028 -11.811)
		(end 162.9918 -11.811)
		(stroke
			(width 0.2)
			(type default)
		)
		(fill no)
		(layer "In8.Cu")
	)
	(gr_circle
		(center 162.1028 -11.176)
		(end 162.9918 -11.176)
		(stroke
			(width 0.2)
			(type default)
		)
		(fill no)
		(layer "In8.Cu")
	)
	(gr_circle
		(center 162.7886 -10.7442)
		(end 163.6776 -10.7442)
		(stroke
			(width 0.2)
			(type default)
		)
		(fill no)
		(layer "In8.Cu")
	)
	(gr_circle
		(center 162.8394 -12.2174)
		(end 163.7284 -12.2174)
		(stroke
			(width 0.2)
			(type default)
		)
		(fill no)
		(layer "In8.Cu")
	)
	(gr_circle
		(center 162.910774 -131.572)
		(end 163.799774 -131.572)
		(stroke
			(width 0.2)
			(type default)
		)
		(fill no)
		(layer "In8.Cu")
	)
	(gr_circle
		(center 162.910774 -126.492)
		(end 163.799774 -126.492)
		(stroke
			(width 0.2)
			(type default)
		)
		(fill no)
		(layer "In8.Cu")
	)
	(gr_circle
		(center 163.672774 -131.572)
		(end 164.561774 -131.572)
		(stroke
			(width 0.2)
			(type default)
		)
		(fill no)
		(layer "In8.Cu")
	)
	(gr_circle
		(center 163.672774 -126.492)
		(end 164.561774 -126.492)
		(stroke
			(width 0.2)
			(type default)
		)
		(fill no)
		(layer "In8.Cu")
	)
	(gr_circle
		(center 166.37 -52.197)
		(end 167.259 -52.197)
		(stroke
			(width 0.2)
			(type default)
		)
		(fill no)
		(layer "In8.Cu")
	)
	(gr_circle
		(center 166.37 -51.562)
		(end 167.259 -51.562)
		(stroke
			(width 0.2)
			(type default)
		)
		(fill no)
		(layer "In8.Cu")
	)
	(gr_circle
		(center 166.37 -50.292)
		(end 167.259 -50.292)
		(stroke
			(width 0.2)
			(type default)
		)
		(fill no)
		(layer "In8.Cu")
	)
	(gr_circle
		(center 166.37 -49.657)
		(end 167.259 -49.657)
		(stroke
			(width 0.2)
			(type default)
		)
		(fill no)
		(layer "In8.Cu")
	)
	(gr_circle
		(center 169.291 -60.96)
		(end 170.688 -60.96)
		(stroke
			(width 0.2)
			(type default)
		)
		(fill no)
		(layer "In8.Cu")
	)
	(gr_circle
		(center 171.831 -52.197)
		(end 172.72 -52.197)
		(stroke
			(width 0.2)
			(type default)
		)
		(fill no)
		(layer "In8.Cu")
	)
	(gr_circle
		(center 171.831 -51.562)
		(end 172.72 -51.562)
		(stroke
			(width 0.2)
			(type default)
		)
		(fill no)
		(layer "In8.Cu")
	)
	(gr_circle
		(center 171.831 -50.292)
		(end 172.72 -50.292)
		(stroke
			(width 0.2)
			(type default)
		)
		(fill no)
		(layer "In8.Cu")
	)
	(gr_circle
		(center 171.831 -49.657)
		(end 172.72 -49.657)
		(stroke
			(width 0.2)
			(type default)
		)
		(fill no)
		(layer "In8.Cu")
	)
	(gr_circle
		(center 174.239174 -136.906)
		(end 175.661574 -136.906)
		(stroke
			(width 0.2)
			(type default)
		)
		(fill no)
		(layer "In8.Cu")
	)
	(gr_circle
		(center 175.102774 -131.572)
		(end 175.991774 -131.572)
		(stroke
			(width 0.2)
			(type default)
		)
		(fill no)
		(layer "In8.Cu")
	)
	(gr_circle
		(center 175.102774 -126.492)
		(end 175.991774 -126.492)
		(stroke
			(width 0.2)
			(type default)
		)
		(fill no)
		(layer "In8.Cu")
	)
	(gr_circle
		(center 175.864774 -131.572)
		(end 176.753774 -131.572)
		(stroke
			(width 0.2)
			(type default)
		)
		(fill no)
		(layer "In8.Cu")
	)
	(gr_circle
		(center 175.864774 -126.492)
		(end 176.753774 -126.492)
		(stroke
			(width 0.2)
			(type default)
		)
		(fill no)
		(layer "In8.Cu")
	)
	(gr_circle
		(center 177.28946 -52.197)
		(end 178.17846 -52.197)
		(stroke
			(width 0.2)
			(type default)
		)
		(fill no)
		(layer "In8.Cu")
	)
	(gr_circle
		(center 177.28946 -51.562)
		(end 178.17846 -51.562)
		(stroke
			(width 0.2)
			(type default)
		)
		(fill no)
		(layer "In8.Cu")
	)
	(gr_circle
		(center 177.28946 -50.292)
		(end 178.17846 -50.292)
		(stroke
			(width 0.2)
			(type default)
		)
		(fill no)
		(layer "In8.Cu")
	)
	(gr_circle
		(center 177.28946 -49.657)
		(end 178.17846 -49.657)
		(stroke
			(width 0.2)
			(type default)
		)
		(fill no)
		(layer "In8.Cu")
	)
	(gr_circle
		(center 180.989986 -37.949632)
		(end 182.389018 -37.949632)
		(stroke
			(width 0.2)
			(type default)
		)
		(fill no)
		(layer "In8.Cu")
	)
	(gr_circle
		(center 180.989986 -35.409632)
		(end 182.389018 -35.409632)
		(stroke
			(width 0.2)
			(type default)
		)
		(fill no)
		(layer "In8.Cu")
	)
	(gr_circle
		(center 180.989986 -32.869632)
		(end 182.389018 -32.869632)
		(stroke
			(width 0.2)
			(type default)
		)
		(fill no)
		(layer "In8.Cu")
	)
	(gr_circle
		(center 180.989986 -30.329632)
		(end 182.389018 -30.329632)
		(stroke
			(width 0.2)
			(type default)
		)
		(fill no)
		(layer "In8.Cu")
	)
	(gr_circle
		(center 182.132986 -36.679632)
		(end 183.532018 -36.679632)
		(stroke
			(width 0.2)
			(type default)
		)
		(fill no)
		(layer "In8.Cu")
	)
	(gr_circle
		(center 182.132986 -31.599632)
		(end 183.532018 -31.599632)
		(stroke
			(width 0.2)
			(type default)
		)
		(fill no)
		(layer "In8.Cu")
	)
	(gr_circle
		(center 182.259986 -34.266632)
		(end 183.659018 -34.266632)
		(stroke
			(width 0.2)
			(type default)
		)
		(fill no)
		(layer "In8.Cu")
	)
	(gr_circle
		(center 182.75046 -52.197)
		(end 183.63946 -52.197)
		(stroke
			(width 0.2)
			(type default)
		)
		(fill no)
		(layer "In8.Cu")
	)
	(gr_circle
		(center 182.75046 -51.562)
		(end 183.63946 -51.562)
		(stroke
			(width 0.2)
			(type default)
		)
		(fill no)
		(layer "In8.Cu")
	)
	(gr_circle
		(center 182.75046 -50.292)
		(end 183.63946 -50.292)
		(stroke
			(width 0.2)
			(type default)
		)
		(fill no)
		(layer "In8.Cu")
	)
	(gr_circle
		(center 182.75046 -49.657)
		(end 183.63946 -49.657)
		(stroke
			(width 0.2)
			(type default)
		)
		(fill no)
		(layer "In8.Cu")
	)
	(gr_circle
		(center 182.850282 -77.71765)
		(end 183.739282 -77.71765)
		(stroke
			(width 0.2)
			(type default)
		)
		(fill no)
		(layer "In8.Cu")
	)
	(gr_circle
		(center 183.529986 -37.949632)
		(end 184.929018 -37.949632)
		(stroke
			(width 0.2)
			(type default)
		)
		(fill no)
		(layer "In8.Cu")
	)
	(gr_circle
		(center 183.529986 -35.409632)
		(end 184.929018 -35.409632)
		(stroke
			(width 0.2)
			(type default)
		)
		(fill no)
		(layer "In8.Cu")
	)
	(gr_circle
		(center 183.529986 -32.869632)
		(end 184.929018 -32.869632)
		(stroke
			(width 0.2)
			(type default)
		)
		(fill no)
		(layer "In8.Cu")
	)
	(gr_circle
		(center 183.529986 -30.329632)
		(end 184.929018 -30.329632)
		(stroke
			(width 0.2)
			(type default)
		)
		(fill no)
		(layer "In8.Cu")
	)
	(gr_circle
		(center 184.470294 -121.209816)
		(end 186.286394 -121.209816)
		(stroke
			(width 0.2)
			(type default)
		)
		(fill no)
		(layer "In8.Cu")
	)
	(gr_circle
		(center 184.470294 -70.409816)
		(end 186.667394 -70.409816)
		(stroke
			(width 0.2)
			(type default)
		)
		(fill no)
		(layer "In8.Cu")
	)
	(gr_circle
		(center 186.431174 -136.906)
		(end 187.853574 -136.906)
		(stroke
			(width 0.2)
			(type default)
		)
		(fill no)
		(layer "In8.Cu")
	)
	(gr_circle
		(center 186.939174 -60.96)
		(end 188.336174 -60.96)
		(stroke
			(width 0.2)
			(type default)
		)
		(fill no)
		(layer "In8.Cu")
	)
	(gr_circle
		(center 187.294774 -131.572)
		(end 188.183774 -131.572)
		(stroke
			(width 0.2)
			(type default)
		)
		(fill no)
		(layer "In8.Cu")
	)
	(gr_circle
		(center 187.294774 -126.492)
		(end 188.183774 -126.492)
		(stroke
			(width 0.2)
			(type default)
		)
		(fill no)
		(layer "In8.Cu")
	)
	(gr_circle
		(center 188.056774 -131.572)
		(end 188.945774 -131.572)
		(stroke
			(width 0.2)
			(type default)
		)
		(fill no)
		(layer "In8.Cu")
	)
	(gr_circle
		(center 188.056774 -126.492)
		(end 188.945774 -126.492)
		(stroke
			(width 0.2)
			(type default)
		)
		(fill no)
		(layer "In8.Cu")
	)
	(gr_circle
		(center 188.280294 -70.409816)
		(end 190.477394 -70.409816)
		(stroke
			(width 0.2)
			(type default)
		)
		(fill no)
		(layer "In8.Cu")
	)
	(gr_circle
		(center 189.879986 -37.949632)
		(end 191.279018 -37.949632)
		(stroke
			(width 0.2)
			(type default)
		)
		(fill no)
		(layer "In8.Cu")
	)
	(gr_circle
		(center 189.879986 -35.409632)
		(end 191.279018 -35.409632)
		(stroke
			(width 0.2)
			(type default)
		)
		(fill no)
		(layer "In8.Cu")
	)
	(gr_circle
		(center 189.879986 -32.869632)
		(end 191.279018 -32.869632)
		(stroke
			(width 0.2)
			(type default)
		)
		(fill no)
		(layer "In8.Cu")
	)
	(gr_circle
		(center 189.879986 -30.329632)
		(end 191.279018 -30.329632)
		(stroke
			(width 0.2)
			(type default)
		)
		(fill no)
		(layer "In8.Cu")
	)
	(gr_circle
		(center 191.149986 -36.806632)
		(end 192.549018 -36.806632)
		(stroke
			(width 0.2)
			(type default)
		)
		(fill no)
		(layer "In8.Cu")
	)
	(gr_circle
		(center 191.276986 -34.520632)
		(end 192.676018 -34.520632)
		(stroke
			(width 0.2)
			(type default)
		)
		(fill no)
		(layer "In8.Cu")
	)
	(gr_circle
		(center 191.403986 -31.726632)
		(end 192.803018 -31.726632)
		(stroke
			(width 0.2)
			(type default)
		)
		(fill no)
		(layer "In8.Cu")
	)
	(gr_circle
		(center 192.419986 -37.949632)
		(end 193.819018 -37.949632)
		(stroke
			(width 0.2)
			(type default)
		)
		(fill no)
		(layer "In8.Cu")
	)
	(gr_circle
		(center 192.419986 -35.409632)
		(end 193.819018 -35.409632)
		(stroke
			(width 0.2)
			(type default)
		)
		(fill no)
		(layer "In8.Cu")
	)
	(gr_circle
		(center 192.419986 -32.869632)
		(end 193.819018 -32.869632)
		(stroke
			(width 0.2)
			(type default)
		)
		(fill no)
		(layer "In8.Cu")
	)
	(gr_circle
		(center 192.419986 -30.329632)
		(end 193.819018 -30.329632)
		(stroke
			(width 0.2)
			(type default)
		)
		(fill no)
		(layer "In8.Cu")
	)
	(gr_circle
		(center 198.115174 -60.96)
		(end 199.512174 -60.96)
		(stroke
			(width 0.2)
			(type default)
		)
		(fill no)
		(layer "In8.Cu")
	)
	(gr_circle
		(center 198.769986 -37.949632)
		(end 200.169018 -37.949632)
		(stroke
			(width 0.2)
			(type default)
		)
		(fill no)
		(layer "In8.Cu")
	)
	(gr_circle
		(center 198.769986 -35.409632)
		(end 200.169018 -35.409632)
		(stroke
			(width 0.2)
			(type default)
		)
		(fill no)
		(layer "In8.Cu")
	)
	(gr_circle
		(center 198.769986 -32.869632)
		(end 200.169018 -32.869632)
		(stroke
			(width 0.2)
			(type default)
		)
		(fill no)
		(layer "In8.Cu")
	)
	(gr_circle
		(center 198.769986 -30.329632)
		(end 200.169018 -30.329632)
		(stroke
			(width 0.2)
			(type default)
		)
		(fill no)
		(layer "In8.Cu")
	)
	(gr_circle
		(center 200.039986 -36.933632)
		(end 201.439018 -36.933632)
		(stroke
			(width 0.2)
			(type default)
		)
		(fill no)
		(layer "In8.Cu")
	)
	(gr_circle
		(center 200.039986 -34.520632)
		(end 201.439018 -34.520632)
		(stroke
			(width 0.2)
			(type default)
		)
		(fill no)
		(layer "In8.Cu")
	)
	(gr_circle
		(center 200.039986 -31.599632)
		(end 201.439018 -31.599632)
		(stroke
			(width 0.2)
			(type default)
		)
		(fill no)
		(layer "In8.Cu")
	)
	(gr_circle
		(center 201.309986 -37.949632)
		(end 202.709018 -37.949632)
		(stroke
			(width 0.2)
			(type default)
		)
		(fill no)
		(layer "In8.Cu")
	)
	(gr_circle
		(center 201.309986 -35.409632)
		(end 202.709018 -35.409632)
		(stroke
			(width 0.2)
			(type default)
		)
		(fill no)
		(layer "In8.Cu")
	)
	(gr_circle
		(center 201.309986 -32.869632)
		(end 202.709018 -32.869632)
		(stroke
			(width 0.2)
			(type default)
		)
		(fill no)
		(layer "In8.Cu")
	)
	(gr_circle
		(center 201.309986 -30.329632)
		(end 202.709018 -30.329632)
		(stroke
			(width 0.2)
			(type default)
		)
		(fill no)
		(layer "In8.Cu")
	)
	(gr_circle
		(center 202.3364 -105.883202)
		(end 203.2254 -105.883202)
		(stroke
			(width 0.2)
			(type default)
		)
		(fill no)
		(layer "In8.Cu")
	)
	(gr_circle
		(center 202.3364 -105.121202)
		(end 203.2254 -105.121202)
		(stroke
			(width 0.2)
			(type default)
		)
		(fill no)
		(layer "In8.Cu")
	)
	(gr_circle
		(center 202.3364 -104.418638)
		(end 203.2254 -104.418638)
		(stroke
			(width 0.2)
			(type default)
		)
		(fill no)
		(layer "In8.Cu")
	)
	(gr_circle
		(center 202.3364 -103.656638)
		(end 203.2254 -103.656638)
		(stroke
			(width 0.2)
			(type default)
		)
		(fill no)
		(layer "In8.Cu")
	)
	(gr_circle
		(center 202.3364 -102.894638)
		(end 203.2254 -102.894638)
		(stroke
			(width 0.2)
			(type default)
		)
		(fill no)
		(layer "In8.Cu")
	)
	(gr_circle
		(center 202.35037 -122.809762)
		(end 203.23937 -122.809762)
		(stroke
			(width 0.2)
			(type default)
		)
		(fill no)
		(layer "In8.Cu")
	)
	(gr_circle
		(center 202.35037 -122.047762)
		(end 203.23937 -122.047762)
		(stroke
			(width 0.2)
			(type default)
		)
		(fill no)
		(layer "In8.Cu")
	)
	(gr_circle
		(center 202.35037 -121.331736)
		(end 203.23937 -121.331736)
		(stroke
			(width 0.2)
			(type default)
		)
		(fill no)
		(layer "In8.Cu")
	)
	(gr_circle
		(center 202.35037 -120.569736)
		(end 203.23937 -120.569736)
		(stroke
			(width 0.2)
			(type default)
		)
		(fill no)
		(layer "In8.Cu")
	)
	(gr_circle
		(center 202.364086 -123.528328)
		(end 203.253086 -123.528328)
		(stroke
			(width 0.2)
			(type default)
		)
		(fill no)
		(layer "In8.Cu")
	)
	(gr_circle
		(center 203.028042 -105.896664)
		(end 203.917042 -105.896664)
		(stroke
			(width 0.2)
			(type default)
		)
		(fill no)
		(layer "In8.Cu")
	)
	(gr_circle
		(center 203.028042 -105.134664)
		(end 203.917042 -105.134664)
		(stroke
			(width 0.2)
			(type default)
		)
		(fill no)
		(layer "In8.Cu")
	)
	(gr_circle
		(center 203.028042 -104.4321)
		(end 203.917042 -104.4321)
		(stroke
			(width 0.2)
			(type default)
		)
		(fill no)
		(layer "In8.Cu")
	)
	(gr_circle
		(center 203.028042 -103.6701)
		(end 203.917042 -103.6701)
		(stroke
			(width 0.2)
			(type default)
		)
		(fill no)
		(layer "In8.Cu")
	)
	(gr_circle
		(center 203.028042 -102.9081)
		(end 203.917042 -102.9081)
		(stroke
			(width 0.2)
			(type default)
		)
		(fill no)
		(layer "In8.Cu")
	)
	(gr_circle
		(center 203.11237 -122.809762)
		(end 204.00137 -122.809762)
		(stroke
			(width 0.2)
			(type default)
		)
		(fill no)
		(layer "In8.Cu")
	)
	(gr_circle
		(center 203.11237 -122.047762)
		(end 204.00137 -122.047762)
		(stroke
			(width 0.2)
			(type default)
		)
		(fill no)
		(layer "In8.Cu")
	)
	(gr_circle
		(center 203.11237 -121.331736)
		(end 204.00137 -121.331736)
		(stroke
			(width 0.2)
			(type default)
		)
		(fill no)
		(layer "In8.Cu")
	)
	(gr_circle
		(center 203.11237 -120.569736)
		(end 204.00137 -120.569736)
		(stroke
			(width 0.2)
			(type default)
		)
		(fill no)
		(layer "In8.Cu")
	)
	(gr_circle
		(center 203.126086 -123.528328)
		(end 204.015086 -123.528328)
		(stroke
			(width 0.2)
			(type default)
		)
		(fill no)
		(layer "In8.Cu")
	)
	(gr_circle
		(center 203.790042 -105.896664)
		(end 204.679042 -105.896664)
		(stroke
			(width 0.2)
			(type default)
		)
		(fill no)
		(layer "In8.Cu")
	)
	(gr_circle
		(center 203.790042 -105.134664)
		(end 204.679042 -105.134664)
		(stroke
			(width 0.2)
			(type default)
		)
		(fill no)
		(layer "In8.Cu")
	)
	(gr_circle
		(center 203.790042 -104.4321)
		(end 204.679042 -104.4321)
		(stroke
			(width 0.2)
			(type default)
		)
		(fill no)
		(layer "In8.Cu")
	)
	(gr_circle
		(center 203.790042 -103.6701)
		(end 204.679042 -103.6701)
		(stroke
			(width 0.2)
			(type default)
		)
		(fill no)
		(layer "In8.Cu")
	)
	(gr_circle
		(center 203.790042 -102.9081)
		(end 204.679042 -102.9081)
		(stroke
			(width 0.2)
			(type default)
		)
		(fill no)
		(layer "In8.Cu")
	)
	(gr_circle
		(center 203.87437 -122.809762)
		(end 204.76337 -122.809762)
		(stroke
			(width 0.2)
			(type default)
		)
		(fill no)
		(layer "In8.Cu")
	)
	(gr_circle
		(center 203.87437 -122.047762)
		(end 204.76337 -122.047762)
		(stroke
			(width 0.2)
			(type default)
		)
		(fill no)
		(layer "In8.Cu")
	)
	(gr_circle
		(center 203.87437 -121.331736)
		(end 204.76337 -121.331736)
		(stroke
			(width 0.2)
			(type default)
		)
		(fill no)
		(layer "In8.Cu")
	)
	(gr_circle
		(center 203.87437 -120.569736)
		(end 204.76337 -120.569736)
		(stroke
			(width 0.2)
			(type default)
		)
		(fill no)
		(layer "In8.Cu")
	)
	(gr_circle
		(center 203.888086 -123.528328)
		(end 204.777086 -123.528328)
		(stroke
			(width 0.2)
			(type default)
		)
		(fill no)
		(layer "In8.Cu")
	)
	(gr_circle
		(center 204.552042 -105.896664)
		(end 205.441042 -105.896664)
		(stroke
			(width 0.2)
			(type default)
		)
		(fill no)
		(layer "In8.Cu")
	)
	(gr_circle
		(center 204.552042 -105.134664)
		(end 205.441042 -105.134664)
		(stroke
			(width 0.2)
			(type default)
		)
		(fill no)
		(layer "In8.Cu")
	)
	(gr_circle
		(center 204.552042 -104.4321)
		(end 205.441042 -104.4321)
		(stroke
			(width 0.2)
			(type default)
		)
		(fill no)
		(layer "In8.Cu")
	)
	(gr_circle
		(center 204.552042 -103.6701)
		(end 205.441042 -103.6701)
		(stroke
			(width 0.2)
			(type default)
		)
		(fill no)
		(layer "In8.Cu")
	)
	(gr_circle
		(center 204.552042 -102.9081)
		(end 205.441042 -102.9081)
		(stroke
			(width 0.2)
			(type default)
		)
		(fill no)
		(layer "In8.Cu")
	)
	(gr_circle
		(center 204.63637 -122.809762)
		(end 205.52537 -122.809762)
		(stroke
			(width 0.2)
			(type default)
		)
		(fill no)
		(layer "In8.Cu")
	)
	(gr_circle
		(center 204.63637 -122.047762)
		(end 205.52537 -122.047762)
		(stroke
			(width 0.2)
			(type default)
		)
		(fill no)
		(layer "In8.Cu")
	)
	(gr_circle
		(center 204.63637 -121.331736)
		(end 205.52537 -121.331736)
		(stroke
			(width 0.2)
			(type default)
		)
		(fill no)
		(layer "In8.Cu")
	)
	(gr_circle
		(center 204.63637 -120.569736)
		(end 205.52537 -120.569736)
		(stroke
			(width 0.2)
			(type default)
		)
		(fill no)
		(layer "In8.Cu")
	)
	(gr_circle
		(center 204.650086 -123.528328)
		(end 205.539086 -123.528328)
		(stroke
			(width 0.2)
			(type default)
		)
		(fill no)
		(layer "In8.Cu")
	)
	(gr_circle
		(center 205.314042 -105.896664)
		(end 206.203042 -105.896664)
		(stroke
			(width 0.2)
			(type default)
		)
		(fill no)
		(layer "In8.Cu")
	)
	(gr_circle
		(center 205.314042 -105.134664)
		(end 206.203042 -105.134664)
		(stroke
			(width 0.2)
			(type default)
		)
		(fill no)
		(layer "In8.Cu")
	)
	(gr_circle
		(center 205.314042 -104.4321)
		(end 206.203042 -104.4321)
		(stroke
			(width 0.2)
			(type default)
		)
		(fill no)
		(layer "In8.Cu")
	)
	(gr_circle
		(center 205.314042 -103.6701)
		(end 206.203042 -103.6701)
		(stroke
			(width 0.2)
			(type default)
		)
		(fill no)
		(layer "In8.Cu")
	)
	(gr_circle
		(center 205.314042 -102.9081)
		(end 206.203042 -102.9081)
		(stroke
			(width 0.2)
			(type default)
		)
		(fill no)
		(layer "In8.Cu")
	)
	(gr_circle
		(center 205.39837 -122.809762)
		(end 206.28737 -122.809762)
		(stroke
			(width 0.2)
			(type default)
		)
		(fill no)
		(layer "In8.Cu")
	)
	(gr_circle
		(center 205.39837 -122.047762)
		(end 206.28737 -122.047762)
		(stroke
			(width 0.2)
			(type default)
		)
		(fill no)
		(layer "In8.Cu")
	)
	(gr_circle
		(center 205.39837 -121.331736)
		(end 206.28737 -121.331736)
		(stroke
			(width 0.2)
			(type default)
		)
		(fill no)
		(layer "In8.Cu")
	)
	(gr_circle
		(center 205.39837 -120.569736)
		(end 206.28737 -120.569736)
		(stroke
			(width 0.2)
			(type default)
		)
		(fill no)
		(layer "In8.Cu")
	)
	(gr_circle
		(center 205.412086 -123.528328)
		(end 206.301086 -123.528328)
		(stroke
			(width 0.2)
			(type default)
		)
		(fill no)
		(layer "In8.Cu")
	)
	(gr_circle
		(center 206.076042 -105.896664)
		(end 206.965042 -105.896664)
		(stroke
			(width 0.2)
			(type default)
		)
		(fill no)
		(layer "In8.Cu")
	)
	(gr_circle
		(center 206.076042 -105.134664)
		(end 206.965042 -105.134664)
		(stroke
			(width 0.2)
			(type default)
		)
		(fill no)
		(layer "In8.Cu")
	)
	(gr_circle
		(center 206.076042 -104.4321)
		(end 206.965042 -104.4321)
		(stroke
			(width 0.2)
			(type default)
		)
		(fill no)
		(layer "In8.Cu")
	)
	(gr_circle
		(center 206.076042 -103.6701)
		(end 206.965042 -103.6701)
		(stroke
			(width 0.2)
			(type default)
		)
		(fill no)
		(layer "In8.Cu")
	)
	(gr_circle
		(center 206.076042 -102.9081)
		(end 206.965042 -102.9081)
		(stroke
			(width 0.2)
			(type default)
		)
		(fill no)
		(layer "In8.Cu")
	)
	(gr_circle
		(center 206.16037 -122.809762)
		(end 207.04937 -122.809762)
		(stroke
			(width 0.2)
			(type default)
		)
		(fill no)
		(layer "In8.Cu")
	)
	(gr_circle
		(center 206.16037 -122.047762)
		(end 207.04937 -122.047762)
		(stroke
			(width 0.2)
			(type default)
		)
		(fill no)
		(layer "In8.Cu")
	)
	(gr_circle
		(center 206.16037 -121.331736)
		(end 207.04937 -121.331736)
		(stroke
			(width 0.2)
			(type default)
		)
		(fill no)
		(layer "In8.Cu")
	)
	(gr_circle
		(center 206.16037 -120.569736)
		(end 207.04937 -120.569736)
		(stroke
			(width 0.2)
			(type default)
		)
		(fill no)
		(layer "In8.Cu")
	)
	(gr_circle
		(center 206.174086 -123.528328)
		(end 207.063086 -123.528328)
		(stroke
			(width 0.2)
			(type default)
		)
		(fill no)
		(layer "In8.Cu")
	)
	(gr_circle
		(center 206.838042 -105.896664)
		(end 207.727042 -105.896664)
		(stroke
			(width 0.2)
			(type default)
		)
		(fill no)
		(layer "In8.Cu")
	)
	(gr_circle
		(center 206.838042 -105.134664)
		(end 207.727042 -105.134664)
		(stroke
			(width 0.2)
			(type default)
		)
		(fill no)
		(layer "In8.Cu")
	)
	(gr_circle
		(center 206.838042 -104.4321)
		(end 207.727042 -104.4321)
		(stroke
			(width 0.2)
			(type default)
		)
		(fill no)
		(layer "In8.Cu")
	)
	(gr_circle
		(center 206.838042 -103.6701)
		(end 207.727042 -103.6701)
		(stroke
			(width 0.2)
			(type default)
		)
		(fill no)
		(layer "In8.Cu")
	)
	(gr_circle
		(center 206.838042 -102.9081)
		(end 207.727042 -102.9081)
		(stroke
			(width 0.2)
			(type default)
		)
		(fill no)
		(layer "In8.Cu")
	)
	(gr_circle
		(center 206.92237 -122.809762)
		(end 207.81137 -122.809762)
		(stroke
			(width 0.2)
			(type default)
		)
		(fill no)
		(layer "In8.Cu")
	)
	(gr_circle
		(center 206.92237 -122.047762)
		(end 207.81137 -122.047762)
		(stroke
			(width 0.2)
			(type default)
		)
		(fill no)
		(layer "In8.Cu")
	)
	(gr_circle
		(center 206.92237 -121.331736)
		(end 207.81137 -121.331736)
		(stroke
			(width 0.2)
			(type default)
		)
		(fill no)
		(layer "In8.Cu")
	)
	(gr_circle
		(center 206.92237 -120.569736)
		(end 207.81137 -120.569736)
		(stroke
			(width 0.2)
			(type default)
		)
		(fill no)
		(layer "In8.Cu")
	)
	(gr_circle
		(center 206.936086 -123.528328)
		(end 207.825086 -123.528328)
		(stroke
			(width 0.2)
			(type default)
		)
		(fill no)
		(layer "In8.Cu")
	)
	(gr_circle
		(center 207.556862 -105.882948)
		(end 208.445862 -105.882948)
		(stroke
			(width 0.2)
			(type default)
		)
		(fill no)
		(layer "In8.Cu")
	)
	(gr_circle
		(center 207.556862 -105.120948)
		(end 208.445862 -105.120948)
		(stroke
			(width 0.2)
			(type default)
		)
		(fill no)
		(layer "In8.Cu")
	)
	(gr_circle
		(center 207.556862 -104.418384)
		(end 208.445862 -104.418384)
		(stroke
			(width 0.2)
			(type default)
		)
		(fill no)
		(layer "In8.Cu")
	)
	(gr_circle
		(center 207.556862 -103.656384)
		(end 208.445862 -103.656384)
		(stroke
			(width 0.2)
			(type default)
		)
		(fill no)
		(layer "In8.Cu")
	)
	(gr_circle
		(center 207.556862 -102.894384)
		(end 208.445862 -102.894384)
		(stroke
			(width 0.2)
			(type default)
		)
		(fill no)
		(layer "In8.Cu")
	)
	(gr_circle
		(center 207.68437 -122.809762)
		(end 208.57337 -122.809762)
		(stroke
			(width 0.2)
			(type default)
		)
		(fill no)
		(layer "In8.Cu")
	)
	(gr_circle
		(center 207.68437 -122.047762)
		(end 208.57337 -122.047762)
		(stroke
			(width 0.2)
			(type default)
		)
		(fill no)
		(layer "In8.Cu")
	)
	(gr_circle
		(center 207.68437 -121.331736)
		(end 208.57337 -121.331736)
		(stroke
			(width 0.2)
			(type default)
		)
		(fill no)
		(layer "In8.Cu")
	)
	(gr_circle
		(center 207.68437 -120.569736)
		(end 208.57337 -120.569736)
		(stroke
			(width 0.2)
			(type default)
		)
		(fill no)
		(layer "In8.Cu")
	)
	(gr_circle
		(center 207.698086 -123.528328)
		(end 208.587086 -123.528328)
		(stroke
			(width 0.2)
			(type default)
		)
		(fill no)
		(layer "In8.Cu")
	)
	(gr_circle
		(center 209.291174 -60.96)
		(end 210.688174 -60.96)
		(stroke
			(width 0.2)
			(type default)
		)
		(fill no)
		(layer "In8.Cu")
	)
	(gr_circle
		(center 213.978236 -132.959856)
		(end 214.867236 -132.959856)
		(stroke
			(width 0.2)
			(type default)
		)
		(fill no)
		(layer "In8.Cu")
	)
	(gr_circle
		(center 213.978236 -132.197856)
		(end 214.867236 -132.197856)
		(stroke
			(width 0.2)
			(type default)
		)
		(fill no)
		(layer "In8.Cu")
	)
	(gr_circle
		(center 213.978236 -131.435856)
		(end 214.867236 -131.435856)
		(stroke
			(width 0.2)
			(type default)
		)
		(fill no)
		(layer "In8.Cu")
	)
	(gr_circle
		(center 213.978236 -130.673856)
		(end 214.867236 -130.673856)
		(stroke
			(width 0.2)
			(type default)
		)
		(fill no)
		(layer "In8.Cu")
	)
	(gr_circle
		(center 213.978236 -129.911856)
		(end 214.867236 -129.911856)
		(stroke
			(width 0.2)
			(type default)
		)
		(fill no)
		(layer "In8.Cu")
	)
	(gr_circle
		(center 213.978236 -129.149856)
		(end 214.867236 -129.149856)
		(stroke
			(width 0.2)
			(type default)
		)
		(fill no)
		(layer "In8.Cu")
	)
	(gr_circle
		(center 213.978236 -128.387856)
		(end 214.867236 -128.387856)
		(stroke
			(width 0.2)
			(type default)
		)
		(fill no)
		(layer "In8.Cu")
	)
	(gr_circle
		(center 213.978236 -127.625856)
		(end 214.867236 -127.625856)
		(stroke
			(width 0.2)
			(type default)
		)
		(fill no)
		(layer "In8.Cu")
	)
	(gr_circle
		(center 214.696802 -132.94614)
		(end 215.585802 -132.94614)
		(stroke
			(width 0.2)
			(type default)
		)
		(fill no)
		(layer "In8.Cu")
	)
	(gr_circle
		(center 214.696802 -132.18414)
		(end 215.585802 -132.18414)
		(stroke
			(width 0.2)
			(type default)
		)
		(fill no)
		(layer "In8.Cu")
	)
	(gr_circle
		(center 214.696802 -131.42214)
		(end 215.585802 -131.42214)
		(stroke
			(width 0.2)
			(type default)
		)
		(fill no)
		(layer "In8.Cu")
	)
	(gr_circle
		(center 214.696802 -130.66014)
		(end 215.585802 -130.66014)
		(stroke
			(width 0.2)
			(type default)
		)
		(fill no)
		(layer "In8.Cu")
	)
	(gr_circle
		(center 214.696802 -129.89814)
		(end 215.585802 -129.89814)
		(stroke
			(width 0.2)
			(type default)
		)
		(fill no)
		(layer "In8.Cu")
	)
	(gr_circle
		(center 214.696802 -129.13614)
		(end 215.585802 -129.13614)
		(stroke
			(width 0.2)
			(type default)
		)
		(fill no)
		(layer "In8.Cu")
	)
	(gr_circle
		(center 214.696802 -128.37414)
		(end 215.585802 -128.37414)
		(stroke
			(width 0.2)
			(type default)
		)
		(fill no)
		(layer "In8.Cu")
	)
	(gr_circle
		(center 214.696802 -127.61214)
		(end 215.585802 -127.61214)
		(stroke
			(width 0.2)
			(type default)
		)
		(fill no)
		(layer "In8.Cu")
	)
	(gr_circle
		(center 215.23706 -98.013012)
		(end 216.12606 -98.013012)
		(stroke
			(width 0.2)
			(type default)
		)
		(fill no)
		(layer "In8.Cu")
	)
	(gr_circle
		(center 215.458802 -132.94614)
		(end 216.347802 -132.94614)
		(stroke
			(width 0.2)
			(type default)
		)
		(fill no)
		(layer "In8.Cu")
	)
	(gr_circle
		(center 215.458802 -132.18414)
		(end 216.347802 -132.18414)
		(stroke
			(width 0.2)
			(type default)
		)
		(fill no)
		(layer "In8.Cu")
	)
	(gr_circle
		(center 215.458802 -131.42214)
		(end 216.347802 -131.42214)
		(stroke
			(width 0.2)
			(type default)
		)
		(fill no)
		(layer "In8.Cu")
	)
	(gr_circle
		(center 215.458802 -130.66014)
		(end 216.347802 -130.66014)
		(stroke
			(width 0.2)
			(type default)
		)
		(fill no)
		(layer "In8.Cu")
	)
	(gr_circle
		(center 215.458802 -129.89814)
		(end 216.347802 -129.89814)
		(stroke
			(width 0.2)
			(type default)
		)
		(fill no)
		(layer "In8.Cu")
	)
	(gr_circle
		(center 215.458802 -129.13614)
		(end 216.347802 -129.13614)
		(stroke
			(width 0.2)
			(type default)
		)
		(fill no)
		(layer "In8.Cu")
	)
	(gr_circle
		(center 215.458802 -128.37414)
		(end 216.347802 -128.37414)
		(stroke
			(width 0.2)
			(type default)
		)
		(fill no)
		(layer "In8.Cu")
	)
	(gr_circle
		(center 215.458802 -127.61214)
		(end 216.347802 -127.61214)
		(stroke
			(width 0.2)
			(type default)
		)
		(fill no)
		(layer "In8.Cu")
	)
	(gr_circle
		(center 215.646 -101.346)
		(end 216.535 -101.346)
		(stroke
			(width 0.2)
			(type default)
		)
		(fill no)
		(layer "In8.Cu")
	)
	(gr_circle
		(center 215.99906 -98.013012)
		(end 216.88806 -98.013012)
		(stroke
			(width 0.2)
			(type default)
		)
		(fill no)
		(layer "In8.Cu")
	)
	(gr_circle
		(center 216.174828 -132.94614)
		(end 217.063828 -132.94614)
		(stroke
			(width 0.2)
			(type default)
		)
		(fill no)
		(layer "In8.Cu")
	)
	(gr_circle
		(center 216.174828 -132.18414)
		(end 217.063828 -132.18414)
		(stroke
			(width 0.2)
			(type default)
		)
		(fill no)
		(layer "In8.Cu")
	)
	(gr_circle
		(center 216.174828 -131.42214)
		(end 217.063828 -131.42214)
		(stroke
			(width 0.2)
			(type default)
		)
		(fill no)
		(layer "In8.Cu")
	)
	(gr_circle
		(center 216.174828 -130.66014)
		(end 217.063828 -130.66014)
		(stroke
			(width 0.2)
			(type default)
		)
		(fill no)
		(layer "In8.Cu")
	)
	(gr_circle
		(center 216.174828 -129.89814)
		(end 217.063828 -129.89814)
		(stroke
			(width 0.2)
			(type default)
		)
		(fill no)
		(layer "In8.Cu")
	)
	(gr_circle
		(center 216.174828 -129.13614)
		(end 217.063828 -129.13614)
		(stroke
			(width 0.2)
			(type default)
		)
		(fill no)
		(layer "In8.Cu")
	)
	(gr_circle
		(center 216.174828 -128.37414)
		(end 217.063828 -128.37414)
		(stroke
			(width 0.2)
			(type default)
		)
		(fill no)
		(layer "In8.Cu")
	)
	(gr_circle
		(center 216.174828 -127.61214)
		(end 217.063828 -127.61214)
		(stroke
			(width 0.2)
			(type default)
		)
		(fill no)
		(layer "In8.Cu")
	)
	(gr_circle
		(center 216.727278 -122.809762)
		(end 217.616278 -122.809762)
		(stroke
			(width 0.2)
			(type default)
		)
		(fill no)
		(layer "In8.Cu")
	)
	(gr_circle
		(center 216.727278 -122.047762)
		(end 217.616278 -122.047762)
		(stroke
			(width 0.2)
			(type default)
		)
		(fill no)
		(layer "In8.Cu")
	)
	(gr_circle
		(center 216.727278 -121.331736)
		(end 217.616278 -121.331736)
		(stroke
			(width 0.2)
			(type default)
		)
		(fill no)
		(layer "In8.Cu")
	)
	(gr_circle
		(center 216.727278 -120.569736)
		(end 217.616278 -120.569736)
		(stroke
			(width 0.2)
			(type default)
		)
		(fill no)
		(layer "In8.Cu")
	)
	(gr_circle
		(center 216.740994 -123.528328)
		(end 217.629994 -123.528328)
		(stroke
			(width 0.2)
			(type default)
		)
		(fill no)
		(layer "In8.Cu")
	)
	(gr_circle
		(center 216.819226 -105.883202)
		(end 217.708226 -105.883202)
		(stroke
			(width 0.2)
			(type default)
		)
		(fill no)
		(layer "In8.Cu")
	)
	(gr_circle
		(center 216.819226 -105.121202)
		(end 217.708226 -105.121202)
		(stroke
			(width 0.2)
			(type default)
		)
		(fill no)
		(layer "In8.Cu")
	)
	(gr_circle
		(center 216.819226 -104.418638)
		(end 217.708226 -104.418638)
		(stroke
			(width 0.2)
			(type default)
		)
		(fill no)
		(layer "In8.Cu")
	)
	(gr_circle
		(center 216.819226 -103.656638)
		(end 217.708226 -103.656638)
		(stroke
			(width 0.2)
			(type default)
		)
		(fill no)
		(layer "In8.Cu")
	)
	(gr_circle
		(center 216.819226 -102.894638)
		(end 217.708226 -102.894638)
		(stroke
			(width 0.2)
			(type default)
		)
		(fill no)
		(layer "In8.Cu")
	)
	(gr_circle
		(center 216.936828 -132.94614)
		(end 217.825828 -132.94614)
		(stroke
			(width 0.2)
			(type default)
		)
		(fill no)
		(layer "In8.Cu")
	)
	(gr_circle
		(center 216.936828 -132.18414)
		(end 217.825828 -132.18414)
		(stroke
			(width 0.2)
			(type default)
		)
		(fill no)
		(layer "In8.Cu")
	)
	(gr_circle
		(center 216.936828 -131.42214)
		(end 217.825828 -131.42214)
		(stroke
			(width 0.2)
			(type default)
		)
		(fill no)
		(layer "In8.Cu")
	)
	(gr_circle
		(center 216.936828 -130.66014)
		(end 217.825828 -130.66014)
		(stroke
			(width 0.2)
			(type default)
		)
		(fill no)
		(layer "In8.Cu")
	)
	(gr_circle
		(center 216.936828 -129.89814)
		(end 217.825828 -129.89814)
		(stroke
			(width 0.2)
			(type default)
		)
		(fill no)
		(layer "In8.Cu")
	)
	(gr_circle
		(center 216.936828 -129.13614)
		(end 217.825828 -129.13614)
		(stroke
			(width 0.2)
			(type default)
		)
		(fill no)
		(layer "In8.Cu")
	)
	(gr_circle
		(center 216.936828 -128.37414)
		(end 217.825828 -128.37414)
		(stroke
			(width 0.2)
			(type default)
		)
		(fill no)
		(layer "In8.Cu")
	)
	(gr_circle
		(center 216.936828 -127.61214)
		(end 217.825828 -127.61214)
		(stroke
			(width 0.2)
			(type default)
		)
		(fill no)
		(layer "In8.Cu")
	)
	(gr_circle
		(center 217.488262 -98.013012)
		(end 218.377262 -98.013012)
		(stroke
			(width 0.2)
			(type default)
		)
		(fill no)
		(layer "In8.Cu")
	)
	(gr_circle
		(center 217.489278 -122.809762)
		(end 218.378278 -122.809762)
		(stroke
			(width 0.2)
			(type default)
		)
		(fill no)
		(layer "In8.Cu")
	)
	(gr_circle
		(center 217.489278 -122.047762)
		(end 218.378278 -122.047762)
		(stroke
			(width 0.2)
			(type default)
		)
		(fill no)
		(layer "In8.Cu")
	)
	(gr_circle
		(center 217.489278 -121.331736)
		(end 218.378278 -121.331736)
		(stroke
			(width 0.2)
			(type default)
		)
		(fill no)
		(layer "In8.Cu")
	)
	(gr_circle
		(center 217.489278 -120.569736)
		(end 218.378278 -120.569736)
		(stroke
			(width 0.2)
			(type default)
		)
		(fill no)
		(layer "In8.Cu")
	)
	(gr_circle
		(center 217.502994 -123.528328)
		(end 218.391994 -123.528328)
		(stroke
			(width 0.2)
			(type default)
		)
		(fill no)
		(layer "In8.Cu")
	)
	(gr_circle
		(center 217.510868 -105.896664)
		(end 218.399868 -105.896664)
		(stroke
			(width 0.2)
			(type default)
		)
		(fill no)
		(layer "In8.Cu")
	)
	(gr_circle
		(center 217.510868 -105.134664)
		(end 218.399868 -105.134664)
		(stroke
			(width 0.2)
			(type default)
		)
		(fill no)
		(layer "In8.Cu")
	)
	(gr_circle
		(center 217.510868 -104.4321)
		(end 218.399868 -104.4321)
		(stroke
			(width 0.2)
			(type default)
		)
		(fill no)
		(layer "In8.Cu")
	)
	(gr_circle
		(center 217.510868 -103.6701)
		(end 218.399868 -103.6701)
		(stroke
			(width 0.2)
			(type default)
		)
		(fill no)
		(layer "In8.Cu")
	)
	(gr_circle
		(center 217.510868 -102.9081)
		(end 218.399868 -102.9081)
		(stroke
			(width 0.2)
			(type default)
		)
		(fill no)
		(layer "In8.Cu")
	)
	(gr_circle
		(center 218.250262 -98.013012)
		(end 219.139262 -98.013012)
		(stroke
			(width 0.2)
			(type default)
		)
		(fill no)
		(layer "In8.Cu")
	)
	(gr_circle
		(center 218.251278 -122.809762)
		(end 219.140278 -122.809762)
		(stroke
			(width 0.2)
			(type default)
		)
		(fill no)
		(layer "In8.Cu")
	)
	(gr_circle
		(center 218.251278 -122.047762)
		(end 219.140278 -122.047762)
		(stroke
			(width 0.2)
			(type default)
		)
		(fill no)
		(layer "In8.Cu")
	)
	(gr_circle
		(center 218.251278 -121.331736)
		(end 219.140278 -121.331736)
		(stroke
			(width 0.2)
			(type default)
		)
		(fill no)
		(layer "In8.Cu")
	)
	(gr_circle
		(center 218.251278 -120.569736)
		(end 219.140278 -120.569736)
		(stroke
			(width 0.2)
			(type default)
		)
		(fill no)
		(layer "In8.Cu")
	)
	(gr_circle
		(center 218.264994 -123.528328)
		(end 219.153994 -123.528328)
		(stroke
			(width 0.2)
			(type default)
		)
		(fill no)
		(layer "In8.Cu")
	)
	(gr_circle
		(center 218.272868 -105.896664)
		(end 219.161868 -105.896664)
		(stroke
			(width 0.2)
			(type default)
		)
		(fill no)
		(layer "In8.Cu")
	)
	(gr_circle
		(center 218.272868 -105.134664)
		(end 219.161868 -105.134664)
		(stroke
			(width 0.2)
			(type default)
		)
		(fill no)
		(layer "In8.Cu")
	)
	(gr_circle
		(center 218.272868 -104.4321)
		(end 219.161868 -104.4321)
		(stroke
			(width 0.2)
			(type default)
		)
		(fill no)
		(layer "In8.Cu")
	)
	(gr_circle
		(center 218.272868 -103.6701)
		(end 219.161868 -103.6701)
		(stroke
			(width 0.2)
			(type default)
		)
		(fill no)
		(layer "In8.Cu")
	)
	(gr_circle
		(center 218.272868 -102.9081)
		(end 219.161868 -102.9081)
		(stroke
			(width 0.2)
			(type default)
		)
		(fill no)
		(layer "In8.Cu")
	)
	(gr_circle
		(center 219.013278 -122.809762)
		(end 219.902278 -122.809762)
		(stroke
			(width 0.2)
			(type default)
		)
		(fill no)
		(layer "In8.Cu")
	)
	(gr_circle
		(center 219.013278 -122.047762)
		(end 219.902278 -122.047762)
		(stroke
			(width 0.2)
			(type default)
		)
		(fill no)
		(layer "In8.Cu")
	)
	(gr_circle
		(center 219.013278 -121.331736)
		(end 219.902278 -121.331736)
		(stroke
			(width 0.2)
			(type default)
		)
		(fill no)
		(layer "In8.Cu")
	)
	(gr_circle
		(center 219.013278 -120.569736)
		(end 219.902278 -120.569736)
		(stroke
			(width 0.2)
			(type default)
		)
		(fill no)
		(layer "In8.Cu")
	)
	(gr_circle
		(center 219.026994 -123.528328)
		(end 219.915994 -123.528328)
		(stroke
			(width 0.2)
			(type default)
		)
		(fill no)
		(layer "In8.Cu")
	)
	(gr_circle
		(center 219.034868 -105.896664)
		(end 219.923868 -105.896664)
		(stroke
			(width 0.2)
			(type default)
		)
		(fill no)
		(layer "In8.Cu")
	)
	(gr_circle
		(center 219.034868 -105.134664)
		(end 219.923868 -105.134664)
		(stroke
			(width 0.2)
			(type default)
		)
		(fill no)
		(layer "In8.Cu")
	)
	(gr_circle
		(center 219.034868 -104.4321)
		(end 219.923868 -104.4321)
		(stroke
			(width 0.2)
			(type default)
		)
		(fill no)
		(layer "In8.Cu")
	)
	(gr_circle
		(center 219.034868 -103.6701)
		(end 219.923868 -103.6701)
		(stroke
			(width 0.2)
			(type default)
		)
		(fill no)
		(layer "In8.Cu")
	)
	(gr_circle
		(center 219.034868 -102.9081)
		(end 219.923868 -102.9081)
		(stroke
			(width 0.2)
			(type default)
		)
		(fill no)
		(layer "In8.Cu")
	)
	(gr_circle
		(center 219.775278 -122.809762)
		(end 220.664278 -122.809762)
		(stroke
			(width 0.2)
			(type default)
		)
		(fill no)
		(layer "In8.Cu")
	)
	(gr_circle
		(center 219.775278 -122.047762)
		(end 220.664278 -122.047762)
		(stroke
			(width 0.2)
			(type default)
		)
		(fill no)
		(layer "In8.Cu")
	)
	(gr_circle
		(center 219.775278 -121.331736)
		(end 220.664278 -121.331736)
		(stroke
			(width 0.2)
			(type default)
		)
		(fill no)
		(layer "In8.Cu")
	)
	(gr_circle
		(center 219.775278 -120.569736)
		(end 220.664278 -120.569736)
		(stroke
			(width 0.2)
			(type default)
		)
		(fill no)
		(layer "In8.Cu")
	)
	(gr_circle
		(center 219.788994 -123.528328)
		(end 220.677994 -123.528328)
		(stroke
			(width 0.2)
			(type default)
		)
		(fill no)
		(layer "In8.Cu")
	)
	(gr_circle
		(center 219.796868 -105.896664)
		(end 220.685868 -105.896664)
		(stroke
			(width 0.2)
			(type default)
		)
		(fill no)
		(layer "In8.Cu")
	)
	(gr_circle
		(center 219.796868 -105.134664)
		(end 220.685868 -105.134664)
		(stroke
			(width 0.2)
			(type default)
		)
		(fill no)
		(layer "In8.Cu")
	)
	(gr_circle
		(center 219.796868 -104.4321)
		(end 220.685868 -104.4321)
		(stroke
			(width 0.2)
			(type default)
		)
		(fill no)
		(layer "In8.Cu")
	)
	(gr_circle
		(center 219.796868 -103.6701)
		(end 220.685868 -103.6701)
		(stroke
			(width 0.2)
			(type default)
		)
		(fill no)
		(layer "In8.Cu")
	)
	(gr_circle
		(center 219.796868 -102.9081)
		(end 220.685868 -102.9081)
		(stroke
			(width 0.2)
			(type default)
		)
		(fill no)
		(layer "In8.Cu")
	)
	(gr_circle
		(center 219.847668 -97.985834)
		(end 220.736668 -97.985834)
		(stroke
			(width 0.2)
			(type default)
		)
		(fill no)
		(layer "In8.Cu")
	)
	(gr_circle
		(center 220.537278 -122.809762)
		(end 221.426278 -122.809762)
		(stroke
			(width 0.2)
			(type default)
		)
		(fill no)
		(layer "In8.Cu")
	)
	(gr_circle
		(center 220.537278 -122.047762)
		(end 221.426278 -122.047762)
		(stroke
			(width 0.2)
			(type default)
		)
		(fill no)
		(layer "In8.Cu")
	)
	(gr_circle
		(center 220.537278 -121.331736)
		(end 221.426278 -121.331736)
		(stroke
			(width 0.2)
			(type default)
		)
		(fill no)
		(layer "In8.Cu")
	)
	(gr_circle
		(center 220.537278 -120.569736)
		(end 221.426278 -120.569736)
		(stroke
			(width 0.2)
			(type default)
		)
		(fill no)
		(layer "In8.Cu")
	)
	(gr_circle
		(center 220.550994 -123.528328)
		(end 221.439994 -123.528328)
		(stroke
			(width 0.2)
			(type default)
		)
		(fill no)
		(layer "In8.Cu")
	)
	(gr_circle
		(center 220.558868 -105.896664)
		(end 221.447868 -105.896664)
		(stroke
			(width 0.2)
			(type default)
		)
		(fill no)
		(layer "In8.Cu")
	)
	(gr_circle
		(center 220.558868 -105.134664)
		(end 221.447868 -105.134664)
		(stroke
			(width 0.2)
			(type default)
		)
		(fill no)
		(layer "In8.Cu")
	)
	(gr_circle
		(center 220.558868 -104.4321)
		(end 221.447868 -104.4321)
		(stroke
			(width 0.2)
			(type default)
		)
		(fill no)
		(layer "In8.Cu")
	)
	(gr_circle
		(center 220.558868 -103.6701)
		(end 221.447868 -103.6701)
		(stroke
			(width 0.2)
			(type default)
		)
		(fill no)
		(layer "In8.Cu")
	)
	(gr_circle
		(center 220.558868 -102.9081)
		(end 221.447868 -102.9081)
		(stroke
			(width 0.2)
			(type default)
		)
		(fill no)
		(layer "In8.Cu")
	)
	(gr_circle
		(center 220.609668 -97.985834)
		(end 221.498668 -97.985834)
		(stroke
			(width 0.2)
			(type default)
		)
		(fill no)
		(layer "In8.Cu")
	)
	(gr_circle
		(center 221.299278 -122.809762)
		(end 222.188278 -122.809762)
		(stroke
			(width 0.2)
			(type default)
		)
		(fill no)
		(layer "In8.Cu")
	)
	(gr_circle
		(center 221.299278 -122.047762)
		(end 222.188278 -122.047762)
		(stroke
			(width 0.2)
			(type default)
		)
		(fill no)
		(layer "In8.Cu")
	)
	(gr_circle
		(center 221.299278 -121.331736)
		(end 222.188278 -121.331736)
		(stroke
			(width 0.2)
			(type default)
		)
		(fill no)
		(layer "In8.Cu")
	)
	(gr_circle
		(center 221.299278 -120.569736)
		(end 222.188278 -120.569736)
		(stroke
			(width 0.2)
			(type default)
		)
		(fill no)
		(layer "In8.Cu")
	)
	(gr_circle
		(center 221.312994 -123.528328)
		(end 222.201994 -123.528328)
		(stroke
			(width 0.2)
			(type default)
		)
		(fill no)
		(layer "In8.Cu")
	)
	(gr_circle
		(center 221.320868 -105.896664)
		(end 222.209868 -105.896664)
		(stroke
			(width 0.2)
			(type default)
		)
		(fill no)
		(layer "In8.Cu")
	)
	(gr_circle
		(center 221.320868 -105.134664)
		(end 222.209868 -105.134664)
		(stroke
			(width 0.2)
			(type default)
		)
		(fill no)
		(layer "In8.Cu")
	)
	(gr_circle
		(center 221.320868 -104.4321)
		(end 222.209868 -104.4321)
		(stroke
			(width 0.2)
			(type default)
		)
		(fill no)
		(layer "In8.Cu")
	)
	(gr_circle
		(center 221.320868 -103.6701)
		(end 222.209868 -103.6701)
		(stroke
			(width 0.2)
			(type default)
		)
		(fill no)
		(layer "In8.Cu")
	)
	(gr_circle
		(center 221.320868 -102.9081)
		(end 222.209868 -102.9081)
		(stroke
			(width 0.2)
			(type default)
		)
		(fill no)
		(layer "In8.Cu")
	)
	(gr_circle
		(center 222.039688 -105.882948)
		(end 222.928688 -105.882948)
		(stroke
			(width 0.2)
			(type default)
		)
		(fill no)
		(layer "In8.Cu")
	)
	(gr_circle
		(center 222.039688 -105.120948)
		(end 222.928688 -105.120948)
		(stroke
			(width 0.2)
			(type default)
		)
		(fill no)
		(layer "In8.Cu")
	)
	(gr_circle
		(center 222.039688 -104.418384)
		(end 222.928688 -104.418384)
		(stroke
			(width 0.2)
			(type default)
		)
		(fill no)
		(layer "In8.Cu")
	)
	(gr_circle
		(center 222.039688 -103.656384)
		(end 222.928688 -103.656384)
		(stroke
			(width 0.2)
			(type default)
		)
		(fill no)
		(layer "In8.Cu")
	)
	(gr_circle
		(center 222.039688 -102.894384)
		(end 222.928688 -102.894384)
		(stroke
			(width 0.2)
			(type default)
		)
		(fill no)
		(layer "In8.Cu")
	)
	(gr_circle
		(center 222.061278 -122.809762)
		(end 222.950278 -122.809762)
		(stroke
			(width 0.2)
			(type default)
		)
		(fill no)
		(layer "In8.Cu")
	)
	(gr_circle
		(center 222.061278 -122.047762)
		(end 222.950278 -122.047762)
		(stroke
			(width 0.2)
			(type default)
		)
		(fill no)
		(layer "In8.Cu")
	)
	(gr_circle
		(center 222.061278 -121.331736)
		(end 222.950278 -121.331736)
		(stroke
			(width 0.2)
			(type default)
		)
		(fill no)
		(layer "In8.Cu")
	)
	(gr_circle
		(center 222.061278 -120.569736)
		(end 222.950278 -120.569736)
		(stroke
			(width 0.2)
			(type default)
		)
		(fill no)
		(layer "In8.Cu")
	)
	(gr_circle
		(center 222.074994 -123.528328)
		(end 222.963994 -123.528328)
		(stroke
			(width 0.2)
			(type default)
		)
		(fill no)
		(layer "In8.Cu")
	)
	(gr_circle
		(center 222.09887 -97.985834)
		(end 222.98787 -97.985834)
		(stroke
			(width 0.2)
			(type default)
		)
		(fill no)
		(layer "In8.Cu")
	)
	(gr_circle
		(center 222.86087 -97.985834)
		(end 223.74987 -97.985834)
		(stroke
			(width 0.2)
			(type default)
		)
		(fill no)
		(layer "In8.Cu")
	)
	(gr_circle
		(center 224.593912 -97.985834)
		(end 225.482912 -97.985834)
		(stroke
			(width 0.2)
			(type default)
		)
		(fill no)
		(layer "In8.Cu")
	)
	(gr_circle
		(center 225.355912 -97.985834)
		(end 226.244912 -97.985834)
		(stroke
			(width 0.2)
			(type default)
		)
		(fill no)
		(layer "In8.Cu")
	)
	(gr_circle
		(center 226.845114 -97.985834)
		(end 227.734114 -97.985834)
		(stroke
			(width 0.2)
			(type default)
		)
		(fill no)
		(layer "In8.Cu")
	)
	(gr_circle
		(center 227.607114 -97.985834)
		(end 228.496114 -97.985834)
		(stroke
			(width 0.2)
			(type default)
		)
		(fill no)
		(layer "In8.Cu")
	)
	(gr_circle
		(center 229.530148 -98.012758)
		(end 230.419148 -98.012758)
		(stroke
			(width 0.2)
			(type default)
		)
		(fill no)
		(layer "In8.Cu")
	)
	(gr_circle
		(center 230.292148 -98.012758)
		(end 231.181148 -98.012758)
		(stroke
			(width 0.2)
			(type default)
		)
		(fill no)
		(layer "In8.Cu")
	)
	(gr_circle
		(center 231.591104 -131.110736)
		(end 232.480104 -131.110736)
		(stroke
			(width 0.2)
			(type default)
		)
		(fill no)
		(layer "In8.Cu")
	)
	(gr_circle
		(center 231.591104 -130.348736)
		(end 232.480104 -130.348736)
		(stroke
			(width 0.2)
			(type default)
		)
		(fill no)
		(layer "In8.Cu")
	)
	(gr_circle
		(center 231.591104 -129.586736)
		(end 232.480104 -129.586736)
		(stroke
			(width 0.2)
			(type default)
		)
		(fill no)
		(layer "In8.Cu")
	)
	(gr_circle
		(center 231.591104 -128.824736)
		(end 232.480104 -128.824736)
		(stroke
			(width 0.2)
			(type default)
		)
		(fill no)
		(layer "In8.Cu")
	)
	(gr_circle
		(center 231.591104 -128.062736)
		(end 232.480104 -128.062736)
		(stroke
			(width 0.2)
			(type default)
		)
		(fill no)
		(layer "In8.Cu")
	)
	(gr_circle
		(center 231.591104 -127.300736)
		(end 232.480104 -127.300736)
		(stroke
			(width 0.2)
			(type default)
		)
		(fill no)
		(layer "In8.Cu")
	)
	(gr_circle
		(center 231.604566 -126.609094)
		(end 232.493566 -126.609094)
		(stroke
			(width 0.2)
			(type default)
		)
		(fill no)
		(layer "In8.Cu")
	)
	(gr_circle
		(center 231.60482 -131.829556)
		(end 232.49382 -131.829556)
		(stroke
			(width 0.2)
			(type default)
		)
		(fill no)
		(layer "In8.Cu")
	)
	(gr_circle
		(center 231.78135 -98.012758)
		(end 232.67035 -98.012758)
		(stroke
			(width 0.2)
			(type default)
		)
		(fill no)
		(layer "In8.Cu")
	)
	(gr_circle
		(center 232.353104 -131.110736)
		(end 233.242104 -131.110736)
		(stroke
			(width 0.2)
			(type default)
		)
		(fill no)
		(layer "In8.Cu")
	)
	(gr_circle
		(center 232.353104 -130.348736)
		(end 233.242104 -130.348736)
		(stroke
			(width 0.2)
			(type default)
		)
		(fill no)
		(layer "In8.Cu")
	)
	(gr_circle
		(center 232.353104 -129.586736)
		(end 233.242104 -129.586736)
		(stroke
			(width 0.2)
			(type default)
		)
		(fill no)
		(layer "In8.Cu")
	)
	(gr_circle
		(center 232.353104 -128.824736)
		(end 233.242104 -128.824736)
		(stroke
			(width 0.2)
			(type default)
		)
		(fill no)
		(layer "In8.Cu")
	)
	(gr_circle
		(center 232.353104 -128.062736)
		(end 233.242104 -128.062736)
		(stroke
			(width 0.2)
			(type default)
		)
		(fill no)
		(layer "In8.Cu")
	)
	(gr_circle
		(center 232.353104 -127.300736)
		(end 233.242104 -127.300736)
		(stroke
			(width 0.2)
			(type default)
		)
		(fill no)
		(layer "In8.Cu")
	)
	(gr_circle
		(center 232.366566 -126.609094)
		(end 233.255566 -126.609094)
		(stroke
			(width 0.2)
			(type default)
		)
		(fill no)
		(layer "In8.Cu")
	)
	(gr_circle
		(center 232.36682 -131.829556)
		(end 233.25582 -131.829556)
		(stroke
			(width 0.2)
			(type default)
		)
		(fill no)
		(layer "In8.Cu")
	)
	(gr_circle
		(center 232.54335 -98.012758)
		(end 233.43235 -98.012758)
		(stroke
			(width 0.2)
			(type default)
		)
		(fill no)
		(layer "In8.Cu")
	)
	(gr_circle
		(center 233.055668 -131.110736)
		(end 233.944668 -131.110736)
		(stroke
			(width 0.2)
			(type default)
		)
		(fill no)
		(layer "In8.Cu")
	)
	(gr_circle
		(center 233.055668 -130.348736)
		(end 233.944668 -130.348736)
		(stroke
			(width 0.2)
			(type default)
		)
		(fill no)
		(layer "In8.Cu")
	)
	(gr_circle
		(center 233.055668 -129.586736)
		(end 233.944668 -129.586736)
		(stroke
			(width 0.2)
			(type default)
		)
		(fill no)
		(layer "In8.Cu")
	)
	(gr_circle
		(center 233.055668 -128.824736)
		(end 233.944668 -128.824736)
		(stroke
			(width 0.2)
			(type default)
		)
		(fill no)
		(layer "In8.Cu")
	)
	(gr_circle
		(center 233.055668 -128.062736)
		(end 233.944668 -128.062736)
		(stroke
			(width 0.2)
			(type default)
		)
		(fill no)
		(layer "In8.Cu")
	)
	(gr_circle
		(center 233.055668 -127.300736)
		(end 233.944668 -127.300736)
		(stroke
			(width 0.2)
			(type default)
		)
		(fill no)
		(layer "In8.Cu")
	)
	(gr_circle
		(center 233.06913 -126.609094)
		(end 233.95813 -126.609094)
		(stroke
			(width 0.2)
			(type default)
		)
		(fill no)
		(layer "In8.Cu")
	)
	(gr_circle
		(center 233.069384 -131.829556)
		(end 233.958384 -131.829556)
		(stroke
			(width 0.2)
			(type default)
		)
		(fill no)
		(layer "In8.Cu")
	)
	(gr_circle
		(center 233.817668 -131.110736)
		(end 234.706668 -131.110736)
		(stroke
			(width 0.2)
			(type default)
		)
		(fill no)
		(layer "In8.Cu")
	)
	(gr_circle
		(center 233.817668 -130.348736)
		(end 234.706668 -130.348736)
		(stroke
			(width 0.2)
			(type default)
		)
		(fill no)
		(layer "In8.Cu")
	)
	(gr_circle
		(center 233.817668 -129.586736)
		(end 234.706668 -129.586736)
		(stroke
			(width 0.2)
			(type default)
		)
		(fill no)
		(layer "In8.Cu")
	)
	(gr_circle
		(center 233.817668 -128.824736)
		(end 234.706668 -128.824736)
		(stroke
			(width 0.2)
			(type default)
		)
		(fill no)
		(layer "In8.Cu")
	)
	(gr_circle
		(center 233.817668 -128.062736)
		(end 234.706668 -128.062736)
		(stroke
			(width 0.2)
			(type default)
		)
		(fill no)
		(layer "In8.Cu")
	)
	(gr_circle
		(center 233.817668 -127.300736)
		(end 234.706668 -127.300736)
		(stroke
			(width 0.2)
			(type default)
		)
		(fill no)
		(layer "In8.Cu")
	)
	(gr_circle
		(center 233.83113 -126.609094)
		(end 234.72013 -126.609094)
		(stroke
			(width 0.2)
			(type default)
		)
		(fill no)
		(layer "In8.Cu")
	)
	(gr_circle
		(center 233.831384 -131.829556)
		(end 234.720384 -131.829556)
		(stroke
			(width 0.2)
			(type default)
		)
		(fill no)
		(layer "In8.Cu")
	)
	(gr_circle
		(center 234.303316 -97.985834)
		(end 235.192316 -97.985834)
		(stroke
			(width 0.2)
			(type default)
		)
		(fill no)
		(layer "In8.Cu")
	)
	(gr_circle
		(center 234.579668 -131.110736)
		(end 235.468668 -131.110736)
		(stroke
			(width 0.2)
			(type default)
		)
		(fill no)
		(layer "In8.Cu")
	)
	(gr_circle
		(center 234.579668 -130.348736)
		(end 235.468668 -130.348736)
		(stroke
			(width 0.2)
			(type default)
		)
		(fill no)
		(layer "In8.Cu")
	)
	(gr_circle
		(center 234.579668 -129.586736)
		(end 235.468668 -129.586736)
		(stroke
			(width 0.2)
			(type default)
		)
		(fill no)
		(layer "In8.Cu")
	)
	(gr_circle
		(center 234.579668 -128.824736)
		(end 235.468668 -128.824736)
		(stroke
			(width 0.2)
			(type default)
		)
		(fill no)
		(layer "In8.Cu")
	)
	(gr_circle
		(center 234.579668 -128.062736)
		(end 235.468668 -128.062736)
		(stroke
			(width 0.2)
			(type default)
		)
		(fill no)
		(layer "In8.Cu")
	)
	(gr_circle
		(center 234.579668 -127.300736)
		(end 235.468668 -127.300736)
		(stroke
			(width 0.2)
			(type default)
		)
		(fill no)
		(layer "In8.Cu")
	)
	(gr_circle
		(center 234.59313 -126.609094)
		(end 235.48213 -126.609094)
		(stroke
			(width 0.2)
			(type default)
		)
		(fill no)
		(layer "In8.Cu")
	)
	(gr_circle
		(center 234.593384 -131.829556)
		(end 235.482384 -131.829556)
		(stroke
			(width 0.2)
			(type default)
		)
		(fill no)
		(layer "In8.Cu")
	)
	(gr_circle
		(center 235.065316 -97.985834)
		(end 235.954316 -97.985834)
		(stroke
			(width 0.2)
			(type default)
		)
		(fill no)
		(layer "In8.Cu")
	)
	(gr_circle
		(center 236.554518 -97.985834)
		(end 237.443518 -97.985834)
		(stroke
			(width 0.2)
			(type default)
		)
		(fill no)
		(layer "In8.Cu")
	)
	(gr_circle
		(center 237.316518 -97.985834)
		(end 238.205518 -97.985834)
		(stroke
			(width 0.2)
			(type default)
		)
		(fill no)
		(layer "In8.Cu")
	)
	(gr_circle
		(center 239.076738 -98.012758)
		(end 239.965738 -98.012758)
		(stroke
			(width 0.2)
			(type default)
		)
		(fill no)
		(layer "In8.Cu")
	)
	(gr_circle
		(center 239.838738 -98.012758)
		(end 240.727738 -98.012758)
		(stroke
			(width 0.2)
			(type default)
		)
		(fill no)
		(layer "In8.Cu")
	)
	(gr_circle
		(center 241.32794 -98.012758)
		(end 242.21694 -98.012758)
		(stroke
			(width 0.2)
			(type default)
		)
		(fill no)
		(layer "In8.Cu")
	)
	(gr_circle
		(center 242.08994 -98.012758)
		(end 242.97894 -98.012758)
		(stroke
			(width 0.2)
			(type default)
		)
		(fill no)
		(layer "In8.Cu")
	)
	(gr_circle
		(center 258.219956 -50.232818)
		(end 259.108956 -50.232818)
		(stroke
			(width 0.2)
			(type default)
		)
		(fill no)
		(layer "In8.Cu")
	)
	(gr_circle
		(center 258.219956 -48.327818)
		(end 259.108956 -48.327818)
		(stroke
			(width 0.2)
			(type default)
		)
		(fill no)
		(layer "In8.Cu")
	)
	(gr_circle
		(center 258.219956 -47.565818)
		(end 259.108956 -47.565818)
		(stroke
			(width 0.2)
			(type default)
		)
		(fill no)
		(layer "In8.Cu")
	)
	(gr_circle
		(center 258.530598 -39.18712)
		(end 259.419598 -39.18712)
		(stroke
			(width 0.2)
			(type default)
		)
		(fill no)
		(layer "In8.Cu")
	)
	(gr_circle
		(center 258.548886 -38.461696)
		(end 259.437886 -38.461696)
		(stroke
			(width 0.2)
			(type default)
		)
		(fill no)
		(layer "In8.Cu")
	)
	(gr_circle
		(center 258.83362 -40.72382)
		(end 259.72262 -40.72382)
		(stroke
			(width 0.2)
			(type default)
		)
		(fill no)
		(layer "In8.Cu")
	)
	(gr_circle
		(center 258.83616 -39.95674)
		(end 259.72516 -39.95674)
		(stroke
			(width 0.2)
			(type default)
		)
		(fill no)
		(layer "In8.Cu")
	)
	(gr_circle
		(center 259.0038 -42.3164)
		(end 259.8928 -42.3164)
		(stroke
			(width 0.2)
			(type default)
		)
		(fill no)
		(layer "In8.Cu")
	)
	(gr_circle
		(center 259.588 -43.4848)
		(end 260.477 -43.4848)
		(stroke
			(width 0.2)
			(type default)
		)
		(fill no)
		(layer "In8.Cu")
	)
	(gr_circle
		(center 259.630672 -41.092882)
		(end 260.519672 -41.092882)
		(stroke
			(width 0.2)
			(type default)
		)
		(fill no)
		(layer "In8.Cu")
	)
	(gr_circle
		(center 259.630672 -39.592758)
		(end 260.519672 -39.592758)
		(stroke
			(width 0.2)
			(type default)
		)
		(fill no)
		(layer "In8.Cu")
	)
	(gr_circle
		(center 260.182106 -37.2364)
		(end 261.071106 -37.2364)
		(stroke
			(width 0.2)
			(type default)
		)
		(fill no)
		(layer "In8.Cu")
	)
	(gr_circle
		(center 269.24 -125.857)
		(end 270.129 -125.857)
		(stroke
			(width 0.2)
			(type default)
		)
		(fill no)
		(layer "In8.Cu")
	)
	(gr_circle
		(center 269.24 -125.095)
		(end 270.129 -125.095)
		(stroke
			(width 0.2)
			(type default)
		)
		(fill no)
		(layer "In8.Cu")
	)
	(gr_circle
		(center 269.24 -124.333)
		(end 270.129 -124.333)
		(stroke
			(width 0.2)
			(type default)
		)
		(fill no)
		(layer "In8.Cu")
	)
	(gr_circle
		(center 269.24 -123.571)
		(end 270.129 -123.571)
		(stroke
			(width 0.2)
			(type default)
		)
		(fill no)
		(layer "In8.Cu")
	)
	(gr_circle
		(center 269.24 -122.809)
		(end 270.129 -122.809)
		(stroke
			(width 0.2)
			(type default)
		)
		(fill no)
		(layer "In8.Cu")
	)
	(gr_circle
		(center 269.24 -122.047)
		(end 270.129 -122.047)
		(stroke
			(width 0.2)
			(type default)
		)
		(fill no)
		(layer "In8.Cu")
	)
	(gr_circle
		(center 269.24 -113.792)
		(end 270.129 -113.792)
		(stroke
			(width 0.2)
			(type default)
		)
		(fill no)
		(layer "In8.Cu")
	)
	(gr_circle
		(center 269.24 -113.03)
		(end 270.129 -113.03)
		(stroke
			(width 0.2)
			(type default)
		)
		(fill no)
		(layer "In8.Cu")
	)
	(gr_circle
		(center 269.24 -112.268)
		(end 270.129 -112.268)
		(stroke
			(width 0.2)
			(type default)
		)
		(fill no)
		(layer "In8.Cu")
	)
	(gr_circle
		(center 269.24 -111.506)
		(end 270.129 -111.506)
		(stroke
			(width 0.2)
			(type default)
		)
		(fill no)
		(layer "In8.Cu")
	)
	(gr_circle
		(center 269.24 -110.744)
		(end 270.129 -110.744)
		(stroke
			(width 0.2)
			(type default)
		)
		(fill no)
		(layer "In8.Cu")
	)
	(gr_circle
		(center 269.24 -109.982)
		(end 270.129 -109.982)
		(stroke
			(width 0.2)
			(type default)
		)
		(fill no)
		(layer "In8.Cu")
	)
	(gr_circle
		(center 269.24 -101.727)
		(end 270.129 -101.727)
		(stroke
			(width 0.2)
			(type default)
		)
		(fill no)
		(layer "In8.Cu")
	)
	(gr_circle
		(center 269.24 -100.965)
		(end 270.129 -100.965)
		(stroke
			(width 0.2)
			(type default)
		)
		(fill no)
		(layer "In8.Cu")
	)
	(gr_circle
		(center 269.24 -100.203)
		(end 270.129 -100.203)
		(stroke
			(width 0.2)
			(type default)
		)
		(fill no)
		(layer "In8.Cu")
	)
	(gr_circle
		(center 269.24 -99.441)
		(end 270.129 -99.441)
		(stroke
			(width 0.2)
			(type default)
		)
		(fill no)
		(layer "In8.Cu")
	)
	(gr_circle
		(center 269.24 -98.679)
		(end 270.129 -98.679)
		(stroke
			(width 0.2)
			(type default)
		)
		(fill no)
		(layer "In8.Cu")
	)
	(gr_circle
		(center 269.24 -97.917)
		(end 270.129 -97.917)
		(stroke
			(width 0.2)
			(type default)
		)
		(fill no)
		(layer "In8.Cu")
	)
	(gr_circle
		(center 269.24 -89.662)
		(end 270.129 -89.662)
		(stroke
			(width 0.2)
			(type default)
		)
		(fill no)
		(layer "In8.Cu")
	)
	(gr_circle
		(center 269.24 -88.9)
		(end 270.129 -88.9)
		(stroke
			(width 0.2)
			(type default)
		)
		(fill no)
		(layer "In8.Cu")
	)
	(gr_circle
		(center 269.24 -88.138)
		(end 270.129 -88.138)
		(stroke
			(width 0.2)
			(type default)
		)
		(fill no)
		(layer "In8.Cu")
	)
	(gr_circle
		(center 269.24 -87.376)
		(end 270.129 -87.376)
		(stroke
			(width 0.2)
			(type default)
		)
		(fill no)
		(layer "In8.Cu")
	)
	(gr_circle
		(center 269.24 -86.614)
		(end 270.129 -86.614)
		(stroke
			(width 0.2)
			(type default)
		)
		(fill no)
		(layer "In8.Cu")
	)
	(gr_circle
		(center 269.24 -85.852)
		(end 270.129 -85.852)
		(stroke
			(width 0.2)
			(type default)
		)
		(fill no)
		(layer "In8.Cu")
	)
	(gr_circle
		(center 269.24 -77.597)
		(end 270.129 -77.597)
		(stroke
			(width 0.2)
			(type default)
		)
		(fill no)
		(layer "In8.Cu")
	)
	(gr_circle
		(center 269.24 -76.835)
		(end 270.129 -76.835)
		(stroke
			(width 0.2)
			(type default)
		)
		(fill no)
		(layer "In8.Cu")
	)
	(gr_circle
		(center 269.24 -76.073)
		(end 270.129 -76.073)
		(stroke
			(width 0.2)
			(type default)
		)
		(fill no)
		(layer "In8.Cu")
	)
	(gr_circle
		(center 269.24 -75.311)
		(end 270.129 -75.311)
		(stroke
			(width 0.2)
			(type default)
		)
		(fill no)
		(layer "In8.Cu")
	)
	(gr_circle
		(center 269.24 -74.549)
		(end 270.129 -74.549)
		(stroke
			(width 0.2)
			(type default)
		)
		(fill no)
		(layer "In8.Cu")
	)
	(gr_circle
		(center 269.24 -73.787)
		(end 270.129 -73.787)
		(stroke
			(width 0.2)
			(type default)
		)
		(fill no)
		(layer "In8.Cu")
	)
	(gr_circle
		(center 269.24 -65.532)
		(end 270.129 -65.532)
		(stroke
			(width 0.2)
			(type default)
		)
		(fill no)
		(layer "In8.Cu")
	)
	(gr_circle
		(center 269.24 -64.77)
		(end 270.129 -64.77)
		(stroke
			(width 0.2)
			(type default)
		)
		(fill no)
		(layer "In8.Cu")
	)
	(gr_circle
		(center 269.24 -64.008)
		(end 270.129 -64.008)
		(stroke
			(width 0.2)
			(type default)
		)
		(fill no)
		(layer "In8.Cu")
	)
	(gr_circle
		(center 269.24 -63.246)
		(end 270.129 -63.246)
		(stroke
			(width 0.2)
			(type default)
		)
		(fill no)
		(layer "In8.Cu")
	)
	(gr_circle
		(center 269.24 -62.484)
		(end 270.129 -62.484)
		(stroke
			(width 0.2)
			(type default)
		)
		(fill no)
		(layer "In8.Cu")
	)
	(gr_circle
		(center 269.24 -61.722)
		(end 270.129 -61.722)
		(stroke
			(width 0.2)
			(type default)
		)
		(fill no)
		(layer "In8.Cu")
	)
	(gr_circle
		(center 270.002 -125.857)
		(end 270.891 -125.857)
		(stroke
			(width 0.2)
			(type default)
		)
		(fill no)
		(layer "In8.Cu")
	)
	(gr_circle
		(center 270.002 -125.095)
		(end 270.891 -125.095)
		(stroke
			(width 0.2)
			(type default)
		)
		(fill no)
		(layer "In8.Cu")
	)
	(gr_circle
		(center 270.002 -124.333)
		(end 270.891 -124.333)
		(stroke
			(width 0.2)
			(type default)
		)
		(fill no)
		(layer "In8.Cu")
	)
	(gr_circle
		(center 270.002 -123.571)
		(end 270.891 -123.571)
		(stroke
			(width 0.2)
			(type default)
		)
		(fill no)
		(layer "In8.Cu")
	)
	(gr_circle
		(center 270.002 -122.809)
		(end 270.891 -122.809)
		(stroke
			(width 0.2)
			(type default)
		)
		(fill no)
		(layer "In8.Cu")
	)
	(gr_circle
		(center 270.002 -122.047)
		(end 270.891 -122.047)
		(stroke
			(width 0.2)
			(type default)
		)
		(fill no)
		(layer "In8.Cu")
	)
	(gr_circle
		(center 270.002 -113.792)
		(end 270.891 -113.792)
		(stroke
			(width 0.2)
			(type default)
		)
		(fill no)
		(layer "In8.Cu")
	)
	(gr_circle
		(center 270.002 -113.03)
		(end 270.891 -113.03)
		(stroke
			(width 0.2)
			(type default)
		)
		(fill no)
		(layer "In8.Cu")
	)
	(gr_circle
		(center 270.002 -112.268)
		(end 270.891 -112.268)
		(stroke
			(width 0.2)
			(type default)
		)
		(fill no)
		(layer "In8.Cu")
	)
	(gr_circle
		(center 270.002 -111.506)
		(end 270.891 -111.506)
		(stroke
			(width 0.2)
			(type default)
		)
		(fill no)
		(layer "In8.Cu")
	)
	(gr_circle
		(center 270.002 -110.744)
		(end 270.891 -110.744)
		(stroke
			(width 0.2)
			(type default)
		)
		(fill no)
		(layer "In8.Cu")
	)
	(gr_circle
		(center 270.002 -109.982)
		(end 270.891 -109.982)
		(stroke
			(width 0.2)
			(type default)
		)
		(fill no)
		(layer "In8.Cu")
	)
	(gr_circle
		(center 270.002 -101.727)
		(end 270.891 -101.727)
		(stroke
			(width 0.2)
			(type default)
		)
		(fill no)
		(layer "In8.Cu")
	)
	(gr_circle
		(center 270.002 -100.965)
		(end 270.891 -100.965)
		(stroke
			(width 0.2)
			(type default)
		)
		(fill no)
		(layer "In8.Cu")
	)
	(gr_circle
		(center 270.002 -100.203)
		(end 270.891 -100.203)
		(stroke
			(width 0.2)
			(type default)
		)
		(fill no)
		(layer "In8.Cu")
	)
	(gr_circle
		(center 270.002 -99.441)
		(end 270.891 -99.441)
		(stroke
			(width 0.2)
			(type default)
		)
		(fill no)
		(layer "In8.Cu")
	)
	(gr_circle
		(center 270.002 -98.679)
		(end 270.891 -98.679)
		(stroke
			(width 0.2)
			(type default)
		)
		(fill no)
		(layer "In8.Cu")
	)
	(gr_circle
		(center 270.002 -97.917)
		(end 270.891 -97.917)
		(stroke
			(width 0.2)
			(type default)
		)
		(fill no)
		(layer "In8.Cu")
	)
	(gr_circle
		(center 270.002 -89.662)
		(end 270.891 -89.662)
		(stroke
			(width 0.2)
			(type default)
		)
		(fill no)
		(layer "In8.Cu")
	)
	(gr_circle
		(center 270.002 -88.9)
		(end 270.891 -88.9)
		(stroke
			(width 0.2)
			(type default)
		)
		(fill no)
		(layer "In8.Cu")
	)
	(gr_circle
		(center 270.002 -88.138)
		(end 270.891 -88.138)
		(stroke
			(width 0.2)
			(type default)
		)
		(fill no)
		(layer "In8.Cu")
	)
	(gr_circle
		(center 270.002 -87.376)
		(end 270.891 -87.376)
		(stroke
			(width 0.2)
			(type default)
		)
		(fill no)
		(layer "In8.Cu")
	)
	(gr_circle
		(center 270.002 -86.614)
		(end 270.891 -86.614)
		(stroke
			(width 0.2)
			(type default)
		)
		(fill no)
		(layer "In8.Cu")
	)
	(gr_circle
		(center 270.002 -85.852)
		(end 270.891 -85.852)
		(stroke
			(width 0.2)
			(type default)
		)
		(fill no)
		(layer "In8.Cu")
	)
	(gr_circle
		(center 270.002 -77.597)
		(end 270.891 -77.597)
		(stroke
			(width 0.2)
			(type default)
		)
		(fill no)
		(layer "In8.Cu")
	)
	(gr_circle
		(center 270.002 -76.835)
		(end 270.891 -76.835)
		(stroke
			(width 0.2)
			(type default)
		)
		(fill no)
		(layer "In8.Cu")
	)
	(gr_circle
		(center 270.002 -76.073)
		(end 270.891 -76.073)
		(stroke
			(width 0.2)
			(type default)
		)
		(fill no)
		(layer "In8.Cu")
	)
	(gr_circle
		(center 270.002 -75.311)
		(end 270.891 -75.311)
		(stroke
			(width 0.2)
			(type default)
		)
		(fill no)
		(layer "In8.Cu")
	)
	(gr_circle
		(center 270.002 -74.549)
		(end 270.891 -74.549)
		(stroke
			(width 0.2)
			(type default)
		)
		(fill no)
		(layer "In8.Cu")
	)
	(gr_circle
		(center 270.002 -73.787)
		(end 270.891 -73.787)
		(stroke
			(width 0.2)
			(type default)
		)
		(fill no)
		(layer "In8.Cu")
	)
	(gr_circle
		(center 270.002 -65.532)
		(end 270.891 -65.532)
		(stroke
			(width 0.2)
			(type default)
		)
		(fill no)
		(layer "In8.Cu")
	)
	(gr_circle
		(center 270.002 -64.77)
		(end 270.891 -64.77)
		(stroke
			(width 0.2)
			(type default)
		)
		(fill no)
		(layer "In8.Cu")
	)
	(gr_circle
		(center 270.002 -64.008)
		(end 270.891 -64.008)
		(stroke
			(width 0.2)
			(type default)
		)
		(fill no)
		(layer "In8.Cu")
	)
	(gr_circle
		(center 270.002 -63.246)
		(end 270.891 -63.246)
		(stroke
			(width 0.2)
			(type default)
		)
		(fill no)
		(layer "In8.Cu")
	)
	(gr_circle
		(center 270.002 -62.484)
		(end 270.891 -62.484)
		(stroke
			(width 0.2)
			(type default)
		)
		(fill no)
		(layer "In8.Cu")
	)
	(gr_circle
		(center 270.002 -61.722)
		(end 270.891 -61.722)
		(stroke
			(width 0.2)
			(type default)
		)
		(fill no)
		(layer "In8.Cu")
	)
	(gr_circle
		(center 270.764 -125.857)
		(end 271.653 -125.857)
		(stroke
			(width 0.2)
			(type default)
		)
		(fill no)
		(layer "In8.Cu")
	)
	(gr_circle
		(center 270.764 -125.095)
		(end 271.653 -125.095)
		(stroke
			(width 0.2)
			(type default)
		)
		(fill no)
		(layer "In8.Cu")
	)
	(gr_circle
		(center 270.764 -124.333)
		(end 271.653 -124.333)
		(stroke
			(width 0.2)
			(type default)
		)
		(fill no)
		(layer "In8.Cu")
	)
	(gr_circle
		(center 270.764 -123.571)
		(end 271.653 -123.571)
		(stroke
			(width 0.2)
			(type default)
		)
		(fill no)
		(layer "In8.Cu")
	)
	(gr_circle
		(center 270.764 -122.809)
		(end 271.653 -122.809)
		(stroke
			(width 0.2)
			(type default)
		)
		(fill no)
		(layer "In8.Cu")
	)
	(gr_circle
		(center 270.764 -122.047)
		(end 271.653 -122.047)
		(stroke
			(width 0.2)
			(type default)
		)
		(fill no)
		(layer "In8.Cu")
	)
	(gr_circle
		(center 270.764 -113.792)
		(end 271.653 -113.792)
		(stroke
			(width 0.2)
			(type default)
		)
		(fill no)
		(layer "In8.Cu")
	)
	(gr_circle
		(center 270.764 -113.03)
		(end 271.653 -113.03)
		(stroke
			(width 0.2)
			(type default)
		)
		(fill no)
		(layer "In8.Cu")
	)
	(gr_circle
		(center 270.764 -112.268)
		(end 271.653 -112.268)
		(stroke
			(width 0.2)
			(type default)
		)
		(fill no)
		(layer "In8.Cu")
	)
	(gr_circle
		(center 270.764 -111.506)
		(end 271.653 -111.506)
		(stroke
			(width 0.2)
			(type default)
		)
		(fill no)
		(layer "In8.Cu")
	)
	(gr_circle
		(center 270.764 -110.744)
		(end 271.653 -110.744)
		(stroke
			(width 0.2)
			(type default)
		)
		(fill no)
		(layer "In8.Cu")
	)
	(gr_circle
		(center 270.764 -109.982)
		(end 271.653 -109.982)
		(stroke
			(width 0.2)
			(type default)
		)
		(fill no)
		(layer "In8.Cu")
	)
	(gr_circle
		(center 270.764 -101.727)
		(end 271.653 -101.727)
		(stroke
			(width 0.2)
			(type default)
		)
		(fill no)
		(layer "In8.Cu")
	)
	(gr_circle
		(center 270.764 -100.965)
		(end 271.653 -100.965)
		(stroke
			(width 0.2)
			(type default)
		)
		(fill no)
		(layer "In8.Cu")
	)
	(gr_circle
		(center 270.764 -100.203)
		(end 271.653 -100.203)
		(stroke
			(width 0.2)
			(type default)
		)
		(fill no)
		(layer "In8.Cu")
	)
	(gr_circle
		(center 270.764 -99.441)
		(end 271.653 -99.441)
		(stroke
			(width 0.2)
			(type default)
		)
		(fill no)
		(layer "In8.Cu")
	)
	(gr_circle
		(center 270.764 -98.679)
		(end 271.653 -98.679)
		(stroke
			(width 0.2)
			(type default)
		)
		(fill no)
		(layer "In8.Cu")
	)
	(gr_circle
		(center 270.764 -97.917)
		(end 271.653 -97.917)
		(stroke
			(width 0.2)
			(type default)
		)
		(fill no)
		(layer "In8.Cu")
	)
	(gr_circle
		(center 270.764 -89.662)
		(end 271.653 -89.662)
		(stroke
			(width 0.2)
			(type default)
		)
		(fill no)
		(layer "In8.Cu")
	)
	(gr_circle
		(center 270.764 -88.9)
		(end 271.653 -88.9)
		(stroke
			(width 0.2)
			(type default)
		)
		(fill no)
		(layer "In8.Cu")
	)
	(gr_circle
		(center 270.764 -88.138)
		(end 271.653 -88.138)
		(stroke
			(width 0.2)
			(type default)
		)
		(fill no)
		(layer "In8.Cu")
	)
	(gr_circle
		(center 270.764 -87.376)
		(end 271.653 -87.376)
		(stroke
			(width 0.2)
			(type default)
		)
		(fill no)
		(layer "In8.Cu")
	)
	(gr_circle
		(center 270.764 -86.614)
		(end 271.653 -86.614)
		(stroke
			(width 0.2)
			(type default)
		)
		(fill no)
		(layer "In8.Cu")
	)
	(gr_circle
		(center 270.764 -85.852)
		(end 271.653 -85.852)
		(stroke
			(width 0.2)
			(type default)
		)
		(fill no)
		(layer "In8.Cu")
	)
	(gr_circle
		(center 270.764 -77.597)
		(end 271.653 -77.597)
		(stroke
			(width 0.2)
			(type default)
		)
		(fill no)
		(layer "In8.Cu")
	)
	(gr_circle
		(center 270.764 -76.835)
		(end 271.653 -76.835)
		(stroke
			(width 0.2)
			(type default)
		)
		(fill no)
		(layer "In8.Cu")
	)
	(gr_circle
		(center 270.764 -76.073)
		(end 271.653 -76.073)
		(stroke
			(width 0.2)
			(type default)
		)
		(fill no)
		(layer "In8.Cu")
	)
	(gr_circle
		(center 270.764 -75.311)
		(end 271.653 -75.311)
		(stroke
			(width 0.2)
			(type default)
		)
		(fill no)
		(layer "In8.Cu")
	)
	(gr_circle
		(center 270.764 -74.549)
		(end 271.653 -74.549)
		(stroke
			(width 0.2)
			(type default)
		)
		(fill no)
		(layer "In8.Cu")
	)
	(gr_circle
		(center 270.764 -73.787)
		(end 271.653 -73.787)
		(stroke
			(width 0.2)
			(type default)
		)
		(fill no)
		(layer "In8.Cu")
	)
	(gr_circle
		(center 270.764 -65.532)
		(end 271.653 -65.532)
		(stroke
			(width 0.2)
			(type default)
		)
		(fill no)
		(layer "In8.Cu")
	)
	(gr_circle
		(center 270.764 -64.77)
		(end 271.653 -64.77)
		(stroke
			(width 0.2)
			(type default)
		)
		(fill no)
		(layer "In8.Cu")
	)
	(gr_circle
		(center 270.764 -64.008)
		(end 271.653 -64.008)
		(stroke
			(width 0.2)
			(type default)
		)
		(fill no)
		(layer "In8.Cu")
	)
	(gr_circle
		(center 270.764 -63.246)
		(end 271.653 -63.246)
		(stroke
			(width 0.2)
			(type default)
		)
		(fill no)
		(layer "In8.Cu")
	)
	(gr_circle
		(center 270.764 -62.484)
		(end 271.653 -62.484)
		(stroke
			(width 0.2)
			(type default)
		)
		(fill no)
		(layer "In8.Cu")
	)
	(gr_circle
		(center 270.764 -61.722)
		(end 271.653 -61.722)
		(stroke
			(width 0.2)
			(type default)
		)
		(fill no)
		(layer "In8.Cu")
	)
	(gr_circle
		(center 270.891 -140.462)
		(end 271.78 -140.462)
		(stroke
			(width 0.2)
			(type default)
		)
		(fill no)
		(layer "In8.Cu")
	)
	(gr_circle
		(center 270.891 -139.7)
		(end 271.78 -139.7)
		(stroke
			(width 0.2)
			(type default)
		)
		(fill no)
		(layer "In8.Cu")
	)
	(gr_circle
		(center 270.891 -138.938)
		(end 271.78 -138.938)
		(stroke
			(width 0.2)
			(type default)
		)
		(fill no)
		(layer "In8.Cu")
	)
	(gr_circle
		(center 270.891 -138.176)
		(end 271.78 -138.176)
		(stroke
			(width 0.2)
			(type default)
		)
		(fill no)
		(layer "In8.Cu")
	)
	(gr_circle
		(center 270.891 -137.414)
		(end 271.78 -137.414)
		(stroke
			(width 0.2)
			(type default)
		)
		(fill no)
		(layer "In8.Cu")
	)
	(gr_circle
		(center 270.891 -136.652)
		(end 271.78 -136.652)
		(stroke
			(width 0.2)
			(type default)
		)
		(fill no)
		(layer "In8.Cu")
	)
	(gr_circle
		(center 271.526 -125.857)
		(end 272.415 -125.857)
		(stroke
			(width 0.2)
			(type default)
		)
		(fill no)
		(layer "In8.Cu")
	)
	(gr_circle
		(center 271.526 -125.095)
		(end 272.415 -125.095)
		(stroke
			(width 0.2)
			(type default)
		)
		(fill no)
		(layer "In8.Cu")
	)
	(gr_circle
		(center 271.526 -122.809)
		(end 272.415 -122.809)
		(stroke
			(width 0.2)
			(type default)
		)
		(fill no)
		(layer "In8.Cu")
	)
	(gr_circle
		(center 271.526 -122.047)
		(end 272.415 -122.047)
		(stroke
			(width 0.2)
			(type default)
		)
		(fill no)
		(layer "In8.Cu")
	)
	(gr_circle
		(center 271.526 -113.792)
		(end 272.415 -113.792)
		(stroke
			(width 0.2)
			(type default)
		)
		(fill no)
		(layer "In8.Cu")
	)
	(gr_circle
		(center 271.526 -113.03)
		(end 272.415 -113.03)
		(stroke
			(width 0.2)
			(type default)
		)
		(fill no)
		(layer "In8.Cu")
	)
	(gr_circle
		(center 271.526 -110.744)
		(end 272.415 -110.744)
		(stroke
			(width 0.2)
			(type default)
		)
		(fill no)
		(layer "In8.Cu")
	)
	(gr_circle
		(center 271.526 -109.982)
		(end 272.415 -109.982)
		(stroke
			(width 0.2)
			(type default)
		)
		(fill no)
		(layer "In8.Cu")
	)
	(gr_circle
		(center 271.526 -101.727)
		(end 272.415 -101.727)
		(stroke
			(width 0.2)
			(type default)
		)
		(fill no)
		(layer "In8.Cu")
	)
	(gr_circle
		(center 271.526 -100.965)
		(end 272.415 -100.965)
		(stroke
			(width 0.2)
			(type default)
		)
		(fill no)
		(layer "In8.Cu")
	)
	(gr_circle
		(center 271.526 -98.679)
		(end 272.415 -98.679)
		(stroke
			(width 0.2)
			(type default)
		)
		(fill no)
		(layer "In8.Cu")
	)
	(gr_circle
		(center 271.526 -97.917)
		(end 272.415 -97.917)
		(stroke
			(width 0.2)
			(type default)
		)
		(fill no)
		(layer "In8.Cu")
	)
	(gr_circle
		(center 271.526 -89.662)
		(end 272.415 -89.662)
		(stroke
			(width 0.2)
			(type default)
		)
		(fill no)
		(layer "In8.Cu")
	)
	(gr_circle
		(center 271.526 -88.9)
		(end 272.415 -88.9)
		(stroke
			(width 0.2)
			(type default)
		)
		(fill no)
		(layer "In8.Cu")
	)
	(gr_circle
		(center 271.526 -86.614)
		(end 272.415 -86.614)
		(stroke
			(width 0.2)
			(type default)
		)
		(fill no)
		(layer "In8.Cu")
	)
	(gr_circle
		(center 271.526 -85.852)
		(end 272.415 -85.852)
		(stroke
			(width 0.2)
			(type default)
		)
		(fill no)
		(layer "In8.Cu")
	)
	(gr_circle
		(center 271.526 -77.597)
		(end 272.415 -77.597)
		(stroke
			(width 0.2)
			(type default)
		)
		(fill no)
		(layer "In8.Cu")
	)
	(gr_circle
		(center 271.526 -76.835)
		(end 272.415 -76.835)
		(stroke
			(width 0.2)
			(type default)
		)
		(fill no)
		(layer "In8.Cu")
	)
	(gr_circle
		(center 271.526 -74.549)
		(end 272.415 -74.549)
		(stroke
			(width 0.2)
			(type default)
		)
		(fill no)
		(layer "In8.Cu")
	)
	(gr_circle
		(center 271.526 -73.787)
		(end 272.415 -73.787)
		(stroke
			(width 0.2)
			(type default)
		)
		(fill no)
		(layer "In8.Cu")
	)
	(gr_circle
		(center 271.526 -65.532)
		(end 272.415 -65.532)
		(stroke
			(width 0.2)
			(type default)
		)
		(fill no)
		(layer "In8.Cu")
	)
	(gr_circle
		(center 271.526 -64.77)
		(end 272.415 -64.77)
		(stroke
			(width 0.2)
			(type default)
		)
		(fill no)
		(layer "In8.Cu")
	)
	(gr_circle
		(center 271.526 -62.484)
		(end 272.415 -62.484)
		(stroke
			(width 0.2)
			(type default)
		)
		(fill no)
		(layer "In8.Cu")
	)
	(gr_circle
		(center 271.526 -61.722)
		(end 272.415 -61.722)
		(stroke
			(width 0.2)
			(type default)
		)
		(fill no)
		(layer "In8.Cu")
	)
	(gr_circle
		(center 271.653 -140.462)
		(end 272.542 -140.462)
		(stroke
			(width 0.2)
			(type default)
		)
		(fill no)
		(layer "In8.Cu")
	)
	(gr_circle
		(center 271.653 -139.7)
		(end 272.542 -139.7)
		(stroke
			(width 0.2)
			(type default)
		)
		(fill no)
		(layer "In8.Cu")
	)
	(gr_circle
		(center 271.653 -138.938)
		(end 272.542 -138.938)
		(stroke
			(width 0.2)
			(type default)
		)
		(fill no)
		(layer "In8.Cu")
	)
	(gr_circle
		(center 271.653 -138.176)
		(end 272.542 -138.176)
		(stroke
			(width 0.2)
			(type default)
		)
		(fill no)
		(layer "In8.Cu")
	)
	(gr_circle
		(center 271.653 -137.414)
		(end 272.542 -137.414)
		(stroke
			(width 0.2)
			(type default)
		)
		(fill no)
		(layer "In8.Cu")
	)
	(gr_circle
		(center 271.653 -136.652)
		(end 272.542 -136.652)
		(stroke
			(width 0.2)
			(type default)
		)
		(fill no)
		(layer "In8.Cu")
	)
	(gr_circle
		(center 272.288 -125.857)
		(end 273.177 -125.857)
		(stroke
			(width 0.2)
			(type default)
		)
		(fill no)
		(layer "In8.Cu")
	)
	(gr_circle
		(center 272.288 -125.095)
		(end 273.177 -125.095)
		(stroke
			(width 0.2)
			(type default)
		)
		(fill no)
		(layer "In8.Cu")
	)
	(gr_circle
		(center 272.288 -122.809)
		(end 273.177 -122.809)
		(stroke
			(width 0.2)
			(type default)
		)
		(fill no)
		(layer "In8.Cu")
	)
	(gr_circle
		(center 272.288 -122.047)
		(end 273.177 -122.047)
		(stroke
			(width 0.2)
			(type default)
		)
		(fill no)
		(layer "In8.Cu")
	)
	(gr_circle
		(center 272.288 -113.792)
		(end 273.177 -113.792)
		(stroke
			(width 0.2)
			(type default)
		)
		(fill no)
		(layer "In8.Cu")
	)
	(gr_circle
		(center 272.288 -113.03)
		(end 273.177 -113.03)
		(stroke
			(width 0.2)
			(type default)
		)
		(fill no)
		(layer "In8.Cu")
	)
	(gr_circle
		(center 272.288 -110.744)
		(end 273.177 -110.744)
		(stroke
			(width 0.2)
			(type default)
		)
		(fill no)
		(layer "In8.Cu")
	)
	(gr_circle
		(center 272.288 -109.982)
		(end 273.177 -109.982)
		(stroke
			(width 0.2)
			(type default)
		)
		(fill no)
		(layer "In8.Cu")
	)
	(gr_circle
		(center 272.288 -101.727)
		(end 273.177 -101.727)
		(stroke
			(width 0.2)
			(type default)
		)
		(fill no)
		(layer "In8.Cu")
	)
	(gr_circle
		(center 272.288 -100.965)
		(end 273.177 -100.965)
		(stroke
			(width 0.2)
			(type default)
		)
		(fill no)
		(layer "In8.Cu")
	)
	(gr_circle
		(center 272.288 -98.679)
		(end 273.177 -98.679)
		(stroke
			(width 0.2)
			(type default)
		)
		(fill no)
		(layer "In8.Cu")
	)
	(gr_circle
		(center 272.288 -97.917)
		(end 273.177 -97.917)
		(stroke
			(width 0.2)
			(type default)
		)
		(fill no)
		(layer "In8.Cu")
	)
	(gr_circle
		(center 272.288 -89.662)
		(end 273.177 -89.662)
		(stroke
			(width 0.2)
			(type default)
		)
		(fill no)
		(layer "In8.Cu")
	)
	(gr_circle
		(center 272.288 -88.9)
		(end 273.177 -88.9)
		(stroke
			(width 0.2)
			(type default)
		)
		(fill no)
		(layer "In8.Cu")
	)
	(gr_circle
		(center 272.288 -86.614)
		(end 273.177 -86.614)
		(stroke
			(width 0.2)
			(type default)
		)
		(fill no)
		(layer "In8.Cu")
	)
	(gr_circle
		(center 272.288 -85.852)
		(end 273.177 -85.852)
		(stroke
			(width 0.2)
			(type default)
		)
		(fill no)
		(layer "In8.Cu")
	)
	(gr_circle
		(center 272.288 -77.597)
		(end 273.177 -77.597)
		(stroke
			(width 0.2)
			(type default)
		)
		(fill no)
		(layer "In8.Cu")
	)
	(gr_circle
		(center 272.288 -76.835)
		(end 273.177 -76.835)
		(stroke
			(width 0.2)
			(type default)
		)
		(fill no)
		(layer "In8.Cu")
	)
	(gr_circle
		(center 272.288 -74.549)
		(end 273.177 -74.549)
		(stroke
			(width 0.2)
			(type default)
		)
		(fill no)
		(layer "In8.Cu")
	)
	(gr_circle
		(center 272.288 -73.787)
		(end 273.177 -73.787)
		(stroke
			(width 0.2)
			(type default)
		)
		(fill no)
		(layer "In8.Cu")
	)
	(gr_circle
		(center 272.288 -65.532)
		(end 273.177 -65.532)
		(stroke
			(width 0.2)
			(type default)
		)
		(fill no)
		(layer "In8.Cu")
	)
	(gr_circle
		(center 272.288 -64.77)
		(end 273.177 -64.77)
		(stroke
			(width 0.2)
			(type default)
		)
		(fill no)
		(layer "In8.Cu")
	)
	(gr_circle
		(center 272.288 -62.484)
		(end 273.177 -62.484)
		(stroke
			(width 0.2)
			(type default)
		)
		(fill no)
		(layer "In8.Cu")
	)
	(gr_circle
		(center 272.288 -61.722)
		(end 273.177 -61.722)
		(stroke
			(width 0.2)
			(type default)
		)
		(fill no)
		(layer "In8.Cu")
	)
	(gr_circle
		(center 272.5928 -23.0886)
		(end 273.4818 -23.0886)
		(stroke
			(width 0.2)
			(type default)
		)
		(fill no)
		(layer "In8.Cu")
	)
	(gr_circle
		(center 273.6088 -23.0886)
		(end 274.4978 -23.0886)
		(stroke
			(width 0.2)
			(type default)
		)
		(fill no)
		(layer "In8.Cu")
	)
	(gr_circle
		(center 275.41855 -33.070038)
		(end 276.30755 -33.070038)
		(stroke
			(width 0.2)
			(type default)
		)
		(fill no)
		(layer "In8.Cu")
	)
	(gr_circle
		(center 277.368 -20.955)
		(end 278.257 -20.955)
		(stroke
			(width 0.2)
			(type default)
		)
		(fill no)
		(layer "In8.Cu")
	)
	(gr_line
		(start 278.19985 -131.594352)
		(end 278.19985 -61.165994)
		(stroke
			(width 1.016)
			(type default)
		)
		(layer "In8.Cu")
	)
	(gr_line
		(start 278.19985 -97.85985)
		(end 279.6921 -96.3676)
		(stroke
			(width 1.016)
			(type default)
		)
		(layer "In8.Cu")
	)
	(gr_line
		(start 278.19985 -94.87535)
		(end 279.6921 -96.3676)
		(stroke
			(width 1.016)
			(type default)
		)
		(layer "In8.Cu")
	)
	(gr_line
		(start 278.19985 -61.165994)
		(end 278.19985 -55.65775)
		(stroke
			(width 1.016)
			(type default)
		)
		(layer "In8.Cu")
	)
	(gr_line
		(start 278.19985 -55.65775)
		(end 278.19985 -52.12715)
		(stroke
			(width 1.016)
			(type default)
		)
		(layer "In8.Cu")
	)
	(gr_line
		(start 278.19985 -55.65775)
		(end 279.648666 -57.106566)
		(stroke
			(width 1.016)
			(type default)
		)
		(layer "In8.Cu")
	)
	(gr_line
		(start 278.326342 -58.394854)
		(end 279.648666 -59.717178)
		(stroke
			(width 1.016)
			(type default)
		)
		(layer "In8.Cu")
	)
	(gr_line
		(start 278.326342 -58.027062)
		(end 278.326342 -58.394854)
		(stroke
			(width 1.016)
			(type default)
		)
		(layer "In8.Cu")
	)
	(gr_line
		(start 278.326342 -58.027062)
		(end 295.422574 -58.027062)
		(stroke
			(width 1.016)
			(type default)
		)
		(layer "In8.Cu")
	)
	(gr_line
		(start 278.34971 -57.345072)
		(end 295.070022 -57.345072)
		(stroke
			(width 1.016)
			(type default)
		)
		(layer "In8.Cu")
	)
	(gr_line
		(start 278.44369 -60.00242)
		(end 278.44369 -59.838082)
		(stroke
			(width 1.016)
			(type default)
		)
		(layer "In8.Cu")
	)
	(gr_line
		(start 278.44369 -59.838082)
		(end 279.619964 -58.661808)
		(stroke
			(width 1.016)
			(type default)
		)
		(layer "In8.Cu")
	)
	(gr_line
		(start 279.007316 -55.444136)
		(end 279.007316 -52.168044)
		(stroke
			(width 1.016)
			(type default)
		)
		(layer "In8.Cu")
	)
	(gr_line
		(start 279.007316 -52.168044)
		(end 281.543252 -49.632108)
		(stroke
			(width 1.016)
			(type default)
		)
		(layer "In8.Cu")
	)
	(gr_line
		(start 279.0571 -56.515)
		(end 278.19985 -55.65775)
		(stroke
			(width 1.016)
			(type default)
		)
		(layer "In8.Cu")
	)
	(gr_line
		(start 279.290526 -58.991246)
		(end 278.326342 -58.027062)
		(stroke
			(width 1.016)
			(type default)
		)
		(layer "In8.Cu")
	)
	(gr_line
		(start 279.297638 -55.734458)
		(end 279.007316 -55.444136)
		(stroke
			(width 1.016)
			(type default)
		)
		(layer "In8.Cu")
	)
	(gr_line
		(start 279.565862 -132.960364)
		(end 278.19985 -131.594352)
		(stroke
			(width 1.016)
			(type default)
		)
		(layer "In8.Cu")
	)
	(gr_line
		(start 279.619964 -58.661808)
		(end 296.386758 -58.661808)
		(stroke
			(width 1.016)
			(type default)
		)
		(layer "In8.Cu")
	)
	(gr_line
		(start 279.648666 -59.717178)
		(end 278.19985 -61.165994)
		(stroke
			(width 1.016)
			(type default)
		)
		(layer "In8.Cu")
	)
	(gr_line
		(start 279.648666 -59.717178)
		(end 291.200078 -59.717178)
		(stroke
			(width 1.016)
			(type default)
		)
		(layer "In8.Cu")
	)
	(gr_line
		(start 279.681178 -54.9021)
		(end 279.681178 -52.676044)
		(stroke
			(width 1.016)
			(type default)
		)
		(layer "In8.Cu")
	)
	(gr_line
		(start 279.681178 -52.676044)
		(end 281.86253 -50.494692)
		(stroke
			(width 1.016)
			(type default)
		)
		(layer "In8.Cu")
	)
	(gr_line
		(start 279.879806 -55.100728)
		(end 279.681178 -54.9021)
		(stroke
			(width 1.016)
			(type default)
		)
		(layer "In8.Cu")
	)
	(gr_line
		(start 280.315162 -54.457854)
		(end 280.315162 -53.123846)
		(stroke
			(width 1.016)
			(type default)
		)
		(layer "In8.Cu")
	)
	(gr_line
		(start 280.315162 -53.123846)
		(end 282.16479 -51.274218)
		(stroke
			(width 1.016)
			(type default)
		)
		(layer "In8.Cu")
	)
	(gr_line
		(start 280.486866 -54.629558)
		(end 280.315162 -54.457854)
		(stroke
			(width 1.016)
			(type default)
		)
		(layer "In8.Cu")
	)
	(gr_line
		(start 280.790904 -53.783992)
		(end 280.790904 -53.572664)
		(stroke
			(width 1.016)
			(type default)
		)
		(layer "In8.Cu")
	)
	(gr_line
		(start 280.790904 -53.572664)
		(end 282.468574 -51.894994)
		(stroke
			(width 1.016)
			(type default)
		)
		(layer "In8.Cu")
	)
	(gr_line
		(start 281.028648 -54.021736)
		(end 280.790904 -53.783992)
		(stroke
			(width 1.016)
			(type default)
		)
		(layer "In8.Cu")
	)
	(gr_line
		(start 281.3558 -48.9712)
		(end 278.19985 -52.12715)
		(stroke
			(width 1.016)
			(type default)
		)
		(layer "In8.Cu")
	)
	(gr_line
		(start 281.432 -48.895)
		(end 281.3558 -48.9712)
		(stroke
			(width 1.016)
			(type default)
		)
		(layer "In8.Cu")
	)
	(gr_line
		(start 281.543252 -49.632108)
		(end 291.61105 -49.632108)
		(stroke
			(width 1.016)
			(type default)
		)
		(layer "In8.Cu")
	)
	(gr_line
		(start 281.570176 -53.427376)
		(end 282.442158 -52.555394)
		(stroke
			(width 1.016)
			(type default)
		)
		(layer "In8.Cu")
	)
	(gr_line
		(start 281.86253 -50.494692)
		(end 289.747452 -50.494692)
		(stroke
			(width 1.016)
			(type default)
		)
		(layer "In8.Cu")
	)
	(gr_line
		(start 282.16479 -51.274218)
		(end 289.13963 -51.274218)
		(stroke
			(width 1.016)
			(type default)
		)
		(layer "In8.Cu")
	)
	(gr_line
		(start 282.442158 -52.555394)
		(end 288.082736 -52.555394)
		(stroke
			(width 1.016)
			(type default)
		)
		(layer "In8.Cu")
	)
	(gr_line
		(start 282.468574 -51.894994)
		(end 288.386774 -51.894994)
		(stroke
			(width 1.016)
			(type default)
		)
		(layer "In8.Cu")
	)
	(gr_circle
		(center 283.413454 -32.1564)
		(end 284.302454 -32.1564)
		(stroke
			(width 0.2)
			(type default)
		)
		(fill no)
		(layer "In8.Cu")
	)
	(gr_circle
		(center 285.242 -30.687264)
		(end 286.131 -30.687264)
		(stroke
			(width 0.2)
			(type default)
		)
		(fill no)
		(layer "In8.Cu")
	)
	(gr_circle
		(center 286.004 -30.687264)
		(end 286.893 -30.687264)
		(stroke
			(width 0.2)
			(type default)
		)
		(fill no)
		(layer "In8.Cu")
	)
	(gr_circle
		(center 287.401 -30.687264)
		(end 288.29 -30.687264)
		(stroke
			(width 0.2)
			(type default)
		)
		(fill no)
		(layer "In8.Cu")
	)
	(gr_line
		(start 288.082736 -52.555394)
		(end 288.14903 -52.621688)
		(stroke
			(width 1.016)
			(type default)
		)
		(layer "In8.Cu")
	)
	(gr_circle
		(center 288.163 -30.687264)
		(end 289.052 -30.687264)
		(stroke
			(width 0.2)
			(type default)
		)
		(fill no)
		(layer "In8.Cu")
	)
	(gr_line
		(start 288.294318 -53.427376)
		(end 281.570176 -53.427376)
		(stroke
			(width 1.016)
			(type default)
		)
		(layer "In8.Cu")
	)
	(gr_line
		(start 288.386774 -51.894994)
		(end 288.439606 -51.947826)
		(stroke
			(width 1.016)
			(type default)
		)
		(layer "In8.Cu")
	)
	(gr_line
		(start 288.439606 -53.282088)
		(end 288.294318 -53.427376)
		(stroke
			(width 1.016)
			(type default)
		)
		(layer "In8.Cu")
	)
	(gr_line
		(start 288.439606 -51.947826)
		(end 288.439606 -53.282088)
		(stroke
			(width 1.016)
			(type default)
		)
		(layer "In8.Cu")
	)
	(gr_line
		(start 288.901886 -54.021736)
		(end 281.028648 -54.021736)
		(stroke
			(width 1.016)
			(type default)
		)
		(layer "In8.Cu")
	)
	(gr_line
		(start 289.13963 -53.783992)
		(end 288.901886 -54.021736)
		(stroke
			(width 1.016)
			(type default)
		)
		(layer "In8.Cu")
	)
	(gr_line
		(start 289.13963 -51.274218)
		(end 289.13963 -53.783992)
		(stroke
			(width 1.016)
			(type default)
		)
		(layer "In8.Cu")
	)
	(gr_line
		(start 289.350958 -54.629558)
		(end 280.486866 -54.629558)
		(stroke
			(width 1.016)
			(type default)
		)
		(layer "In8.Cu")
	)
	(gr_line
		(start 289.747452 -54.233064)
		(end 289.350958 -54.629558)
		(stroke
			(width 1.016)
			(type default)
		)
		(layer "In8.Cu")
	)
	(gr_line
		(start 289.747452 -50.494692)
		(end 289.747452 -54.233064)
		(stroke
			(width 1.016)
			(type default)
		)
		(layer "In8.Cu")
	)
	(gr_line
		(start 289.918902 -55.100728)
		(end 279.879806 -55.100728)
		(stroke
			(width 1.016)
			(type default)
		)
		(layer "In8.Cu")
	)
	(gr_line
		(start 290.209478 -49.737264)
		(end 290.367974 -49.89576)
		(stroke
			(width 1.016)
			(type default)
		)
		(layer "In8.Cu")
	)
	(gr_line
		(start 290.367974 -54.651656)
		(end 289.918902 -55.100728)
		(stroke
			(width 1.016)
			(type default)
		)
		(layer "In8.Cu")
	)
	(gr_line
		(start 290.367974 -49.89576)
		(end 290.367974 -54.651656)
		(stroke
			(width 1.016)
			(type default)
		)
		(layer "In8.Cu")
	)
	(gr_line
		(start 290.871148 -55.10022)
		(end 290.871148 -50.37201)
		(stroke
			(width 1.016)
			(type default)
		)
		(layer "In8.Cu")
	)
	(gr_line
		(start 290.871148 -50.37201)
		(end 291.161978 -50.08118)
		(stroke
			(width 1.016)
			(type default)
		)
		(layer "In8.Cu")
	)
	(gr_line
		(start 291.161978 -50.08118)
		(end 291.61105 -49.632108)
		(stroke
			(width 1.016)
			(type default)
		)
		(layer "In8.Cu")
	)
	(gr_line
		(start 291.161978 -50.08118)
		(end 297.899074 -50.08118)
		(stroke
			(width 1.016)
			(type default)
		)
		(layer "In8.Cu")
	)
	(gr_line
		(start 291.505386 -55.734458)
		(end 279.297638 -55.734458)
		(stroke
			(width 1.016)
			(type default)
		)
		(layer "In8.Cu")
	)
	(gr_line
		(start 291.505386 -55.734458)
		(end 290.871148 -55.10022)
		(stroke
			(width 1.016)
			(type default)
		)
		(layer "In8.Cu")
	)
	(gr_line
		(start 291.584634 -54.59857)
		(end 291.584634 -50.899822)
		(stroke
			(width 1.016)
			(type default)
		)
		(layer "In8.Cu")
	)
	(gr_line
		(start 291.584634 -50.899822)
		(end 291.716714 -50.767742)
		(stroke
			(width 1.016)
			(type default)
		)
		(layer "In8.Cu")
	)
	(gr_line
		(start 291.61105 -49.632108)
		(end 291.61105 -49.605438)
		(stroke
			(width 1.016)
			(type default)
		)
		(layer "In8.Cu")
	)
	(gr_line
		(start 291.61105 -49.605438)
		(end 298.348146 -49.605438)
		(stroke
			(width 1.016)
			(type default)
		)
		(layer "In8.Cu")
	)
	(gr_line
		(start 291.716714 -50.767742)
		(end 297.581574 -50.767742)
		(stroke
			(width 1.016)
			(type default)
		)
		(layer "In8.Cu")
	)
	(gr_line
		(start 291.901626 -54.915562)
		(end 291.584634 -54.59857)
		(stroke
			(width 1.016)
			(type default)
		)
		(layer "In8.Cu")
	)
	(gr_line
		(start 292.007036 -52.775612)
		(end 292.773354 -53.54193)
		(stroke
			(width 1.016)
			(type default)
		)
		(layer "In8.Cu")
	)
	(gr_line
		(start 292.007036 -51.375564)
		(end 292.007036 -52.775612)
		(stroke
			(width 1.016)
			(type default)
		)
		(layer "In8.Cu")
	)
	(gr_line
		(start 292.245034 -54.123082)
		(end 292.245034 -51.851052)
		(stroke
			(width 1.016)
			(type default)
		)
		(layer "In8.Cu")
	)
	(gr_line
		(start 292.245034 -51.851052)
		(end 292.654482 -51.441604)
		(stroke
			(width 1.016)
			(type default)
		)
		(layer "In8.Cu")
	)
	(gr_line
		(start 292.324282 -54.20233)
		(end 292.245034 -54.123082)
		(stroke
			(width 1.016)
			(type default)
		)
		(layer "In8.Cu")
	)
	(gr_line
		(start 292.614858 -52.485036)
		(end 293.037768 -52.907946)
		(stroke
			(width 1.016)
			(type default)
		)
		(layer "In8.Cu")
	)
	(gr_line
		(start 292.654482 -51.441604)
		(end 297.330876 -51.441604)
		(stroke
			(width 1.016)
			(type default)
		)
		(layer "In8.Cu")
	)
	(gr_line
		(start 292.773354 -53.54193)
		(end 296.472102 -53.54193)
		(stroke
			(width 1.016)
			(type default)
		)
		(layer "In8.Cu")
	)
	(gr_line
		(start 292.93185 -52.168044)
		(end 292.614858 -52.485036)
		(stroke
			(width 1.016)
			(type default)
		)
		(layer "In8.Cu")
	)
	(gr_line
		(start 293.037768 -52.907946)
		(end 295.969944 -52.907946)
		(stroke
			(width 1.016)
			(type default)
		)
		(layer "In8.Cu")
	)
	(gr_circle
		(center 294.132 -45.466)
		(end 295.021 -45.466)
		(stroke
			(width 0.2)
			(type default)
		)
		(fill no)
		(layer "In8.Cu")
	)
	(gr_circle
		(center 294.1828 -34.9758)
		(end 295.0718 -34.9758)
		(stroke
			(width 0.2)
			(type default)
		)
		(fill no)
		(layer "In8.Cu")
	)
	(gr_circle
		(center 294.6908 -44.699428)
		(end 295.5798 -44.699428)
		(stroke
			(width 0.2)
			(type default)
		)
		(fill no)
		(layer "In8.Cu")
	)
	(gr_line
		(start 295.070022 -57.345072)
		(end 296.386758 -58.661808)
		(stroke
			(width 1.016)
			(type default)
		)
		(layer "In8.Cu")
	)
	(gr_line
		(start 295.323006 -56.515)
		(end 279.0571 -56.515)
		(stroke
			(width 1.016)
			(type default)
		)
		(layer "In8.Cu")
	)
	(gr_circle
		(center 295.3258 -44.693586)
		(end 296.2148 -44.693586)
		(stroke
			(width 0.2)
			(type default)
		)
		(fill no)
		(layer "In8.Cu")
	)
	(gr_line
		(start 295.422574 -58.027062)
		(end 296.386758 -58.991246)
		(stroke
			(width 1.016)
			(type default)
		)
		(layer "In8.Cu")
	)
	(gr_line
		(start 295.660826 -59.717178)
		(end 279.648666 -59.717178)
		(stroke
			(width 1.016)
			(type default)
		)
		(layer "In8.Cu")
	)
	(gr_line
		(start 295.706038 -55.734458)
		(end 291.505386 -55.734458)
		(stroke
			(width 1.016)
			(type default)
		)
		(layer "In8.Cu")
	)
	(gr_line
		(start 295.917112 -52.168044)
		(end 292.93185 -52.168044)
		(stroke
			(width 1.016)
			(type default)
		)
		(layer "In8.Cu")
	)
	(gr_line
		(start 295.969944 -54.915562)
		(end 291.901626 -54.915562)
		(stroke
			(width 1.016)
			(type default)
		)
		(layer "In8.Cu")
	)
	(gr_line
		(start 296.181272 -51.375564)
		(end 292.007036 -51.375564)
		(stroke
			(width 1.016)
			(type default)
		)
		(layer "In8.Cu")
	)
	(gr_line
		(start 296.366438 -54.20233)
		(end 292.324282 -54.20233)
		(stroke
			(width 1.016)
			(type default)
		)
		(layer "In8.Cu")
	)
	(gr_line
		(start 296.386758 -58.991246)
		(end 279.290526 -58.991246)
		(stroke
			(width 1.016)
			(type default)
		)
		(layer "In8.Cu")
	)
	(gr_line
		(start 296.386758 -58.991246)
		(end 295.660826 -59.717178)
		(stroke
			(width 1.016)
			(type default)
		)
		(layer "In8.Cu")
	)
	(gr_line
		(start 296.386758 -58.661808)
		(end 296.386758 -58.991246)
		(stroke
			(width 1.016)
			(type default)
		)
		(layer "In8.Cu")
	)
	(gr_line
		(start 296.472102 -53.54193)
		(end 302.390048 -59.459876)
		(stroke
			(width 1.016)
			(type default)
		)
		(layer "In8.Cu")
	)
	(gr_line
		(start 297.0784 -59.406028)
		(end 296.76725 -59.717178)
		(stroke
			(width 1.016)
			(type default)
		)
		(layer "In8.Cu")
	)
	(gr_line
		(start 297.0784 -59.406028)
		(end 297.0784 -58.5724)
		(stroke
			(width 1.016)
			(type default)
		)
		(layer "In8.Cu")
	)
	(gr_line
		(start 297.330876 -51.441604)
		(end 303.407064 -57.517792)
		(stroke
			(width 1.016)
			(type default)
		)
		(layer "In8.Cu")
	)
	(gr_line
		(start 297.581574 -50.767742)
		(end 304.160174 -57.346342)
		(stroke
			(width 1.016)
			(type default)
		)
		(layer "In8.Cu")
	)
	(gr_line
		(start 297.899074 -50.08118)
		(end 304.97907 -57.161176)
		(stroke
			(width 1.016)
			(type default)
		)
		(layer "In8.Cu")
	)
	(gr_line
		(start 298.26077 -46.604428)
		(end 298.64177 -46.985428)
		(stroke
			(width 1.016)
			(type default)
		)
		(layer "In8.Cu")
	)
	(gr_line
		(start 298.26077 -38.218364)
		(end 298.26077 -46.604428)
		(stroke
			(width 1.016)
			(type default)
		)
		(layer "In8.Cu")
	)
	(gr_line
		(start 298.271184 -96.3676)
		(end 278.19985 -96.3676)
		(stroke
			(width 1.016)
			(type default)
		)
		(layer "In8.Cu")
	)
	(gr_line
		(start 298.348146 -49.605438)
		(end 305.66614 -56.923432)
		(stroke
			(width 1.016)
			(type default)
		)
		(layer "In8.Cu")
	)
	(gr_line
		(start 298.510706 -37.968428)
		(end 298.26077 -38.218364)
		(stroke
			(width 1.016)
			(type default)
		)
		(layer "In8.Cu")
	)
	(gr_line
		(start 298.525184 -59.717178)
		(end 291.200078 -59.717178)
		(stroke
			(width 1.016)
			(type default)
		)
		(layer "In8.Cu")
	)
	(gr_line
		(start 298.533566 -132.960364)
		(end 279.565862 -132.960364)
		(stroke
			(width 1.016)
			(type default)
		)
		(layer "In8.Cu")
	)
	(gr_line
		(start 298.64177 -46.985428)
		(end 302.45177 -46.985428)
		(stroke
			(width 1.016)
			(type default)
		)
		(layer "In8.Cu")
	)
	(gr_line
		(start 298.831 -48.9712)
		(end 281.3558 -48.9712)
		(stroke
			(width 1.016)
			(type default)
		)
		(layer "In8.Cu")
	)
	(gr_line
		(start 298.831 -48.9712)
		(end 306.451 -56.5912)
		(stroke
			(width 1.016)
			(type default)
		)
		(layer "In8.Cu")
	)
	(gr_line
		(start 298.971716 -46.985428)
		(end 298.971716 -37.991796)
		(stroke
			(width 1.016)
			(type default)
		)
		(layer "In8.Cu")
	)
	(gr_line
		(start 298.971716 -37.991796)
		(end 298.995084 -37.968428)
		(stroke
			(width 1.016)
			(type default)
		)
		(layer "In8.Cu")
	)
	(gr_line
		(start 299.479716 -46.985428)
		(end 299.479716 -37.991796)
		(stroke
			(width 1.016)
			(type default)
		)
		(layer "In8.Cu")
	)
	(gr_line
		(start 299.479716 -37.991796)
		(end 299.503084 -37.968428)
		(stroke
			(width 1.016)
			(type default)
		)
		(layer "In8.Cu")
	)
	(gr_line
		(start 299.763434 -131.730496)
		(end 298.533566 -132.960364)
		(stroke
			(width 1.016)
			(type default)
		)
		(layer "In8.Cu")
	)
	(gr_line
		(start 299.763434 -127.672338)
		(end 299.763434 -131.730496)
		(stroke
			(width 1.016)
			(type default)
		)
		(layer "In8.Cu")
	)
	(gr_line
		(start 299.763434 -127.672338)
		(end 299.763434 -126.359666)
		(stroke
			(width 1.016)
			(type default)
		)
		(layer "In8.Cu")
	)
	(gr_line
		(start 299.763434 -127.672338)
		(end 299.763434 -126.219966)
		(stroke
			(width 1.016)
			(type default)
		)
		(layer "In8.Cu")
	)
	(gr_line
		(start 299.763434 -126.219966)
		(end 303.6824 -122.301)
		(stroke
			(width 1.016)
			(type default)
		)
		(layer "In8.Cu")
	)
	(gr_line
		(start 299.763434 -125.046994)
		(end 299.763434 -126.359666)
		(stroke
			(width 1.016)
			(type default)
		)
		(layer "In8.Cu")
	)
	(gr_line
		(start 299.763434 -125.046994)
		(end 299.763434 -122.1994)
		(stroke
			(width 1.016)
			(type default)
		)
		(layer "In8.Cu")
	)
	(gr_line
		(start 299.763434 -122.1994)
		(end 299.763434 -60.955428)
		(stroke
			(width 1.016)
			(type default)
		)
		(layer "In8.Cu")
	)
	(gr_line
		(start 299.763434 -97.85985)
		(end 298.271184 -96.3676)
		(stroke
			(width 1.016)
			(type default)
		)
		(layer "In8.Cu")
	)
	(gr_line
		(start 299.763434 -96.3676)
		(end 298.271184 -96.3676)
		(stroke
			(width 1.016)
			(type default)
		)
		(layer "In8.Cu")
	)
	(gr_line
		(start 299.763434 -94.87535)
		(end 298.271184 -96.3676)
		(stroke
			(width 1.016)
			(type default)
		)
		(layer "In8.Cu")
	)
	(gr_line
		(start 299.763434 -60.955428)
		(end 295.323006 -56.515)
		(stroke
			(width 1.016)
			(type default)
		)
		(layer "In8.Cu")
	)
	(gr_line
		(start 299.987716 -46.985428)
		(end 299.987716 -37.991796)
		(stroke
			(width 1.016)
			(type default)
		)
		(layer "In8.Cu")
	)
	(gr_line
		(start 299.987716 -37.991796)
		(end 300.011084 -37.968428)
		(stroke
			(width 1.016)
			(type default)
		)
		(layer "In8.Cu")
	)
	(gr_line
		(start 300.36897 -73.26376)
		(end 300.36897 -60.001404)
		(stroke
			(width 1.016)
			(type default)
		)
		(layer "In8.Cu")
	)
	(gr_line
		(start 300.495716 -46.985428)
		(end 300.495716 -37.991796)
		(stroke
			(width 1.016)
			(type default)
		)
		(layer "In8.Cu")
	)
	(gr_line
		(start 300.495716 -37.991796)
		(end 300.519084 -37.968428)
		(stroke
			(width 1.016)
			(type default)
		)
		(layer "In8.Cu")
	)
	(gr_line
		(start 300.501304 -60.529724)
		(end 295.706038 -55.734458)
		(stroke
			(width 1.016)
			(type default)
		)
		(layer "In8.Cu")
	)
	(gr_line
		(start 300.632876 -73.53935)
		(end 299.798994 -74.373232)
		(stroke
			(width 1.016)
			(type default)
		)
		(layer "In8.Cu")
	)
	(gr_line
		(start 300.910752 -73.078848)
		(end 300.910752 -59.816492)
		(stroke
			(width 1.016)
			(type default)
		)
		(layer "In8.Cu")
	)
	(gr_line
		(start 301.003716 -46.985428)
		(end 301.003716 -37.991796)
		(stroke
			(width 1.016)
			(type default)
		)
		(layer "In8.Cu")
	)
	(gr_line
		(start 301.003716 -37.991796)
		(end 301.027084 -37.968428)
		(stroke
			(width 1.016)
			(type default)
		)
		(layer "In8.Cu")
	)
	(gr_line
		(start 301.084742 -122.1994)
		(end 299.763434 -123.520708)
		(stroke
			(width 1.016)
			(type default)
		)
		(layer "In8.Cu")
	)
	(gr_line
		(start 301.084742 -122.1994)
		(end 299.763434 -120.878092)
		(stroke
			(width 1.016)
			(type default)
		)
		(layer "In8.Cu")
	)
	(gr_line
		(start 301.22749 -60.173108)
		(end 295.969944 -54.915562)
		(stroke
			(width 1.016)
			(type default)
		)
		(layer "In8.Cu")
	)
	(gr_line
		(start 301.399448 -73.144888)
		(end 301.399448 -59.882532)
		(stroke
			(width 1.016)
			(type default)
		)
		(layer "In8.Cu")
	)
	(gr_line
		(start 301.447708 -122.503692)
		(end 300.1264 -123.825)
		(stroke
			(width 1.016)
			(type default)
		)
		(layer "In8.Cu")
	)
	(gr_line
		(start 301.511716 -46.985428)
		(end 301.511716 -37.991796)
		(stroke
			(width 1.016)
			(type default)
		)
		(layer "In8.Cu")
	)
	(gr_line
		(start 301.511716 -37.991796)
		(end 301.535084 -37.968428)
		(stroke
			(width 1.016)
			(type default)
		)
		(layer "In8.Cu")
	)
	(gr_line
		(start 301.993808 -73.092056)
		(end 301.993808 -59.8297)
		(stroke
			(width 1.016)
			(type default)
		)
		(layer "In8.Cu")
	)
	(gr_line
		(start 301.993808 -59.8297)
		(end 296.366438 -54.20233)
		(stroke
			(width 1.016)
			(type default)
		)
		(layer "In8.Cu")
	)
	(gr_line
		(start 302.019716 -46.985428)
		(end 302.019716 -37.991796)
		(stroke
			(width 1.016)
			(type default)
		)
		(layer "In8.Cu")
	)
	(gr_line
		(start 302.019716 -37.991796)
		(end 302.043084 -37.968428)
		(stroke
			(width 1.016)
			(type default)
		)
		(layer "In8.Cu")
	)
	(gr_line
		(start 302.390048 -59.459876)
		(end 302.390048 -58.64098)
		(stroke
			(width 1.016)
			(type default)
		)
		(layer "In8.Cu")
	)
	(gr_line
		(start 302.390048 -58.64098)
		(end 295.917112 -52.168044)
		(stroke
			(width 1.016)
			(type default)
		)
		(layer "In8.Cu")
	)
	(gr_line
		(start 302.45177 -46.985428)
		(end 302.85817 -46.579028)
		(stroke
			(width 1.016)
			(type default)
		)
		(layer "In8.Cu")
	)
	(gr_line
		(start 302.50257 -37.968428)
		(end 298.510706 -37.968428)
		(stroke
			(width 1.016)
			(type default)
		)
		(layer "In8.Cu")
	)
	(gr_line
		(start 302.50257 -37.968428)
		(end 302.85817 -38.324028)
		(stroke
			(width 1.016)
			(type default)
		)
		(layer "In8.Cu")
	)
	(gr_line
		(start 302.509428 -122.301)
		(end 299.763434 -125.046994)
		(stroke
			(width 1.016)
			(type default)
		)
		(layer "In8.Cu")
	)
	(gr_line
		(start 302.707294 -71.692262)
		(end 302.707294 -57.901586)
		(stroke
			(width 1.016)
			(type default)
		)
		(layer "In8.Cu")
	)
	(gr_line
		(start 302.707294 -57.901586)
		(end 296.181272 -51.375564)
		(stroke
			(width 1.016)
			(type default)
		)
		(layer "In8.Cu")
	)
	(gr_line
		(start 302.85817 -46.579028)
		(end 302.85817 -38.324028)
		(stroke
			(width 1.016)
			(type default)
		)
		(layer "In8.Cu")
	)
	(gr_line
		(start 303.050448 -72.035416)
		(end 301.993808 -73.092056)
		(stroke
			(width 1.016)
			(type default)
		)
		(layer "In8.Cu")
	)
	(gr_line
		(start 303.050448 -72.035416)
		(end 302.707294 -71.692262)
		(stroke
			(width 1.016)
			(type default)
		)
		(layer "In8.Cu")
	)
	(gr_line
		(start 303.288192 -72.458072)
		(end 302.416464 -73.3298)
		(stroke
			(width 1.016)
			(type default)
		)
		(layer "In8.Cu")
	)
	(gr_line
		(start 303.407064 -71.6788)
		(end 303.050448 -72.035416)
		(stroke
			(width 1.016)
			(type default)
		)
		(layer "In8.Cu")
	)
	(gr_line
		(start 303.407064 -57.517792)
		(end 303.407064 -71.6788)
		(stroke
			(width 1.016)
			(type default)
		)
		(layer "In8.Cu")
	)
	(gr_line
		(start 303.6824 -122.301)
		(end 302.509428 -122.301)
		(stroke
			(width 1.016)
			(type default)
		)
		(layer "In8.Cu")
	)
	(gr_line
		(start 303.948846 -72.035416)
		(end 303.050448 -72.035416)
		(stroke
			(width 1.016)
			(type default)
		)
		(layer "In8.Cu")
	)
	(gr_line
		(start 304.160174 -71.824088)
		(end 303.948846 -72.035416)
		(stroke
			(width 1.016)
			(type default)
		)
		(layer "In8.Cu")
	)
	(gr_line
		(start 304.160174 -57.346342)
		(end 304.160174 -71.824088)
		(stroke
			(width 1.016)
			(type default)
		)
		(layer "In8.Cu")
	)
	(gr_line
		(start 304.365406 -122.1994)
		(end 304.688494 -122.1994)
		(stroke
			(width 1.016)
			(type default)
		)
		(layer "In8.Cu")
	)
	(gr_line
		(start 304.688494 -72.458072)
		(end 303.288192 -72.458072)
		(stroke
			(width 1.016)
			(type default)
		)
		(layer "In8.Cu")
	)
	(gr_line
		(start 304.97907 -72.167496)
		(end 304.688494 -72.458072)
		(stroke
			(width 1.016)
			(type default)
		)
		(layer "In8.Cu")
	)
	(gr_line
		(start 304.97907 -57.161176)
		(end 304.97907 -72.167496)
		(stroke
			(width 1.016)
			(type default)
		)
		(layer "In8.Cu")
	)
	(gr_line
		(start 305.362102 -72.973184)
		(end 303.62525 -72.973184)
		(stroke
			(width 1.016)
			(type default)
		)
		(layer "In8.Cu")
	)
	(gr_line
		(start 305.66614 -72.669146)
		(end 305.362102 -72.973184)
		(stroke
			(width 1.016)
			(type default)
		)
		(layer "In8.Cu")
	)
	(gr_line
		(start 305.66614 -56.923432)
		(end 305.66614 -72.669146)
		(stroke
			(width 1.016)
			(type default)
		)
		(layer "In8.Cu")
	)
	(gr_line
		(start 306.38115 -73.53935)
		(end 300.632876 -73.53935)
		(stroke
			(width 1.016)
			(type default)
		)
		(layer "In8.Cu")
	)
	(gr_line
		(start 306.451 -73.6092)
		(end 306.38115 -73.53935)
		(stroke
			(width 1.016)
			(type default)
		)
		(layer "In8.Cu")
	)
	(gr_line
		(start 306.451 -73.6092)
		(end 308.6608 -75.819)
		(stroke
			(width 1.016)
			(type default)
		)
		(layer "In8.Cu")
	)
	(gr_line
		(start 306.451 -56.5912)
		(end 306.451 -73.6092)
		(stroke
			(width 1.016)
			(type default)
		)
		(layer "In8.Cu")
	)
	(gr_line
		(start 308.6608 -75.819)
		(end 319.8876 -75.819)
		(stroke
			(width 1.016)
			(type default)
		)
		(layer "In8.Cu")
	)
	(gr_circle
		(center 311.410096 -72.879966)
		(end 312.809128 -72.879966)
		(stroke
			(width 0.2)
			(type default)
		)
		(fill no)
		(layer "In8.Cu")
	)
	(gr_line
		(start 319.6336 -122.1994)
		(end 299.763434 -122.1994)
		(stroke
			(width 1.016)
			(type default)
		)
		(layer "In8.Cu")
	)
	(gr_line
		(start 319.8876 -75.819)
		(end 320.929 -76.8604)
		(stroke
			(width 1.016)
			(type default)
		)
		(layer "In8.Cu")
	)
	(gr_line
		(start 320.929 -120.904)
		(end 319.6336 -122.1994)
		(stroke
			(width 1.016)
			(type default)
		)
		(layer "In8.Cu")
	)
	(gr_line
		(start 320.929 -76.8604)
		(end 320.929 -120.904)
		(stroke
			(width 1.016)
			(type default)
		)
		(layer "In8.Cu")
	)
	(gr_line
		(start 0 -141.99997)
		(end 0 -131.729988)
		(stroke
			(width 0.05)
			(type default)
		)
		(layer "Edge.Cuts")
	)
	(gr_arc
		(start 0 -141.99997)
		(mid 1.464463 -145.535497)
		(end 4.99999 -146.99996)
		(stroke
			(width 0.05)
			(type default)
		)
		(layer "Edge.Cuts")
	)
	(gr_line
		(start 0 -113.229898)
		(end 0 -34.569908)
		(stroke
			(width 0.05)
			(type default)
		)
		(layer "Edge.Cuts")
	)
	(gr_arc
		(start 0 -113.229898)
		(mid 0.878678 -115.351214)
		(end 2.999994 -116.229892)
		(stroke
			(width 0.05)
			(type default)
		)
		(layer "Edge.Cuts")
	)
	(gr_line
		(start 0 -16.070072)
		(end 0 -4.99999)
		(stroke
			(width 0.05)
			(type default)
		)
		(layer "Edge.Cuts")
	)
	(gr_arc
		(start 0 -16.070072)
		(mid 0.878678 -18.191388)
		(end 2.999994 -19.070066)
		(stroke
			(width 0.05)
			(type default)
		)
		(layer "Edge.Cuts")
	)
	(gr_arc
		(start 2.999994 -128.729994)
		(mid 0.878678 -129.608672)
		(end 0 -131.729988)
		(stroke
			(width 0.05)
			(type default)
		)
		(layer "Edge.Cuts")
	)
	(gr_line
		(start 2.999994 -128.729994)
		(end 9.59993 -128.729994)
		(stroke
			(width 0.05)
			(type default)
		)
		(layer "Edge.Cuts")
	)
	(gr_arc
		(start 2.999994 -31.569914)
		(mid 0.878678 -32.448592)
		(end 0 -34.569908)
		(stroke
			(width 0.05)
			(type default)
		)
		(layer "Edge.Cuts")
	)
	(gr_line
		(start 2.999994 -31.569914)
		(end 9.59993 -31.569914)
		(stroke
			(width 0.05)
			(type default)
		)
		(layer "Edge.Cuts")
	)
	(gr_arc
		(start 4.99999 0)
		(mid 1.464463 -1.464463)
		(end 0 -4.99999)
		(stroke
			(width 0.05)
			(type default)
		)
		(layer "Edge.Cuts")
	)
	(gr_line
		(start 4.99999 0)
		(end 323.000116 0)
		(stroke
			(width 0.05)
			(type default)
		)
		(layer "Edge.Cuts")
	)
	(gr_arc
		(start 9.59993 -128.729994)
		(mid 9.953557 -128.583675)
		(end 10.100056 -128.230122)
		(stroke
			(width 0.05)
			(type default)
		)
		(layer "Edge.Cuts")
	)
	(gr_line
		(start 9.59993 -116.229892)
		(end 2.999994 -116.229892)
		(stroke
			(width 0.05)
			(type default)
		)
		(layer "Edge.Cuts")
	)
	(gr_arc
		(start 9.59993 -31.569914)
		(mid 9.953557 -31.423595)
		(end 10.100056 -31.070042)
		(stroke
			(width 0.05)
			(type default)
		)
		(layer "Edge.Cuts")
	)
	(gr_line
		(start 9.59993 -19.070066)
		(end 2.999994 -19.070066)
		(stroke
			(width 0.05)
			(type default)
		)
		(layer "Edge.Cuts")
	)
	(gr_line
		(start 10.100056 -128.230122)
		(end 10.100056 -116.730018)
		(stroke
			(width 0.05)
			(type default)
		)
		(layer "Edge.Cuts")
	)
	(gr_arc
		(start 10.100056 -116.730018)
		(mid 9.953572 -116.376376)
		(end 9.59993 -116.229892)
		(stroke
			(width 0.05)
			(type default)
		)
		(layer "Edge.Cuts")
	)
	(gr_line
		(start 10.100056 -31.070042)
		(end 10.100056 -19.569938)
		(stroke
			(width 0.05)
			(type default)
		)
		(layer "Edge.Cuts")
	)
	(gr_arc
		(start 10.100056 -19.569938)
		(mid 9.953467 -19.21655)
		(end 9.59993 -19.070066)
		(stroke
			(width 0.05)
			(type default)
		)
		(layer "Edge.Cuts")
	)
	(gr_line
		(start 323.000116 -146.99996)
		(end 4.99999 -146.99996)
		(stroke
			(width 0.05)
			(type default)
		)
		(layer "Edge.Cuts")
	)
	(gr_arc
		(start 323.000116 -146.99996)
		(mid 326.535622 -145.535489)
		(end 328.000106 -141.99997)
		(stroke
			(width 0.05)
			(type default)
		)
		(layer "Edge.Cuts")
	)
	(gr_arc
		(start 328.000106 -4.99999)
		(mid 326.53564 -1.464464)
		(end 323.000116 0)
		(stroke
			(width 0.05)
			(type default)
		)
		(layer "Edge.Cuts")
	)
	(gr_line
		(start 328.000106 -4.99999)
		(end 328.000106 -141.99997)
		(stroke
			(width 0.05)
			(type default)
		)
		(layer "Edge.Cuts")
	)
	(via
		(at 214.63 -76.962)
		(size 0.762)
		(drill 0.254)
		(layers "F.Cu" "B.Cu")
		(net "TP_U4_P06")
	)
	(segment
		(start 214.111078 -77.480922)
		(end 214.63 -76.962)
		(width 0.17272)
		(layer "B.Cu")
		(net "TP_U4_P06")
	)
	(segment
		(start 214.111078 -78.994)
		(end 214.111078 -77.480922)
		(width 0.17272)
		(layer "B.Cu")
		(net "TP_U4_P06")
	)
	(via
		(at 214.0204 -80.6704)
		(size 0.6604)
		(drill 0.3302)
		(layers "F.Cu" "B.Cu")
		(net "TP_U4_P05")
	)
	(segment
		(start 214.0204 -80.6704)
		(end 213.461092 -80.111092)
		(width 0.17272)
		(layer "B.Cu")
		(net "TP_U4_P05")
	)
	(segment
		(start 213.461092 -80.111092)
		(end 213.461092 -78.994)
		(width 0.17272)
		(layer "B.Cu")
		(net "TP_U4_P05")
	)
	(via
		(at 275.6662 -28.960064)
		(size 0.6604)
		(drill 0.3302)
		(layers "F.Cu" "B.Cu")
		(net "FM_AC_PWR_CYCLE_R_BUF")
	)
	(segment
		(start 272.664682 -28.932632)
		(end 272.664682 -28.492704)
		(width 0.17272)
		(layer "B.Cu")
		(net "FM_AC_PWR_CYCLE_R_BUF")
	)
	(segment
		(start 272.664682 -28.492704)
		(end 272.73504 -28.422346)
		(width 0.17272)
		(layer "B.Cu")
		(net "FM_AC_PWR_CYCLE_R_BUF")
	)
	(segment
		(start 273.685 -28.93695)
		(end 273.661886 -28.960064)
		(width 0.17272)
		(layer "B.Cu")
		(net "FM_AC_PWR_CYCLE_R_BUF")
	)
	(segment
		(start 273.21764 -28.956)
		(end 272.68805 -28.956)
		(width 0.17272)
		(layer "B.Cu")
		(net "FM_AC_PWR_CYCLE_R_BUF")
	)
	(segment
		(start 277.961344 -27.178)
		(end 277.935944 -27.1526)
		(width 0.17272)
		(layer "B.Cu")
		(net "FM_AC_PWR_CYCLE_R_BUF")
	)
	(segment
		(start 275.6662 -28.960064)
		(end 273.708114 -28.960064)
		(width 0.17272)
		(layer "B.Cu")
		(net "FM_AC_PWR_CYCLE_R_BUF")
	)
	(segment
		(start 272.68805 -28.956)
		(end 272.664682 -28.932632)
		(width 0.17272)
		(layer "B.Cu")
		(net "FM_AC_PWR_CYCLE_R_BUF")
	)
	(segment
		(start 273.708114 -28.960064)
		(end 273.685 -28.93695)
		(width 0.17272)
		(layer "B.Cu")
		(net "FM_AC_PWR_CYCLE_R_BUF")
	)
	(segment
		(start 277.473664 -27.1526)
		(end 275.6662 -28.960064)
		(width 0.17272)
		(layer "B.Cu")
		(net "FM_AC_PWR_CYCLE_R_BUF")
	)
	(segment
		(start 273.661886 -28.960064)
		(end 273.221704 -28.960064)
		(width 0.17272)
		(layer "B.Cu")
		(net "FM_AC_PWR_CYCLE_R_BUF")
	)
	(segment
		(start 273.221704 -28.960064)
		(end 273.21764 -28.956)
		(width 0.17272)
		(layer "B.Cu")
		(net "FM_AC_PWR_CYCLE_R_BUF")
	)
	(segment
		(start 272.73504 -28.422346)
		(end 272.73504 -27.542998)
		(width 0.17272)
		(layer "B.Cu")
		(net "FM_AC_PWR_CYCLE_R_BUF")
	)
	(segment
		(start 277.935944 -27.1526)
		(end 277.473664 -27.1526)
		(width 0.17272)
		(layer "B.Cu")
		(net "FM_AC_PWR_CYCLE_R_BUF")
	)
	(segment
		(start 279.432004 -27.178)
		(end 277.961344 -27.178)
		(width 0.17272)
		(layer "B.Cu")
		(net "FM_AC_PWR_CYCLE_R_BUF")
	)
	(via
		(at 267.67282 -48.68418)
		(size 0.508)
		(drill 0.254)
		(layers "F.Cu" "B.Cu")
		(net "FM_AC_PWR_CYCLE_R_N")
	)
	(via
		(at 219.3544 -53.0606)
		(size 0.508)
		(drill 0.254)
		(layers "F.Cu" "B.Cu")
		(net "FM_AC_PWR_CYCLE_R_N")
	)
	(via
		(at 214.122 -42.418)
		(size 0.6604)
		(drill 0.3302)
		(layers "F.Cu" "B.Cu")
		(net "FM_AC_PWR_CYCLE_R_N")
	)
	(segment
		(start 272.76044 -49.81956)
		(end 268.8082 -49.81956)
		(width 0.17272)
		(layer "B.Cu")
		(net "FM_AC_PWR_CYCLE_R_N")
	)
	(segment
		(start 274.6248 -47.9552)
		(end 272.76044 -49.81956)
		(width 0.17272)
		(layer "B.Cu")
		(net "FM_AC_PWR_CYCLE_R_N")
	)
	(segment
		(start 215.20785 -42.418)
		(end 214.122 -42.418)
		(width 0.17272)
		(layer "B.Cu")
		(net "FM_AC_PWR_CYCLE_R_N")
	)
	(segment
		(start 281.41676 -47.9552)
		(end 274.6248 -47.9552)
		(width 0.17272)
		(layer "B.Cu")
		(net "FM_AC_PWR_CYCLE_R_N")
	)
	(segment
		(start 214.122 -42.418)
		(end 212.725 -42.418)
		(width 0.17272)
		(layer "B.Cu")
		(net "FM_AC_PWR_CYCLE_R_N")
	)
	(segment
		(start 283.50591 -45.86605)
		(end 281.41676 -47.9552)
		(width 0.17272)
		(layer "B.Cu")
		(net "FM_AC_PWR_CYCLE_R_N")
	)
	(segment
		(start 268.8082 -49.81956)
		(end 267.67282 -48.68418)
		(width 0.17272)
		(layer "B.Cu")
		(net "FM_AC_PWR_CYCLE_R_N")
	)
	(segment
		(start 208.929986 -38.622986)
		(end 208.929986 -37.949632)
		(width 0.17272)
		(layer "B.Cu")
		(net "FM_AC_PWR_CYCLE_R_N")
	)
	(segment
		(start 212.725 -42.418)
		(end 208.929986 -38.622986)
		(width 0.17272)
		(layer "B.Cu")
		(net "FM_AC_PWR_CYCLE_R_N")
	)
	(segment
		(start 219.3544 -53.0606)
		(end 219.3544 -46.56455)
		(width 0.17272)
		(layer "B.Cu")
		(net "FM_AC_PWR_CYCLE_R_N")
	)
	(segment
		(start 219.3544 -46.56455)
		(end 215.20785 -42.418)
		(width 0.17272)
		(layer "B.Cu")
		(net "FM_AC_PWR_CYCLE_R_N")
	)
	(segment
		(start 287.528 -45.86605)
		(end 283.50591 -45.86605)
		(width 0.17272)
		(layer "B.Cu")
		(net "FM_AC_PWR_CYCLE_R_N")
	)
	(segment
		(start 267.67282 -48.68418)
		(end 267.67282 -45.898562)
		(width 0.12954)
		(layer "In7.Cu")
		(net "FM_AC_PWR_CYCLE_R_N")
	)
	(segment
		(start 248.208292 -47.117)
		(end 225.298 -47.117)
		(width 0.12954)
		(layer "In7.Cu")
		(net "FM_AC_PWR_CYCLE_R_N")
	)
	(segment
		(start 274.87245 -38.698932)
		(end 274.87245 -37.928296)
		(width 0.12954)
		(layer "In7.Cu")
		(net "FM_AC_PWR_CYCLE_R_N")
	)
	(segment
		(start 225.298 -47.117)
		(end 219.3544 -53.0606)
		(width 0.12954)
		(layer "In7.Cu")
		(net "FM_AC_PWR_CYCLE_R_N")
	)
	(segment
		(start 263.98093 -28.59278)
		(end 256.04978 -36.52393)
		(width 0.12954)
		(layer "In7.Cu")
		(net "FM_AC_PWR_CYCLE_R_N")
	)
	(segment
		(start 277.368 -32.171386)
		(end 273.789394 -28.59278)
		(width 0.12954)
		(layer "In7.Cu")
		(net "FM_AC_PWR_CYCLE_R_N")
	)
	(segment
		(start 256.04978 -36.52393)
		(end 256.04978 -39.275512)
		(width 0.12954)
		(layer "In7.Cu")
		(net "FM_AC_PWR_CYCLE_R_N")
	)
	(segment
		(start 273.789394 -28.59278)
		(end 263.98093 -28.59278)
		(width 0.12954)
		(layer "In7.Cu")
		(net "FM_AC_PWR_CYCLE_R_N")
	)
	(segment
		(start 277.368 -35.432746)
		(end 277.368 -32.171386)
		(width 0.12954)
		(layer "In7.Cu")
		(net "FM_AC_PWR_CYCLE_R_N")
	)
	(segment
		(start 256.04978 -39.275512)
		(end 248.208292 -47.117)
		(width 0.12954)
		(layer "In7.Cu")
		(net "FM_AC_PWR_CYCLE_R_N")
	)
	(segment
		(start 274.87245 -37.928296)
		(end 277.368 -35.432746)
		(width 0.12954)
		(layer "In7.Cu")
		(net "FM_AC_PWR_CYCLE_R_N")
	)
	(segment
		(start 267.67282 -45.898562)
		(end 274.87245 -38.698932)
		(width 0.12954)
		(layer "In7.Cu")
		(net "FM_AC_PWR_CYCLE_R_N")
	)
	(via
		(at 292.20795 -37.439854)
		(size 0.6604)
		(drill 0.3302)
		(layers "F.Cu" "B.Cu")
		(net "FM_AC_PWR_CYCLE_R1_N")
	)
	(segment
		(start 290.580826 -38.032436)
		(end 290.903152 -38.032436)
		(width 0.17272)
		(layer "B.Cu")
		(net "FM_AC_PWR_CYCLE_R1_N")
	)
	(segment
		(start 292.718998 -36.928806)
		(end 292.20795 -37.439854)
		(width 0.17272)
		(layer "B.Cu")
		(net "FM_AC_PWR_CYCLE_R1_N")
	)
	(segment
		(start 290.580826 -36.866068)
		(end 290.580826 -38.032436)
		(width 0.17272)
		(layer "B.Cu")
		(net "FM_AC_PWR_CYCLE_R1_N")
	)
	(segment
		(start 290.223194 -36.508436)
		(end 290.580826 -36.866068)
		(width 0.17272)
		(layer "B.Cu")
		(net "FM_AC_PWR_CYCLE_R1_N")
	)
	(segment
		(start 290.903152 -38.032436)
		(end 291.986716 -39.116)
		(width 0.17272)
		(layer "B.Cu")
		(net "FM_AC_PWR_CYCLE_R1_N")
	)
	(segment
		(start 292.20795 -37.439854)
		(end 292.20795 -39.116)
		(width 0.17272)
		(layer "B.Cu")
		(net "FM_AC_PWR_CYCLE_R1_N")
	)
	(segment
		(start 292.718998 -36.00196)
		(end 292.718998 -36.928806)
		(width 0.17272)
		(layer "B.Cu")
		(net "FM_AC_PWR_CYCLE_R1_N")
	)
	(segment
		(start 289.78098 -36.508436)
		(end 290.223194 -36.508436)
		(width 0.17272)
		(layer "B.Cu")
		(net "FM_AC_PWR_CYCLE_R1_N")
	)
	(segment
		(start 291.986716 -39.116)
		(end 292.20795 -39.116)
		(width 0.17272)
		(layer "B.Cu")
		(net "FM_AC_PWR_CYCLE_R1_N")
	)
	(via
		(at 47.232316 -57.425082)
		(size 0.6604)
		(drill 0.3302)
		(layers "F.Cu" "B.Cu")
		(net "P12V_HPDB_0_ISET_R")
	)
	(segment
		(start 46.095666 -57.841642)
		(end 46.815756 -57.841642)
		(width 0.17272)
		(layer "B.Cu")
		(net "P12V_HPDB_0_ISET_R")
	)
	(segment
		(start 46.815756 -57.841642)
		(end 47.232316 -57.425082)
		(width 0.17272)
		(layer "B.Cu")
		(net "P12V_HPDB_0_ISET_R")
	)
	(segment
		(start 46.088046 -56.774842)
		(end 46.582076 -56.774842)
		(width 0.17272)
		(layer "B.Cu")
		(net "P12V_HPDB_0_ISET_R")
	)
	(segment
		(start 46.582076 -56.774842)
		(end 47.232316 -57.425082)
		(width 0.17272)
		(layer "B.Cu")
		(net "P12V_HPDB_0_ISET_R")
	)
	(segment
		(start 276.749764 -35.44443)
		(end 276.802088 -35.44443)
		(width 0.17272)
		(layer "F.Cu")
		(net "P52V_HS1_EN_BUF_DELAY")
	)
	(segment
		(start 281.767534 -42.4942)
		(end 281.640534 -42.3672)
		(width 0.17272)
		(layer "F.Cu")
		(net "P52V_HS1_EN_BUF_DELAY")
	)
	(segment
		(start 276.576028 -35.618166)
		(end 276.749764 -35.44443)
		(width 0.17272)
		(layer "F.Cu")
		(net "P52V_HS1_EN_BUF_DELAY")
	)
	(segment
		(start 275.437854 -40.45204)
		(end 276.576028 -39.313866)
		(width 0.17272)
		(layer "F.Cu")
		(net "P52V_HS1_EN_BUF_DELAY")
	)
	(segment
		(start 282.544012 -42.590466)
		(end 282.447746 -42.4942)
		(width 0.17272)
		(layer "F.Cu")
		(net "P52V_HS1_EN_BUF_DELAY")
	)
	(segment
		(start 267.19276 -40.592756)
		(end 270.129 -40.592756)
		(width 0.17272)
		(layer "F.Cu")
		(net "P52V_HS1_EN_BUF_DELAY")
	)
	(segment
		(start 283.595572 -42.590466)
		(end 282.544012 -42.590466)
		(width 0.17272)
		(layer "F.Cu")
		(net "P52V_HS1_EN_BUF_DELAY")
	)
	(segment
		(start 282.447746 -42.4942)
		(end 281.767534 -42.4942)
		(width 0.17272)
		(layer "F.Cu")
		(net "P52V_HS1_EN_BUF_DELAY")
	)
	(segment
		(start 276.576028 -39.313866)
		(end 276.576028 -35.618166)
		(width 0.17272)
		(layer "F.Cu")
		(net "P52V_HS1_EN_BUF_DELAY")
	)
	(via
		(at 270.129 -40.592756)
		(size 0.508)
		(drill 0.254)
		(layers "F.Cu" "B.Cu")
		(net "P52V_HS1_EN_BUF_DELAY")
	)
	(via
		(at 279.019 -39.861998)
		(size 0.6604)
		(drill 0.3302)
		(layers "F.Cu" "B.Cu")
		(net "P52V_HS1_EN_BUF_DELAY")
	)
	(via
		(at 275.437854 -40.45204)
		(size 0.508)
		(drill 0.254)
		(layers "F.Cu" "B.Cu")
		(net "P52V_HS1_EN_BUF_DELAY")
	)
	(via
		(at 281.640534 -42.3672)
		(size 0.508)
		(drill 0.254)
		(layers "F.Cu" "B.Cu")
		(net "P52V_HS1_EN_BUF_DELAY")
	)
	(segment
		(start 279.135332 -39.861998)
		(end 281.640534 -42.3672)
		(width 0.17272)
		(layer "B.Cu")
		(net "P52V_HS1_EN_BUF_DELAY")
	)
	(segment
		(start 271.145 -40.53205)
		(end 270.189706 -40.53205)
		(width 0.17272)
		(layer "B.Cu")
		(net "P52V_HS1_EN_BUF_DELAY")
	)
	(segment
		(start 279.019 -39.861998)
		(end 279.135332 -39.861998)
		(width 0.17272)
		(layer "B.Cu")
		(net "P52V_HS1_EN_BUF_DELAY")
	)
	(segment
		(start 276.352 -39.861998)
		(end 279.019 -39.861998)
		(width 0.17272)
		(layer "B.Cu")
		(net "P52V_HS1_EN_BUF_DELAY")
	)
	(segment
		(start 272.28292 -40.45204)
		(end 272.20291 -40.53205)
		(width 0.17272)
		(layer "B.Cu")
		(net "P52V_HS1_EN_BUF_DELAY")
	)
	(segment
		(start 270.189706 -40.53205)
		(end 270.129 -40.592756)
		(width 0.17272)
		(layer "B.Cu")
		(net "P52V_HS1_EN_BUF_DELAY")
	)
	(segment
		(start 275.761958 -40.45204)
		(end 275.437854 -40.45204)
		(width 0.17272)
		(layer "B.Cu")
		(net "P52V_HS1_EN_BUF_DELAY")
	)
	(segment
		(start 272.20291 -40.53205)
		(end 271.145 -40.53205)
		(width 0.17272)
		(layer "B.Cu")
		(net "P52V_HS1_EN_BUF_DELAY")
	)
	(segment
		(start 276.352 -39.861998)
		(end 275.761958 -40.45204)
		(width 0.17272)
		(layer "B.Cu")
		(net "P52V_HS1_EN_BUF_DELAY")
	)
	(segment
		(start 275.437854 -40.45204)
		(end 272.28292 -40.45204)
		(width 0.17272)
		(layer "B.Cu")
		(net "P52V_HS1_EN_BUF_DELAY")
	)
	(via
		(at 279.908 -37.592)
		(size 0.6604)
		(drill 0.3302)
		(layers "F.Cu" "B.Cu")
		(net "P52V_HS1_EN_DELAY_N")
	)
	(segment
		(start 279.202642 -36.317682)
		(end 280.519632 -36.317682)
		(width 0.17272)
		(layer "B.Cu")
		(net "P52V_HS1_EN_DELAY_N")
	)
	(segment
		(start 277.30196 -35.82416)
		(end 277.30196 -37.862002)
		(width 0.17272)
		(layer "B.Cu")
		(net "P52V_HS1_EN_DELAY_N")
	)
	(segment
		(start 280.519632 -36.317682)
		(end 280.543 -36.34105)
		(width 0.17272)
		(layer "B.Cu")
		(net "P52V_HS1_EN_DELAY_N")
	)
	(segment
		(start 277.17496 -35.69716)
		(end 277.30196 -35.82416)
		(width 0.17272)
		(layer "B.Cu")
		(net "P52V_HS1_EN_DELAY_N")
	)
	(segment
		(start 279.908 -38.210998)
		(end 279.908 -37.592)
		(width 0.17272)
		(layer "B.Cu")
		(net "P52V_HS1_EN_DELAY_N")
	)
	(segment
		(start 280.543 -36.957)
		(end 280.543 -36.34105)
		(width 0.17272)
		(layer "B.Cu")
		(net "P52V_HS1_EN_DELAY_N")
	)
	(segment
		(start 280.940002 -39.243)
		(end 279.908 -38.210998)
		(width 0.17272)
		(layer "B.Cu")
		(net "P52V_HS1_EN_DELAY_N")
	)
	(segment
		(start 277.17496 -34.29)
		(end 277.17496 -35.69716)
		(width 0.17272)
		(layer "B.Cu")
		(net "P52V_HS1_EN_DELAY_N")
	)
	(segment
		(start 277.17496 -34.29)
		(end 279.202642 -36.317682)
		(width 0.17272)
		(layer "B.Cu")
		(net "P52V_HS1_EN_DELAY_N")
	)
	(segment
		(start 279.908 -37.592)
		(end 280.543 -36.957)
		(width 0.17272)
		(layer "B.Cu")
		(net "P52V_HS1_EN_DELAY_N")
	)
	(via
		(at 278.257 -29.73705)
		(size 0.6604)
		(drill 0.3302)
		(layers "F.Cu" "B.Cu")
		(net "FM_AC_PWR_CYCLE_BUF")
	)
	(segment
		(start 282.067 -28.194)
		(end 283.083 -27.178)
		(width 0.17272)
		(layer "B.Cu")
		(net "FM_AC_PWR_CYCLE_BUF")
	)
	(segment
		(start 290.719002 -35.052)
		(end 290.719002 -29.60751)
		(width 0.17272)
		(layer "B.Cu")
		(net "FM_AC_PWR_CYCLE_BUF")
	)
	(segment
		(start 279.08504 -29.78404)
		(end 279.03805 -29.73705)
		(width 0.17272)
		(layer "B.Cu")
		(net "FM_AC_PWR_CYCLE_BUF")
	)
	(segment
		(start 282.067 -29.78404)
		(end 282.067 -28.194)
		(width 0.17272)
		(layer "B.Cu")
		(net "FM_AC_PWR_CYCLE_BUF")
	)
	(segment
		(start 282.067 -29.78404)
		(end 279.08504 -29.78404)
		(width 0.17272)
		(layer "B.Cu")
		(net "FM_AC_PWR_CYCLE_BUF")
	)
	(segment
		(start 289.85591 -29.08935)
		(end 285.241492 -27.178)
		(width 0.17272)
		(layer "B.Cu")
		(net "FM_AC_PWR_CYCLE_BUF")
	)
	(segment
		(start 285.241492 -27.178)
		(end 283.431996 -27.178)
		(width 0.17272)
		(layer "B.Cu")
		(net "FM_AC_PWR_CYCLE_BUF")
	)
	(segment
		(start 279.03805 -29.73705)
		(end 278.257 -29.73705)
		(width 0.17272)
		(layer "B.Cu")
		(net "FM_AC_PWR_CYCLE_BUF")
	)
	(segment
		(start 290.200842 -29.08935)
		(end 289.941 -29.08935)
		(width 0.17272)
		(layer "B.Cu")
		(net "FM_AC_PWR_CYCLE_BUF")
	)
	(segment
		(start 278.257 -29.73705)
		(end 273.685 -29.73705)
		(width 0.17272)
		(layer "B.Cu")
		(net "FM_AC_PWR_CYCLE_BUF")
	)
	(segment
		(start 290.719002 -29.60751)
		(end 290.200842 -29.08935)
		(width 0.17272)
		(layer "B.Cu")
		(net "FM_AC_PWR_CYCLE_BUF")
	)
	(segment
		(start 289.941 -29.08935)
		(end 289.85591 -29.08935)
		(width 0.17272)
		(layer "B.Cu")
		(net "FM_AC_PWR_CYCLE_BUF")
	)
	(segment
		(start 289.941 -29.08935)
		(end 289.941 -29.06395)
		(width 0.17272)
		(layer "B.Cu")
		(net "FM_AC_PWR_CYCLE_BUF")
	)
	(segment
		(start 283.083 -27.178)
		(end 283.431996 -27.178)
		(width 0.17272)
		(layer "B.Cu")
		(net "FM_AC_PWR_CYCLE_BUF")
	)
	(via
		(at 287.394904 -43.000676)
		(size 0.6604)
		(drill 0.3302)
		(layers "F.Cu" "B.Cu")
		(net "FM_AC_PWR_CYCLE_N")
	)
	(segment
		(start 288.181034 -38.439852)
		(end 288.181034 -38.032436)
		(width 0.17272)
		(layer "B.Cu")
		(net "FM_AC_PWR_CYCLE_N")
	)
	(segment
		(start 291.16909 -45.06595)
		(end 291.27704 -44.958)
		(width 0.17272)
		(layer "B.Cu")
		(net "FM_AC_PWR_CYCLE_N")
	)
	(segment
		(start 287.528 -45.06595)
		(end 291.16909 -45.06595)
		(width 0.17272)
		(layer "B.Cu")
		(net "FM_AC_PWR_CYCLE_N")
	)
	(segment
		(start 287.528 -45.06595)
		(end 287.394904 -44.932854)
		(width 0.17272)
		(layer "B.Cu")
		(net "FM_AC_PWR_CYCLE_N")
	)
	(segment
		(start 288.181034 -38.032436)
		(end 288.181034 -36.866322)
		(width 0.17272)
		(layer "B.Cu")
		(net "FM_AC_PWR_CYCLE_N")
	)
	(segment
		(start 288.53892 -36.508436)
		(end 288.98088 -36.508436)
		(width 0.17272)
		(layer "B.Cu")
		(net "FM_AC_PWR_CYCLE_N")
	)
	(segment
		(start 287.394904 -39.225982)
		(end 288.181034 -38.439852)
		(width 0.17272)
		(layer "B.Cu")
		(net "FM_AC_PWR_CYCLE_N")
	)
	(segment
		(start 291.27704 -44.958)
		(end 291.27704 -43.53433)
		(width 0.17272)
		(layer "B.Cu")
		(net "FM_AC_PWR_CYCLE_N")
	)
	(segment
		(start 287.394904 -43.000676)
		(end 287.394904 -39.225982)
		(width 0.17272)
		(layer "B.Cu")
		(net "FM_AC_PWR_CYCLE_N")
	)
	(segment
		(start 288.181034 -36.866322)
		(end 288.53892 -36.508436)
		(width 0.17272)
		(layer "B.Cu")
		(net "FM_AC_PWR_CYCLE_N")
	)
	(segment
		(start 287.394904 -44.932854)
		(end 287.394904 -43.000676)
		(width 0.17272)
		(layer "B.Cu")
		(net "FM_AC_PWR_CYCLE_N")
	)
	(via
		(at 265.049 -28.321)
		(size 0.6604)
		(drill 0.3302)
		(layers "F.Cu" "B.Cu")
		(net "P52V_HS1_EN_DELAY")
	)
	(segment
		(start 271.61236 -30.48)
		(end 276.5044 -30.48)
		(width 0.17272)
		(layer "B.Cu")
		(net "P52V_HS1_EN_DELAY")
	)
	(segment
		(start 281.5082 -33.655)
		(end 282.3972 -34.544)
		(width 0.17272)
		(layer "B.Cu")
		(net "P52V_HS1_EN_DELAY")
	)
	(segment
		(start 279.6794 -33.655)
		(end 281.5082 -33.655)
		(width 0.17272)
		(layer "B.Cu")
		(net "P52V_HS1_EN_DELAY")
	)
	(segment
		(start 270.129 -29.845)
		(end 270.97736 -29.845)
		(width 0.17272)
		(layer "B.Cu")
		(net "P52V_HS1_EN_DELAY")
	)
	(segment
		(start 270.97736 -29.845)
		(end 271.61236 -30.48)
		(width 0.17272)
		(layer "B.Cu")
		(net "P52V_HS1_EN_DELAY")
	)
	(segment
		(start 266.63904 -28.321)
		(end 265.049 -28.321)
		(width 0.17272)
		(layer "B.Cu")
		(net "P52V_HS1_EN_DELAY")
	)
	(segment
		(start 270.129 -29.845)
		(end 267.335 -29.845)
		(width 0.17272)
		(layer "B.Cu")
		(net "P52V_HS1_EN_DELAY")
	)
	(segment
		(start 282.3972 -34.544)
		(end 284.861 -34.544)
		(width 0.17272)
		(layer "B.Cu")
		(net "P52V_HS1_EN_DELAY")
	)
	(segment
		(start 284.861 -34.544)
		(end 285.369 -35.052)
		(width 0.17272)
		(layer "B.Cu")
		(net "P52V_HS1_EN_DELAY")
	)
	(segment
		(start 285.369 -35.052)
		(end 285.369 -37.763958)
		(width 0.17272)
		(layer "B.Cu")
		(net "P52V_HS1_EN_DELAY")
	)
	(segment
		(start 267.335 -29.845)
		(end 266.63904 -29.14904)
		(width 0.17272)
		(layer "B.Cu")
		(net "P52V_HS1_EN_DELAY")
	)
	(segment
		(start 265.049 -28.321)
		(end 265.049 -27.4828)
		(width 0.17272)
		(layer "B.Cu")
		(net "P52V_HS1_EN_DELAY")
	)
	(segment
		(start 276.5044 -30.48)
		(end 279.6794 -33.655)
		(width 0.17272)
		(layer "B.Cu")
		(net "P52V_HS1_EN_DELAY")
	)
	(segment
		(start 285.369 -37.763958)
		(end 282.939998 -40.19296)
		(width 0.17272)
		(layer "B.Cu")
		(net "P52V_HS1_EN_DELAY")
	)
	(segment
		(start 265.716004 -26.815796)
		(end 265.716004 -25.527)
		(width 0.17272)
		(layer "B.Cu")
		(net "P52V_HS1_EN_DELAY")
	)
	(segment
		(start 266.63904 -29.14904)
		(end 266.63904 -28.321)
		(width 0.17272)
		(layer "B.Cu")
		(net "P52V_HS1_EN_DELAY")
	)
	(segment
		(start 265.049 -27.4828)
		(end 265.716004 -26.815796)
		(width 0.17272)
		(layer "B.Cu")
		(net "P52V_HS1_EN_DELAY")
	)
	(segment
		(start 201.6252 -79.6798)
		(end 201.6252 -82.26552)
		(width 0.17272)
		(layer "F.Cu")
		(net "PWRGD_P3V3_HPDB")
	)
	(segment
		(start 206.883 -74.422)
		(end 201.6252 -79.6798)
		(width 0.17272)
		(layer "F.Cu")
		(net "PWRGD_P3V3_HPDB")
	)
	(via
		(at 206.883 -74.422)
		(size 0.508)
		(drill 0.254)
		(layers "F.Cu" "B.Cu")
		(net "PWRGD_P3V3_HPDB")
	)
	(via
		(at 201.6252 -82.26552)
		(size 0.508)
		(drill 0.254)
		(layers "F.Cu" "B.Cu")
		(net "PWRGD_P3V3_HPDB")
	)
	(via
		(at 45.5676 -83.0072)
		(size 0.6604)
		(drill 0.3302)
		(layers "F.Cu" "B.Cu")
		(net "PWRGD_P3V3_HPDB")
	)
	(segment
		(start 14.986 -81.1022)
		(end 12.827 -78.9432)
		(width 0.17272)
		(layer "B.Cu")
		(net "PWRGD_P3V3_HPDB")
	)
	(segment
		(start 214.63 -75.565)
		(end 215.41105 -74.78395)
		(width 0.17272)
		(layer "B.Cu")
		(net "PWRGD_P3V3_HPDB")
	)
	(segment
		(start 192.343278 -80.18272)
		(end 193.590418 -81.42986)
		(width 0.17272)
		(layer "B.Cu")
		(net "PWRGD_P3V3_HPDB")
	)
	(segment
		(start 208.026 -75.565)
		(end 214.63 -75.565)
		(width 0.17272)
		(layer "B.Cu")
		(net "PWRGD_P3V3_HPDB")
	)
	(segment
		(start 182.625746 -81.54924)
		(end 183.992266 -80.18272)
		(width 0.17272)
		(layer "B.Cu")
		(net "PWRGD_P3V3_HPDB")
	)
	(segment
		(start 193.590418 -81.42986)
		(end 199.220074 -81.42986)
		(width 0.17272)
		(layer "B.Cu")
		(net "PWRGD_P3V3_HPDB")
	)
	(segment
		(start 206.883 -74.422)
		(end 208.026 -75.565)
		(width 0.17272)
		(layer "B.Cu")
		(net "PWRGD_P3V3_HPDB")
	)
	(segment
		(start 45.5676 -83.0072)
		(end 44.07408 -81.51368)
		(width 0.17272)
		(layer "B.Cu")
		(net "PWRGD_P3V3_HPDB")
	)
	(segment
		(start 215.41105 -74.78395)
		(end 215.41105 -73.152)
		(width 0.17272)
		(layer "B.Cu")
		(net "PWRGD_P3V3_HPDB")
	)
	(segment
		(start 45.5676 -83.0072)
		(end 46.94936 -84.38896)
		(width 0.17272)
		(layer "B.Cu")
		(net "PWRGD_P3V3_HPDB")
	)
	(segment
		(start 37.828728 -81.51368)
		(end 35.207448 -84.13496)
		(width 0.17272)
		(layer "B.Cu")
		(net "PWRGD_P3V3_HPDB")
	)
	(segment
		(start 44.07408 -81.51368)
		(end 37.828728 -81.51368)
		(width 0.17272)
		(layer "B.Cu")
		(net "PWRGD_P3V3_HPDB")
	)
	(segment
		(start 18.0848 -81.1022)
		(end 14.986 -81.1022)
		(width 0.17272)
		(layer "B.Cu")
		(net "PWRGD_P3V3_HPDB")
	)
	(segment
		(start 46.94936 -84.38896)
		(end 147.178268 -84.38896)
		(width 0.17272)
		(layer "B.Cu")
		(net "PWRGD_P3V3_HPDB")
	)
	(segment
		(start 21.11756 -84.13496)
		(end 18.0848 -81.1022)
		(width 0.17272)
		(layer "B.Cu")
		(net "PWRGD_P3V3_HPDB")
	)
	(segment
		(start 183.992266 -80.18272)
		(end 192.343278 -80.18272)
		(width 0.17272)
		(layer "B.Cu")
		(net "PWRGD_P3V3_HPDB")
	)
	(segment
		(start 199.220074 -81.42986)
		(end 200.055734 -82.26552)
		(width 0.17272)
		(layer "B.Cu")
		(net "PWRGD_P3V3_HPDB")
	)
	(segment
		(start 9.85012 -79.40548)
		(end 9.85012 -81.209896)
		(width 0.17272)
		(layer "B.Cu")
		(net "PWRGD_P3V3_HPDB")
	)
	(segment
		(start 147.178268 -84.38896)
		(end 150.017988 -81.54924)
		(width 0.17272)
		(layer "B.Cu")
		(net "PWRGD_P3V3_HPDB")
	)
	(segment
		(start 10.3124 -78.9432)
		(end 9.85012 -79.40548)
		(width 0.17272)
		(layer "B.Cu")
		(net "PWRGD_P3V3_HPDB")
	)
	(segment
		(start 150.017988 -81.54924)
		(end 182.625746 -81.54924)
		(width 0.17272)
		(layer "B.Cu")
		(net "PWRGD_P3V3_HPDB")
	)
	(segment
		(start 12.827 -78.9432)
		(end 10.3124 -78.9432)
		(width 0.17272)
		(layer "B.Cu")
		(net "PWRGD_P3V3_HPDB")
	)
	(segment
		(start 35.207448 -84.13496)
		(end 21.11756 -84.13496)
		(width 0.17272)
		(layer "B.Cu")
		(net "PWRGD_P3V3_HPDB")
	)
	(segment
		(start 200.055734 -82.26552)
		(end 201.6252 -82.26552)
		(width 0.17272)
		(layer "B.Cu")
		(net "PWRGD_P3V3_HPDB")
	)
	(segment
		(start 199.771 -77.597)
		(end 204.851 -72.517)
		(width 0.17272)
		(layer "F.Cu")
		(net "PRSNT_HPDB_N")
	)
	(segment
		(start 199.771 -80.4418)
		(end 199.771 -77.597)
		(width 0.17272)
		(layer "F.Cu")
		(net "PRSNT_HPDB_N")
	)
	(via
		(at 205.994 -72.644)
		(size 0.6604)
		(drill 0.3302)
		(layers "F.Cu" "B.Cu")
		(net "PRSNT_HPDB_N")
	)
	(via
		(at 204.851 -72.517)
		(size 0.508)
		(drill 0.254)
		(layers "F.Cu" "B.Cu")
		(net "PRSNT_HPDB_N")
	)
	(via
		(at 199.771 -80.4418)
		(size 0.508)
		(drill 0.254)
		(layers "F.Cu" "B.Cu")
		(net "PRSNT_HPDB_N")
	)
	(segment
		(start 15.183866 -80.62468)
		(end 13.024866 -78.46568)
		(width 0.17272)
		(layer "B.Cu")
		(net "PRSNT_HPDB_N")
	)
	(segment
		(start 205.994 -72.644)
		(end 208.265014 -74.915014)
		(width 0.17272)
		(layer "B.Cu")
		(net "PRSNT_HPDB_N")
	)
	(segment
		(start 204.851 -71.77405)
		(end 204.851 -72.517)
		(width 0.17272)
		(layer "B.Cu")
		(net "PRSNT_HPDB_N")
	)
	(segment
		(start 10.054336 -78.46568)
		(end 8.58012 -79.939896)
		(width 0.17272)
		(layer "B.Cu")
		(net "PRSNT_HPDB_N")
	)
	(segment
		(start 21.315426 -83.65744)
		(end 18.282666 -80.62468)
		(width 0.17272)
		(layer "B.Cu")
		(net "PRSNT_HPDB_N")
	)
	(segment
		(start 208.265014 -74.915014)
		(end 214.36076 -74.915014)
		(width 0.17272)
		(layer "B.Cu")
		(net "PRSNT_HPDB_N")
	)
	(segment
		(start 13.024866 -78.46568)
		(end 10.054336 -78.46568)
		(width 0.17272)
		(layer "B.Cu")
		(net "PRSNT_HPDB_N")
	)
	(segment
		(start 192.541144 -79.7052)
		(end 183.7944 -79.7052)
		(width 0.17272)
		(layer "B.Cu")
		(net "PRSNT_HPDB_N")
	)
	(segment
		(start 146.980402 -83.91144)
		(end 47.833026 -83.91144)
		(width 0.17272)
		(layer "B.Cu")
		(net "PRSNT_HPDB_N")
	)
	(segment
		(start 149.820122 -81.07172)
		(end 146.980402 -83.91144)
		(width 0.17272)
		(layer "B.Cu")
		(net "PRSNT_HPDB_N")
	)
	(segment
		(start 214.761064 -74.51471)
		(end 214.761064 -73.152)
		(width 0.17272)
		(layer "B.Cu")
		(net "PRSNT_HPDB_N")
	)
	(segment
		(start 37.630862 -81.03616)
		(end 35.009582 -83.65744)
		(width 0.17272)
		(layer "B.Cu")
		(net "PRSNT_HPDB_N")
	)
	(segment
		(start 182.42788 -81.07172)
		(end 149.820122 -81.07172)
		(width 0.17272)
		(layer "B.Cu")
		(net "PRSNT_HPDB_N")
	)
	(segment
		(start 183.7944 -79.7052)
		(end 182.42788 -81.07172)
		(width 0.17272)
		(layer "B.Cu")
		(net "PRSNT_HPDB_N")
	)
	(segment
		(start 47.833026 -83.91144)
		(end 44.957746 -81.03616)
		(width 0.17272)
		(layer "B.Cu")
		(net "PRSNT_HPDB_N")
	)
	(segment
		(start 193.788284 -80.95234)
		(end 192.541144 -79.7052)
		(width 0.17272)
		(layer "B.Cu")
		(net "PRSNT_HPDB_N")
	)
	(segment
		(start 44.957746 -81.03616)
		(end 37.630862 -81.03616)
		(width 0.17272)
		(layer "B.Cu")
		(net "PRSNT_HPDB_N")
	)
	(segment
		(start 18.282666 -80.62468)
		(end 15.183866 -80.62468)
		(width 0.17272)
		(layer "B.Cu")
		(net "PRSNT_HPDB_N")
	)
	(segment
		(start 205.12405 -71.77405)
		(end 205.994 -72.644)
		(width 0.17272)
		(layer "B.Cu")
		(net "PRSNT_HPDB_N")
	)
	(segment
		(start 35.009582 -83.65744)
		(end 21.315426 -83.65744)
		(width 0.17272)
		(layer "B.Cu")
		(net "PRSNT_HPDB_N")
	)
	(segment
		(start 204.851 -71.77405)
		(end 205.12405 -71.77405)
		(width 0.17272)
		(layer "B.Cu")
		(net "PRSNT_HPDB_N")
	)
	(segment
		(start 199.26046 -80.95234)
		(end 193.788284 -80.95234)
		(width 0.17272)
		(layer "B.Cu")
		(net "PRSNT_HPDB_N")
	)
	(segment
		(start 214.36076 -74.915014)
		(end 214.761064 -74.51471)
		(width 0.17272)
		(layer "B.Cu")
		(net "PRSNT_HPDB_N")
	)
	(segment
		(start 199.771 -80.4418)
		(end 199.26046 -80.95234)
		(width 0.17272)
		(layer "B.Cu")
		(net "PRSNT_HPDB_N")
	)
	(segment
		(start 36.02736 -60.806838)
		(end 35.982656 -60.851542)
		(width 0.12954)
		(layer "F.Cu")
		(net "P12V_HPDB_0_PD")
	)
	(segment
		(start 36.02736 -59.66587)
		(end 36.02736 -60.806838)
		(width 0.12954)
		(layer "F.Cu")
		(net "P12V_HPDB_0_PD")
	)
	(via
		(at 35.982656 -60.851542)
		(size 0.762)
		(drill 0.381)
		(layers "F.Cu" "B.Cu")
		(net "P12V_HPDB_0_PD")
	)
	(segment
		(start 41.181528 -61.24956)
		(end 41.181528 -60.929266)
		(width 0.17272)
		(layer "F.Cu")
		(net "P12V_HPDB_0_FB")
	)
	(segment
		(start 40.644318 -60.392056)
		(end 41.03243 -60.392056)
		(width 0.17272)
		(layer "F.Cu")
		(net "P12V_HPDB_0_FB")
	)
	(segment
		(start 41.03243 -60.392056)
		(end 41.181528 -60.242958)
		(width 0.17272)
		(layer "F.Cu")
		(net "P12V_HPDB_0_FB")
	)
	(segment
		(start 41.181528 -60.929266)
		(end 40.644318 -60.392056)
		(width 0.17272)
		(layer "F.Cu")
		(net "P12V_HPDB_0_FB")
	)
	(segment
		(start 41.181528 -63.28156)
		(end 41.181528 -62.27064)
		(width 0.17272)
		(layer "F.Cu")
		(net "P12V_HPDB_0_FB")
	)
	(segment
		(start 41.181528 -60.242958)
		(end 41.181528 -59.854846)
		(width 0.17272)
		(layer "F.Cu")
		(net "P12V_HPDB_0_FB")
	)
	(segment
		(start 41.181528 -62.27064)
		(end 41.181528 -61.24956)
		(width 0.17272)
		(layer "F.Cu")
		(net "P12V_HPDB_0_FB")
	)
	(via
		(at 40.644318 -60.392056)
		(size 0.508)
		(drill 0.254)
		(layers "F.Cu" "B.Cu")
		(net "P12V_HPDB_0_FB")
	)
	(segment
		(start 43.19016 -61.53277)
		(end 43.714924 -61.53277)
		(width 0.17272)
		(layer "F.Cu")
		(net "P12V_HPDB_0_FLTB")
	)
	(segment
		(start 43.714924 -61.53277)
		(end 43.846496 -61.664342)
		(width 0.17272)
		(layer "F.Cu")
		(net "P12V_HPDB_0_FLTB")
	)
	(segment
		(start 43.846496 -63.670942)
		(end 43.528996 -63.988442)
		(width 0.17272)
		(layer "F.Cu")
		(net "P12V_HPDB_0_FLTB")
	)
	(segment
		(start 43.846496 -61.664342)
		(end 43.846496 -63.670942)
		(width 0.17272)
		(layer "F.Cu")
		(net "P12V_HPDB_0_FLTB")
	)
	(via
		(at 43.528996 -63.988442)
		(size 0.762)
		(drill 0.381)
		(layers "F.Cu" "B.Cu")
		(net "P12V_HPDB_0_FLTB")
	)
	(segment
		(start 43.698414 -58.954924)
		(end 43.081448 -58.954924)
		(width 0.254)
		(layer "F.Cu")
		(net "P12V_HPDB_0_IMON")
	)
	(segment
		(start 45.27931 -62.918848)
		(end 45.27931 -61.55182)
		(width 0.254)
		(layer "F.Cu")
		(net "P12V_HPDB_0_IMON")
	)
	(segment
		(start 45.27931 -61.55182)
		(end 45.27931 -60.53582)
		(width 0.254)
		(layer "F.Cu")
		(net "P12V_HPDB_0_IMON")
	)
	(segment
		(start 45.27931 -60.53582)
		(end 43.698414 -58.954924)
		(width 0.254)
		(layer "F.Cu")
		(net "P12V_HPDB_0_IMON")
	)
	(via
		(at 45.27931 -62.918848)
		(size 0.762)
		(drill 0.381)
		(layers "F.Cu" "B.Cu")
		(net "P12V_HPDB_0_IMON")
	)
	(segment
		(start 45.202348 -57.196482)
		(end 44.572174 -57.196482)
		(width 0.17272)
		(layer "F.Cu")
		(net "P12V_HPDB_0_ISET")
	)
	(segment
		(start 45.29455 -57.10428)
		(end 45.202348 -57.196482)
		(width 0.17272)
		(layer "F.Cu")
		(net "P12V_HPDB_0_ISET")
	)
	(segment
		(start 44.572174 -57.196482)
		(end 44.313856 -57.4548)
		(width 0.17272)
		(layer "F.Cu")
		(net "P12V_HPDB_0_ISET")
	)
	(segment
		(start 44.313856 -57.4548)
		(end 43.081448 -57.4548)
		(width 0.17272)
		(layer "F.Cu")
		(net "P12V_HPDB_0_ISET")
	)
	(via
		(at 45.295566 -59.1566)
		(size 0.6604)
		(drill 0.3302)
		(layers "F.Cu" "B.Cu")
		(net "P12V_HPDB_0_ISET")
	)
	(via
		(at 44.572174 -57.196482)
		(size 0.508)
		(drill 0.254)
		(layers "F.Cu" "B.Cu")
		(net "P12V_HPDB_0_ISET")
	)
	(segment
		(start 44.831 -58.692034)
		(end 45.295566 -59.1566)
		(width 0.17272)
		(layer "B.Cu")
		(net "P12V_HPDB_0_ISET")
	)
	(segment
		(start 44.572174 -57.196482)
		(end 44.831 -57.455308)
		(width 0.17272)
		(layer "B.Cu")
		(net "P12V_HPDB_0_ISET")
	)
	(segment
		(start 44.831 -57.455308)
		(end 44.831 -58.692034)
		(width 0.17272)
		(layer "B.Cu")
		(net "P12V_HPDB_0_ISET")
	)
	(segment
		(start 45.295566 -57.841642)
		(end 45.295566 -59.1566)
		(width 0.17272)
		(layer "B.Cu")
		(net "P12V_HPDB_0_ISET")
	)
	(segment
		(start 44.162726 -57.954672)
		(end 43.081448 -57.954672)
		(width 0.17272)
		(layer "F.Cu")
		(net "P12V_HPDB_0_SS")
	)
	(segment
		(start 45.27931 -58.75782)
		(end 44.476162 -57.954672)
		(width 0.17272)
		(layer "F.Cu")
		(net "P12V_HPDB_0_SS")
	)
	(segment
		(start 44.476162 -57.954672)
		(end 44.162726 -57.954672)
		(width 0.17272)
		(layer "F.Cu")
		(net "P12V_HPDB_0_SS")
	)
	(via
		(at 44.162726 -57.954672)
		(size 0.508)
		(drill 0.254)
		(layers "F.Cu" "B.Cu")
		(net "P12V_HPDB_0_SS")
	)
	(segment
		(start 45.27931 -56.09082)
		(end 45.27931 -55.792116)
		(width 0.17272)
		(layer "F.Cu")
		(net "P12V_HPDB_0_TIMER")
	)
	(segment
		(start 43.081448 -56.954928)
		(end 44.113196 -56.954928)
		(width 0.17272)
		(layer "F.Cu")
		(net "P12V_HPDB_0_TIMER")
	)
	(segment
		(start 45.27931 -55.792116)
		(end 45.056044 -55.56885)
		(width 0.17272)
		(layer "F.Cu")
		(net "P12V_HPDB_0_TIMER")
	)
	(segment
		(start 45.056044 -55.56885)
		(end 44.697904 -55.56885)
		(width 0.17272)
		(layer "F.Cu")
		(net "P12V_HPDB_0_TIMER")
	)
	(segment
		(start 44.426886 -56.641238)
		(end 44.426886 -55.839868)
		(width 0.17272)
		(layer "F.Cu")
		(net "P12V_HPDB_0_TIMER")
	)
	(segment
		(start 44.113196 -56.954928)
		(end 44.426886 -56.641238)
		(width 0.17272)
		(layer "F.Cu")
		(net "P12V_HPDB_0_TIMER")
	)
	(segment
		(start 44.426886 -55.839868)
		(end 44.697904 -55.56885)
		(width 0.17272)
		(layer "F.Cu")
		(net "P12V_HPDB_0_TIMER")
	)
	(via
		(at 44.697904 -55.56885)
		(size 0.508)
		(drill 0.254)
		(layers "F.Cu" "B.Cu")
		(net "P12V_HPDB_0_TIMER")
	)
	(segment
		(start 43.451526 -55.454804)
		(end 43.056302 -55.454804)
		(width 0.17272)
		(layer "F.Cu")
		(net "P12V_HPDB_0_EN_R")
	)
	(segment
		(start 45.27931 -55.07482)
		(end 45.132498 -55.07482)
		(width 0.17272)
		(layer "F.Cu")
		(net "P12V_HPDB_0_EN_R")
	)
	(segment
		(start 44.02455 -54.88178)
		(end 43.451526 -55.454804)
		(width 0.17272)
		(layer "F.Cu")
		(net "P12V_HPDB_0_EN_R")
	)
	(segment
		(start 44.939458 -54.88178)
		(end 44.02455 -54.88178)
		(width 0.17272)
		(layer "F.Cu")
		(net "P12V_HPDB_0_EN_R")
	)
	(segment
		(start 45.27931 -54.214522)
		(end 45.27931 -55.07482)
		(width 0.17272)
		(layer "F.Cu")
		(net "P12V_HPDB_0_EN_R")
	)
	(segment
		(start 45.132498 -55.07482)
		(end 44.939458 -54.88178)
		(width 0.17272)
		(layer "F.Cu")
		(net "P12V_HPDB_0_EN_R")
	)
	(via
		(at 45.27931 -54.214522)
		(size 0.508)
		(drill 0.254)
		(layers "F.Cu" "B.Cu")
		(net "P12V_HPDB_0_EN_R")
	)
	(segment
		(start 278.003 -26.162)
		(end 276.75205 -26.162)
		(width 0.17272)
		(layer "F.Cu")
		(net "P52V_HS1_R_EN")
	)
	(segment
		(start 279.023064 -26.162)
		(end 278.003 -26.162)
		(width 0.17272)
		(layer "F.Cu")
		(net "P52V_HS1_R_EN")
	)
	(segment
		(start 279.470104 -25.71496)
		(end 279.023064 -26.162)
		(width 0.17272)
		(layer "F.Cu")
		(net "P52V_HS1_R_EN")
	)
	(via
		(at 278.003 -26.162)
		(size 0.762)
		(drill 0.381)
		(layers "F.Cu" "B.Cu")
		(net "P52V_HS1_R_EN")
	)
	(via
		(at 260.18236 -35.433)
		(size 0.6604)
		(drill 0.3302)
		(layers "F.Cu" "B.Cu")
		(net "P52V_1_R")
	)
	(via
		(at 283.4132 -32.1564)
		(size 0.508)
		(drill 0.254)
		(layers "F.Cu" "B.Cu")
		(net "P52V_1_R")
	)
	(via
		(at 272.5928 -23.0886)
		(size 0.508)
		(drill 0.254)
		(layers "F.Cu" "B.Cu")
		(net "P52V_1_R")
	)
	(via
		(at 296.5704 -46.863)
		(size 0.508)
		(drill 0.254)
		(layers "F.Cu" "B.Cu")
		(net "P52V_1_R")
	)
	(via
		(at 294.132 -45.466)
		(size 0.508)
		(drill 0.254)
		(layers "F.Cu" "B.Cu")
		(net "P52V_1_R")
	)
	(via
		(at 296.5704 -45.847)
		(size 0.508)
		(drill 0.254)
		(layers "F.Cu" "B.Cu")
		(net "P52V_1_R")
	)
	(via
		(at 273.6088 -23.0886)
		(size 0.508)
		(drill 0.254)
		(layers "F.Cu" "B.Cu")
		(net "P52V_1_R")
	)
	(via
		(at 260.18236 -37.2364)
		(size 0.508)
		(drill 0.254)
		(layers "F.Cu" "B.Cu")
		(net "P52V_1_R")
	)
	(via
		(at 275.41855 -33.070038)
		(size 0.508)
		(drill 0.254)
		(layers "F.Cu" "B.Cu")
		(net "P52V_1_R")
	)
	(segment
		(start 292.123368 -27.709368)
		(end 296.5704 -32.1564)
		(width 1.016)
		(layer "B.Cu")
		(net "P52V_1_R")
	)
	(segment
		(start 260.18236 -35.433)
		(end 260.18236 -31.142432)
		(width 1.016)
		(layer "B.Cu")
		(net "P52V_1_R")
	)
	(segment
		(start 260.18236 -31.142432)
		(end 261.5946 -29.730192)
		(width 1.016)
		(layer "B.Cu")
		(net "P52V_1_R")
	)
	(segment
		(start 296.5704 -46.863)
		(end 296.5704 -48.14824)
		(width 1.016)
		(layer "B.Cu")
		(net "P52V_1_R")
	)
	(segment
		(start 273.6088 -23.0886)
		(end 280.967434 -23.0886)
		(width 1.016)
		(layer "B.Cu")
		(net "P52V_1_R")
	)
	(segment
		(start 273.6088 -23.0886)
		(end 272.5928 -23.0886)
		(width 1.016)
		(layer "B.Cu")
		(net "P52V_1_R")
	)
	(segment
		(start 260.18236 -35.433)
		(end 260.18236 -37.2364)
		(width 1.016)
		(layer "B.Cu")
		(net "P52V_1_R")
	)
	(segment
		(start 296.5704 -45.847)
		(end 296.5704 -46.863)
		(width 1.016)
		(layer "B.Cu")
		(net "P52V_1_R")
	)
	(segment
		(start 263.0932 -22.606)
		(end 272.1102 -22.606)
		(width 1.016)
		(layer "B.Cu")
		(net "P52V_1_R")
	)
	(segment
		(start 296.5704 -32.1564)
		(end 296.5704 -45.847)
		(width 1.016)
		(layer "B.Cu")
		(net "P52V_1_R")
	)
	(segment
		(start 272.1102 -22.606)
		(end 272.5928 -23.0886)
		(width 1.016)
		(layer "B.Cu")
		(net "P52V_1_R")
	)
	(segment
		(start 280.967434 -23.0886)
		(end 292.123368 -27.709368)
		(width 1.016)
		(layer "B.Cu")
		(net "P52V_1_R")
	)
	(segment
		(start 261.5946 -29.730192)
		(end 261.5946 -24.1046)
		(width 1.016)
		(layer "B.Cu")
		(net "P52V_1_R")
	)
	(segment
		(start 261.5946 -24.1046)
		(end 263.0932 -22.606)
		(width 1.016)
		(layer "B.Cu")
		(net "P52V_1_R")
	)
	(segment
		(start 278.19731 -23.81504)
		(end 278.1554 -23.85695)
		(width 0.4572)
		(layer "F.Cu")
		(net "P3V3_AND")
	)
	(segment
		(start 276.225 -22.606)
		(end 277.114 -22.606)
		(width 0.4572)
		(layer "F.Cu")
		(net "P3V3_AND")
	)
	(segment
		(start 279.470104 -23.81504)
		(end 278.19731 -23.81504)
		(width 0.4572)
		(layer "F.Cu")
		(net "P3V3_AND")
	)
	(segment
		(start 275.19376 -24.2316)
		(end 275.19376 -23.63724)
		(width 0.4572)
		(layer "F.Cu")
		(net "P3V3_AND")
	)
	(segment
		(start 275.19376 -23.63724)
		(end 276.225 -22.606)
		(width 0.4572)
		(layer "F.Cu")
		(net "P3V3_AND")
	)
	(segment
		(start 278.1554 -23.85695)
		(end 277.114 -23.85695)
		(width 0.4572)
		(layer "F.Cu")
		(net "P3V3_AND")
	)
	(segment
		(start 277.114 -23.85695)
		(end 277.114 -22.606)
		(width 0.4572)
		(layer "F.Cu")
		(net "P3V3_AND")
	)
	(via
		(at 277.114 -22.606)
		(size 0.762)
		(drill 0.381)
		(layers "F.Cu" "B.Cu")
		(net "P3V3_AND")
	)
	(segment
		(start 281.869896 -22.403054)
		(end 281.92095 -22.352)
		(width 0.17272)
		(layer "F.Cu")
		(net "FM_HSC_EN_BUSBAR")
	)
	(segment
		(start 281.869896 -23.81504)
		(end 281.869896 -22.403054)
		(width 0.17272)
		(layer "F.Cu")
		(net "FM_HSC_EN_BUSBAR")
	)
	(segment
		(start 284.54604 -23.81504)
		(end 284.734 -24.003)
		(width 0.17272)
		(layer "F.Cu")
		(net "FM_HSC_EN_BUSBAR")
	)
	(segment
		(start 281.21864 -20.955)
		(end 280.34996 -20.955)
		(width 0.17272)
		(layer "F.Cu")
		(net "FM_HSC_EN_BUSBAR")
	)
	(segment
		(start 281.9654 -22.30755)
		(end 281.9654 -21.082)
		(width 0.17272)
		(layer "F.Cu")
		(net "FM_HSC_EN_BUSBAR")
	)
	(segment
		(start 281.869896 -23.81504)
		(end 284.54604 -23.81504)
		(width 0.17272)
		(layer "F.Cu")
		(net "FM_HSC_EN_BUSBAR")
	)
	(segment
		(start 281.34564 -21.082)
		(end 281.21864 -20.955)
		(width 0.17272)
		(layer "F.Cu")
		(net "FM_HSC_EN_BUSBAR")
	)
	(segment
		(start 281.92095 -22.352)
		(end 281.9654 -22.30755)
		(width 0.17272)
		(layer "F.Cu")
		(net "FM_HSC_EN_BUSBAR")
	)
	(segment
		(start 292.354 -22.9616)
		(end 291.3126 -24.003)
		(width 0.17272)
		(layer "F.Cu")
		(net "FM_HSC_EN_BUSBAR")
	)
	(segment
		(start 281.9654 -21.082)
		(end 281.34564 -21.082)
		(width 0.17272)
		(layer "F.Cu")
		(net "FM_HSC_EN_BUSBAR")
	)
	(segment
		(start 291.3126 -24.003)
		(end 284.734 -24.003)
		(width 0.17272)
		(layer "F.Cu")
		(net "FM_HSC_EN_BUSBAR")
	)
	(via
		(at 284.734 -24.003)
		(size 0.762)
		(drill 0.381)
		(layers "F.Cu" "B.Cu")
		(net "FM_HSC_EN_BUSBAR")
	)
	(segment
		(start 283.337 -24.765)
		(end 286.258 -24.765)
		(width 0.17272)
		(layer "F.Cu")
		(net "FM_HSC_EN_FUSE")
	)
	(segment
		(start 286.258 -24.765)
		(end 286.766 -25.273)
		(width 0.17272)
		(layer "F.Cu")
		(net "FM_HSC_EN_FUSE")
	)
	(segment
		(start 281.869896 -24.765)
		(end 283.337 -24.765)
		(width 0.17272)
		(layer "F.Cu")
		(net "FM_HSC_EN_FUSE")
	)
	(segment
		(start 286.766 -25.273)
		(end 295.1226 -25.273)
		(width 0.17272)
		(layer "F.Cu")
		(net "FM_HSC_EN_FUSE")
	)
	(segment
		(start 297.3324 -27.98445)
		(end 297.66895 -28.321)
		(width 0.17272)
		(layer "F.Cu")
		(net "FM_HSC_EN_FUSE")
	)
	(segment
		(start 297.434 -26.12644)
		(end 297.434 -22.9616)
		(width 0.17272)
		(layer "F.Cu")
		(net "FM_HSC_EN_FUSE")
	)
	(segment
		(start 297.3324 -26.797)
		(end 297.3324 -26.22804)
		(width 0.17272)
		(layer "F.Cu")
		(net "FM_HSC_EN_FUSE")
	)
	(segment
		(start 296.164 -35.75304)
		(end 296.164 -29.82595)
		(width 0.17272)
		(layer "F.Cu")
		(net "FM_HSC_EN_FUSE")
	)
	(segment
		(start 296.164 -29.82595)
		(end 297.66895 -28.321)
		(width 0.17272)
		(layer "F.Cu")
		(net "FM_HSC_EN_FUSE")
	)
	(segment
		(start 297.3324 -26.797)
		(end 297.3324 -27.98445)
		(width 0.17272)
		(layer "F.Cu")
		(net "FM_HSC_EN_FUSE")
	)
	(segment
		(start 295.1226 -25.273)
		(end 297.434 -22.9616)
		(width 0.17272)
		(layer "F.Cu")
		(net "FM_HSC_EN_FUSE")
	)
	(segment
		(start 297.3324 -26.22804)
		(end 297.434 -26.12644)
		(width 0.17272)
		(layer "F.Cu")
		(net "FM_HSC_EN_FUSE")
	)
	(via
		(at 283.337 -24.765)
		(size 0.762)
		(drill 0.381)
		(layers "F.Cu" "B.Cu")
		(net "FM_HSC_EN_FUSE")
	)
	(segment
		(start 278.627078 -36.358576)
		(end 278.003 -36.358576)
		(width 0.17272)
		(layer "F.Cu")
		(net "SMB_P52V_HSC_SDA")
	)
	(segment
		(start 278.61895 -37.465)
		(end 278.61895 -36.366704)
		(width 0.17272)
		(layer "F.Cu")
		(net "SMB_P52V_HSC_SDA")
	)
	(segment
		(start 268.732 -48.02505)
		(end 267.589 -48.02505)
		(width 0.17272)
		(layer "F.Cu")
		(net "SMB_P52V_HSC_SDA")
	)
	(segment
		(start 279.410922 -38.571424)
		(end 279.410922 -38.29812)
		(width 0.17272)
		(layer "F.Cu")
		(net "SMB_P52V_HSC_SDA")
	)
	(segment
		(start 279.410922 -38.29812)
		(end 278.61895 -37.506148)
		(width 0.17272)
		(layer "F.Cu")
		(net "SMB_P52V_HSC_SDA")
	)
	(segment
		(start 268.732 -48.02505)
		(end 268.732 -48.641)
		(width 0.17272)
		(layer "F.Cu")
		(net "SMB_P52V_HSC_SDA")
	)
	(segment
		(start 278.61895 -37.506148)
		(end 278.61895 -37.465)
		(width 0.17272)
		(layer "F.Cu")
		(net "SMB_P52V_HSC_SDA")
	)
	(segment
		(start 278.61895 -36.366704)
		(end 278.627078 -36.358576)
		(width 0.17272)
		(layer "F.Cu")
		(net "SMB_P52V_HSC_SDA")
	)
	(segment
		(start 259.73405 -24.892)
		(end 259.73405 -25.63495)
		(width 0.17272)
		(layer "F.Cu")
		(net "SMB_P52V_HSC_SDA")
	)
	(via
		(at 278.003 -36.358576)
		(size 0.508)
		(drill 0.254)
		(layers "F.Cu" "B.Cu")
		(net "SMB_P52V_HSC_SDA")
	)
	(via
		(at 259.73405 -25.63495)
		(size 0.508)
		(drill 0.254)
		(layers "F.Cu" "B.Cu")
		(net "SMB_P52V_HSC_SDA")
	)
	(via
		(at 268.732 -48.641)
		(size 0.508)
		(drill 0.254)
		(layers "F.Cu" "B.Cu")
		(net "SMB_P52V_HSC_SDA")
	)
	(via
		(at 185.928 -82.804)
		(size 0.508)
		(drill 0.254)
		(layers "F.Cu" "B.Cu")
		(net "SMB_P52V_HSC_SDA")
	)
	(segment
		(start 185.90895 -83.439)
		(end 185.90895 -82.82305)
		(width 0.17272)
		(layer "B.Cu")
		(net "SMB_P52V_HSC_SDA")
	)
	(segment
		(start 185.90895 -82.82305)
		(end 185.928 -82.804)
		(width 0.17272)
		(layer "B.Cu")
		(net "SMB_P52V_HSC_SDA")
	)
	(segment
		(start 218.48191 -64.618362)
		(end 218.48191 -71.225156)
		(width 0.12954)
		(layer "In7.Cu")
		(net "SMB_P52V_HSC_SDA")
	)
	(segment
		(start 187.198 -81.534)
		(end 185.928 -82.804)
		(width 0.12954)
		(layer "In7.Cu")
		(net "SMB_P52V_HSC_SDA")
	)
	(segment
		(start 221.2848 -74.549)
		(end 220.77426 -75.05954)
		(width 0.12954)
		(layer "In7.Cu")
		(net "SMB_P52V_HSC_SDA")
	)
	(segment
		(start 278.003 -36.358576)
		(end 278.003 -31.877)
		(width 0.12954)
		(layer "In7.Cu")
		(net "SMB_P52V_HSC_SDA")
	)
	(segment
		(start 273.06905 -26.94305)
		(end 261.04215 -26.94305)
		(width 0.12954)
		(layer "In7.Cu")
		(net "SMB_P52V_HSC_SDA")
	)
	(segment
		(start 260.3754 -29.6164)
		(end 254.39878 -35.59302)
		(width 0.12954)
		(layer "In7.Cu")
		(net "SMB_P52V_HSC_SDA")
	)
	(segment
		(start 278.003 -31.877)
		(end 273.06905 -26.94305)
		(width 0.12954)
		(layer "In7.Cu")
		(net "SMB_P52V_HSC_SDA")
	)
	(segment
		(start 218.72448 -52.625244)
		(end 218.72448 -64.375792)
		(width 0.12954)
		(layer "In7.Cu")
		(net "SMB_P52V_HSC_SDA")
	)
	(segment
		(start 278.003 -36.8808)
		(end 275.336 -39.5478)
		(width 0.12954)
		(layer "In7.Cu")
		(net "SMB_P52V_HSC_SDA")
	)
	(segment
		(start 275.336 -39.5478)
		(end 274.8534 -39.5478)
		(width 0.12954)
		(layer "In7.Cu")
		(net "SMB_P52V_HSC_SDA")
	)
	(segment
		(start 254.39878 -35.59302)
		(end 254.39878 -40.037512)
		(width 0.12954)
		(layer "In7.Cu")
		(net "SMB_P52V_HSC_SDA")
	)
	(segment
		(start 213.8934 -76.064618)
		(end 213.8934 -77.0382)
		(width 0.12954)
		(layer "In7.Cu")
		(net "SMB_P52V_HSC_SDA")
	)
	(segment
		(start 221.2848 -73.3044)
		(end 221.2848 -74.549)
		(width 0.12954)
		(layer "In7.Cu")
		(net "SMB_P52V_HSC_SDA")
	)
	(segment
		(start 205.725522 -75.46086)
		(end 198.88454 -75.46086)
		(width 0.12954)
		(layer "In7.Cu")
		(net "SMB_P52V_HSC_SDA")
	)
	(segment
		(start 259.73405 -25.63495)
		(end 259.73405 -28.507182)
		(width 0.12954)
		(layer "In7.Cu")
		(net "SMB_P52V_HSC_SDA")
	)
	(segment
		(start 212.852 -78.0796)
		(end 208.344262 -78.0796)
		(width 0.12954)
		(layer "In7.Cu")
		(net "SMB_P52V_HSC_SDA")
	)
	(segment
		(start 213.8934 -77.0382)
		(end 212.852 -78.0796)
		(width 0.12954)
		(layer "In7.Cu")
		(net "SMB_P52V_HSC_SDA")
	)
	(segment
		(start 208.344262 -78.0796)
		(end 205.725522 -75.46086)
		(width 0.12954)
		(layer "In7.Cu")
		(net "SMB_P52V_HSC_SDA")
	)
	(segment
		(start 219.740734 -72.48398)
		(end 220.46438 -72.48398)
		(width 0.12954)
		(layer "In7.Cu")
		(net "SMB_P52V_HSC_SDA")
	)
	(segment
		(start 274.8534 -39.5478)
		(end 268.732 -45.6692)
		(width 0.12954)
		(layer "In7.Cu")
		(net "SMB_P52V_HSC_SDA")
	)
	(segment
		(start 218.48191 -71.225156)
		(end 219.740734 -72.48398)
		(width 0.12954)
		(layer "In7.Cu")
		(net "SMB_P52V_HSC_SDA")
	)
	(segment
		(start 254.39878 -40.037512)
		(end 247.940576 -46.495716)
		(width 0.12954)
		(layer "In7.Cu")
		(net "SMB_P52V_HSC_SDA")
	)
	(segment
		(start 278.003 -36.358576)
		(end 278.003 -36.8808)
		(width 0.12954)
		(layer "In7.Cu")
		(net "SMB_P52V_HSC_SDA")
	)
	(segment
		(start 247.940576 -46.495716)
		(end 224.854008 -46.495716)
		(width 0.12954)
		(layer "In7.Cu")
		(net "SMB_P52V_HSC_SDA")
	)
	(segment
		(start 198.88454 -75.46086)
		(end 192.8114 -81.534)
		(width 0.12954)
		(layer "In7.Cu")
		(net "SMB_P52V_HSC_SDA")
	)
	(segment
		(start 192.8114 -81.534)
		(end 187.198 -81.534)
		(width 0.12954)
		(layer "In7.Cu")
		(net "SMB_P52V_HSC_SDA")
	)
	(segment
		(start 218.72448 -64.375792)
		(end 218.48191 -64.618362)
		(width 0.12954)
		(layer "In7.Cu")
		(net "SMB_P52V_HSC_SDA")
	)
	(segment
		(start 261.04215 -26.94305)
		(end 259.73405 -25.63495)
		(width 0.12954)
		(layer "In7.Cu")
		(net "SMB_P52V_HSC_SDA")
	)
	(segment
		(start 214.898478 -75.05954)
		(end 213.8934 -76.064618)
		(width 0.12954)
		(layer "In7.Cu")
		(net "SMB_P52V_HSC_SDA")
	)
	(segment
		(start 268.732 -45.6692)
		(end 268.732 -48.641)
		(width 0.12954)
		(layer "In7.Cu")
		(net "SMB_P52V_HSC_SDA")
	)
	(segment
		(start 220.77426 -75.05954)
		(end 214.898478 -75.05954)
		(width 0.12954)
		(layer "In7.Cu")
		(net "SMB_P52V_HSC_SDA")
	)
	(segment
		(start 260.3754 -29.148532)
		(end 260.3754 -29.6164)
		(width 0.12954)
		(layer "In7.Cu")
		(net "SMB_P52V_HSC_SDA")
	)
	(segment
		(start 220.46438 -72.48398)
		(end 221.2848 -73.3044)
		(width 0.12954)
		(layer "In7.Cu")
		(net "SMB_P52V_HSC_SDA")
	)
	(segment
		(start 224.854008 -46.495716)
		(end 218.72448 -52.625244)
		(width 0.12954)
		(layer "In7.Cu")
		(net "SMB_P52V_HSC_SDA")
	)
	(segment
		(start 259.73405 -28.507182)
		(end 260.3754 -29.148532)
		(width 0.12954)
		(layer "In7.Cu")
		(net "SMB_P52V_HSC_SDA")
	)
	(segment
		(start 259.710682 -29.508704)
		(end 259.73405 -29.485336)
		(width 0.17272)
		(layer "F.Cu")
		(net "SMB_P52V_HSC_SCL")
	)
	(segment
		(start 277.599902 -40.744902)
		(end 278.610822 -40.744902)
		(width 0.17272)
		(layer "F.Cu")
		(net "SMB_P52V_HSC_SCL")
	)
	(segment
		(start 259.73405 -29.485336)
		(end 259.73405 -29.337)
		(width 0.17272)
		(layer "F.Cu")
		(net "SMB_P52V_HSC_SCL")
	)
	(segment
		(start 259.73405 -29.972)
		(end 259.710682 -29.948632)
		(width 0.17272)
		(layer "F.Cu")
		(net "SMB_P52V_HSC_SCL")
	)
	(segment
		(start 277.368 -40.513)
		(end 277.599902 -40.744902)
		(width 0.17272)
		(layer "F.Cu")
		(net "SMB_P52V_HSC_SCL")
	)
	(segment
		(start 259.710682 -29.948632)
		(end 259.710682 -29.508704)
		(width 0.17272)
		(layer "F.Cu")
		(net "SMB_P52V_HSC_SCL")
	)
	(segment
		(start 269.875 -48.02505)
		(end 269.875 -48.641)
		(width 0.17272)
		(layer "F.Cu")
		(net "SMB_P52V_HSC_SCL")
	)
	(via
		(at 269.875 -48.641)
		(size 0.508)
		(drill 0.254)
		(layers "F.Cu" "B.Cu")
		(net "SMB_P52V_HSC_SCL")
	)
	(via
		(at 185.90895 -85.344)
		(size 0.508)
		(drill 0.254)
		(layers "F.Cu" "B.Cu")
		(net "SMB_P52V_HSC_SCL")
	)
	(via
		(at 277.368 -40.513)
		(size 0.508)
		(drill 0.254)
		(layers "F.Cu" "B.Cu")
		(net "SMB_P52V_HSC_SCL")
	)
	(via
		(at 259.73405 -29.337)
		(size 0.508)
		(drill 0.254)
		(layers "F.Cu" "B.Cu")
		(net "SMB_P52V_HSC_SCL")
	)
	(segment
		(start 185.90895 -85.979)
		(end 185.90895 -85.344)
		(width 0.17272)
		(layer "B.Cu")
		(net "SMB_P52V_HSC_SCL")
	)
	(segment
		(start 185.42 -84.85505)
		(end 185.90895 -85.344)
		(width 0.12954)
		(layer "In7.Cu")
		(net "SMB_P52V_HSC_SCL")
	)
	(segment
		(start 185.42 -82.482182)
		(end 185.42 -84.85505)
		(width 0.12954)
		(layer "In7.Cu")
		(net "SMB_P52V_HSC_SCL")
	)
	(segment
		(start 213.2838 -76.7588)
		(end 212.5726 -77.47)
		(width 0.12954)
		(layer "In7.Cu")
		(net "SMB_P52V_HSC_SCL")
	)
	(segment
		(start 253.81204 -39.794434)
		(end 247.697498 -45.908976)
		(width 0.12954)
		(layer "In7.Cu")
		(net "SMB_P52V_HSC_SCL")
	)
	(segment
		(start 220.69806 -74.24674)
		(end 220.472 -74.4728)
		(width 0.12954)
		(layer "In7.Cu")
		(net "SMB_P52V_HSC_SCL")
	)
	(segment
		(start 277.368 -40.513)
		(end 277.368 -39.878)
		(width 0.12954)
		(layer "In7.Cu")
		(net "SMB_P52V_HSC_SCL")
	)
	(segment
		(start 208.6102 -77.47)
		(end 205.9432 -74.803)
		(width 0.12954)
		(layer "In7.Cu")
		(net "SMB_P52V_HSC_SCL")
	)
	(segment
		(start 186.954922 -80.94726)
		(end 185.42 -82.482182)
		(width 0.12954)
		(layer "In7.Cu")
		(net "SMB_P52V_HSC_SCL")
	)
	(segment
		(start 278.638 -38.608)
		(end 278.638 -31.623)
		(width 0.12954)
		(layer "In7.Cu")
		(net "SMB_P52V_HSC_SCL")
	)
	(segment
		(start 218.13774 -52.382166)
		(end 218.13774 -64.132714)
		(width 0.12954)
		(layer "In7.Cu")
		(net "SMB_P52V_HSC_SCL")
	)
	(segment
		(start 259.14731 -25.555194)
		(end 259.14731 -28.75026)
		(width 0.12954)
		(layer "In7.Cu")
		(net "SMB_P52V_HSC_SCL")
	)
	(segment
		(start 220.472 -74.4728)
		(end 214.6554 -74.4728)
		(width 0.12954)
		(layer "In7.Cu")
		(net "SMB_P52V_HSC_SCL")
	)
	(segment
		(start 259.14731 -28.75026)
		(end 259.73405 -29.337)
		(width 0.12954)
		(layer "In7.Cu")
		(net "SMB_P52V_HSC_SCL")
	)
	(segment
		(start 278.638 -31.623)
		(end 273.37131 -26.35631)
		(width 0.12954)
		(layer "In7.Cu")
		(net "SMB_P52V_HSC_SCL")
	)
	(segment
		(start 214.6554 -74.4728)
		(end 213.2838 -75.8444)
		(width 0.12954)
		(layer "In7.Cu")
		(net "SMB_P52V_HSC_SCL")
	)
	(segment
		(start 273.37131 -26.35631)
		(end 261.285482 -26.35631)
		(width 0.12954)
		(layer "In7.Cu")
		(net "SMB_P52V_HSC_SCL")
	)
	(segment
		(start 273.558 -44.958)
		(end 275.7551 -44.958)
		(width 0.12954)
		(layer "In7.Cu")
		(net "SMB_P52V_HSC_SCL")
	)
	(segment
		(start 259.73405 -29.337)
		(end 253.81204 -35.25901)
		(width 0.12954)
		(layer "In7.Cu")
		(net "SMB_P52V_HSC_SCL")
	)
	(segment
		(start 269.875 -48.641)
		(end 273.558 -44.958)
		(width 0.12954)
		(layer "In7.Cu")
		(net "SMB_P52V_HSC_SCL")
	)
	(segment
		(start 277.368 -43.3451)
		(end 277.368 -40.513)
		(width 0.12954)
		(layer "In7.Cu")
		(net "SMB_P52V_HSC_SCL")
	)
	(segment
		(start 261.285482 -26.35631)
		(end 260.092952 -25.16378)
		(width 0.12954)
		(layer "In7.Cu")
		(net "SMB_P52V_HSC_SCL")
	)
	(segment
		(start 198.602346 -74.803)
		(end 192.458086 -80.94726)
		(width 0.12954)
		(layer "In7.Cu")
		(net "SMB_P52V_HSC_SCL")
	)
	(segment
		(start 247.697498 -45.908976)
		(end 224.61093 -45.908976)
		(width 0.12954)
		(layer "In7.Cu")
		(net "SMB_P52V_HSC_SCL")
	)
	(segment
		(start 205.9432 -74.803)
		(end 198.602346 -74.803)
		(width 0.12954)
		(layer "In7.Cu")
		(net "SMB_P52V_HSC_SCL")
	)
	(segment
		(start 224.61093 -45.908976)
		(end 218.13774 -52.382166)
		(width 0.12954)
		(layer "In7.Cu")
		(net "SMB_P52V_HSC_SCL")
	)
	(segment
		(start 260.092952 -25.16378)
		(end 259.538724 -25.16378)
		(width 0.12954)
		(layer "In7.Cu")
		(net "SMB_P52V_HSC_SCL")
	)
	(segment
		(start 220.16212 -73.07072)
		(end 220.69806 -73.60666)
		(width 0.12954)
		(layer "In7.Cu")
		(net "SMB_P52V_HSC_SCL")
	)
	(segment
		(start 220.69806 -73.60666)
		(end 220.69806 -74.24674)
		(width 0.12954)
		(layer "In7.Cu")
		(net "SMB_P52V_HSC_SCL")
	)
	(segment
		(start 213.2838 -75.8444)
		(end 213.2838 -76.7588)
		(width 0.12954)
		(layer "In7.Cu")
		(net "SMB_P52V_HSC_SCL")
	)
	(segment
		(start 253.81204 -35.25901)
		(end 253.81204 -39.794434)
		(width 0.12954)
		(layer "In7.Cu")
		(net "SMB_P52V_HSC_SCL")
	)
	(segment
		(start 217.89517 -71.531988)
		(end 219.433902 -73.07072)
		(width 0.12954)
		(layer "In7.Cu")
		(net "SMB_P52V_HSC_SCL")
	)
	(segment
		(start 259.538724 -25.16378)
		(end 259.14731 -25.555194)
		(width 0.12954)
		(layer "In7.Cu")
		(net "SMB_P52V_HSC_SCL")
	)
	(segment
		(start 275.7551 -44.958)
		(end 277.368 -43.3451)
		(width 0.12954)
		(layer "In7.Cu")
		(net "SMB_P52V_HSC_SCL")
	)
	(segment
		(start 218.13774 -64.132714)
		(end 217.89517 -64.375284)
		(width 0.12954)
		(layer "In7.Cu")
		(net "SMB_P52V_HSC_SCL")
	)
	(segment
		(start 219.433902 -73.07072)
		(end 220.16212 -73.07072)
		(width 0.12954)
		(layer "In7.Cu")
		(net "SMB_P52V_HSC_SCL")
	)
	(segment
		(start 277.368 -39.878)
		(end 278.638 -38.608)
		(width 0.12954)
		(layer "In7.Cu")
		(net "SMB_P52V_HSC_SCL")
	)
	(segment
		(start 212.5726 -77.47)
		(end 208.6102 -77.47)
		(width 0.12954)
		(layer "In7.Cu")
		(net "SMB_P52V_HSC_SCL")
	)
	(segment
		(start 192.458086 -80.94726)
		(end 186.954922 -80.94726)
		(width 0.12954)
		(layer "In7.Cu")
		(net "SMB_P52V_HSC_SCL")
	)
	(segment
		(start 217.89517 -64.375284)
		(end 217.89517 -71.531988)
		(width 0.12954)
		(layer "In7.Cu")
		(net "SMB_P52V_HSC_SCL")
	)
	(via
		(at 31.242 -106.807)
		(size 0.508)
		(drill 0.254)
		(layers "F.Cu" "B.Cu")
		(net "P52V_FAN")
	)
	(via
		(at 30.353 -104.521)
		(size 0.508)
		(drill 0.254)
		(layers "F.Cu" "B.Cu")
		(net "P52V_FAN")
	)
	(via
		(at 30.353 -103.759)
		(size 0.508)
		(drill 0.254)
		(layers "F.Cu" "B.Cu")
		(net "P52V_FAN")
	)
	(via
		(at 30.353 -107.5944)
		(size 0.508)
		(drill 0.254)
		(layers "F.Cu" "B.Cu")
		(net "P52V_FAN")
	)
	(via
		(at 31.242 -105.283)
		(size 0.508)
		(drill 0.254)
		(layers "F.Cu" "B.Cu")
		(net "P52V_FAN")
	)
	(via
		(at 29.3878 -108.3818)
		(size 0.508)
		(drill 0.254)
		(layers "F.Cu" "B.Cu")
		(net "P52V_FAN")
	)
	(via
		(at 29.3878 -105.3084)
		(size 0.508)
		(drill 0.254)
		(layers "F.Cu" "B.Cu")
		(net "P52V_FAN")
	)
	(via
		(at 31.242 -107.5944)
		(size 0.508)
		(drill 0.254)
		(layers "F.Cu" "B.Cu")
		(net "P52V_FAN")
	)
	(via
		(at 29.3878 -103.7844)
		(size 0.508)
		(drill 0.254)
		(layers "F.Cu" "B.Cu")
		(net "P52V_FAN")
	)
	(via
		(at 32.639 -108.204)
		(size 0.6604)
		(drill 0.3302)
		(layers "F.Cu" "B.Cu")
		(net "P52V_FAN")
	)
	(via
		(at 31.242 -108.3564)
		(size 0.508)
		(drill 0.254)
		(layers "F.Cu" "B.Cu")
		(net "P52V_FAN")
	)
	(via
		(at 30.353 -106.045)
		(size 0.508)
		(drill 0.254)
		(layers "F.Cu" "B.Cu")
		(net "P52V_FAN")
	)
	(via
		(at 29.3878 -104.5464)
		(size 0.508)
		(drill 0.254)
		(layers "F.Cu" "B.Cu")
		(net "P52V_FAN")
	)
	(via
		(at 30.353 -105.283)
		(size 0.508)
		(drill 0.254)
		(layers "F.Cu" "B.Cu")
		(net "P52V_FAN")
	)
	(via
		(at 30.353 -106.807)
		(size 0.508)
		(drill 0.254)
		(layers "F.Cu" "B.Cu")
		(net "P52V_FAN")
	)
	(via
		(at 31.242 -106.045)
		(size 0.508)
		(drill 0.254)
		(layers "F.Cu" "B.Cu")
		(net "P52V_FAN")
	)
	(via
		(at 31.242 -103.759)
		(size 0.508)
		(drill 0.254)
		(layers "F.Cu" "B.Cu")
		(net "P52V_FAN")
	)
	(via
		(at 29.3878 -107.6198)
		(size 0.508)
		(drill 0.254)
		(layers "F.Cu" "B.Cu")
		(net "P52V_FAN")
	)
	(via
		(at 29.3878 -106.8324)
		(size 0.508)
		(drill 0.254)
		(layers "F.Cu" "B.Cu")
		(net "P52V_FAN")
	)
	(via
		(at 31.242 -104.521)
		(size 0.508)
		(drill 0.254)
		(layers "F.Cu" "B.Cu")
		(net "P52V_FAN")
	)
	(via
		(at 30.353 -108.3564)
		(size 0.508)
		(drill 0.254)
		(layers "F.Cu" "B.Cu")
		(net "P52V_FAN")
	)
	(via
		(at 29.3878 -106.0704)
		(size 0.508)
		(drill 0.254)
		(layers "F.Cu" "B.Cu")
		(net "P52V_FAN")
	)
	(segment
		(start 9.85012 -70.939914)
		(end 10.637774 -70.15226)
		(width 0.508)
		(layer "In2.Cu")
		(net "P52V_FAN")
	)
	(segment
		(start 9.062466 -71.727568)
		(end 9.85012 -70.939914)
		(width 0.508)
		(layer "In2.Cu")
		(net "P52V_FAN")
	)
	(segment
		(start 9.85012 -69.239892)
		(end 10.637774 -70.027546)
		(width 0.508)
		(layer "In2.Cu")
		(net "P52V_FAN")
	)
	(segment
		(start 12.39012 -70.939914)
		(end 13.177774 -71.727568)
		(width 0.508)
		(layer "In2.Cu")
		(net "P52V_FAN")
	)
	(segment
		(start 9.85012 -74.319892)
		(end 10.637774 -75.107546)
		(width 0.508)
		(layer "In2.Cu")
		(net "P52V_FAN")
	)
	(segment
		(start 9.85012 -76.019914)
		(end 10.637774 -76.807568)
		(width 0.508)
		(layer "In2.Cu")
		(net "P52V_FAN")
	)
	(segment
		(start 9.85012 -69.239892)
		(end 10.637774 -68.452238)
		(width 0.508)
		(layer "In2.Cu")
		(net "P52V_FAN")
	)
	(segment
		(start 9.85012 -76.019914)
		(end 10.637774 -75.23226)
		(width 0.508)
		(layer "In2.Cu")
		(net "P52V_FAN")
	)
	(segment
		(start 11.602466 -70.15226)
		(end 12.39012 -70.939914)
		(width 0.508)
		(layer "In2.Cu")
		(net "P52V_FAN")
	)
	(segment
		(start 9.062466 -68.452238)
		(end 9.85012 -69.239892)
		(width 0.508)
		(layer "In2.Cu")
		(net "P52V_FAN")
	)
	(segment
		(start 11.602466 -68.452238)
		(end 12.39012 -69.239892)
		(width 0.508)
		(layer "In2.Cu")
		(net "P52V_FAN")
	)
	(segment
		(start 9.85012 -70.939914)
		(end 10.637774 -71.727568)
		(width 0.508)
		(layer "In2.Cu")
		(net "P52V_FAN")
	)
	(segment
		(start 9.062466 -70.027546)
		(end 9.85012 -69.239892)
		(width 0.508)
		(layer "In2.Cu")
		(net "P52V_FAN")
	)
	(segment
		(start 9.062466 -76.807568)
		(end 9.85012 -76.019914)
		(width 0.508)
		(layer "In2.Cu")
		(net "P52V_FAN")
	)
	(segment
		(start 11.602466 -73.532238)
		(end 12.39012 -74.319892)
		(width 0.508)
		(layer "In2.Cu")
		(net "P52V_FAN")
	)
	(segment
		(start 9.062466 -75.107546)
		(end 9.85012 -74.319892)
		(width 0.508)
		(layer "In2.Cu")
		(net "P52V_FAN")
	)
	(segment
		(start 11.602466 -71.727568)
		(end 12.39012 -70.939914)
		(width 0.508)
		(layer "In2.Cu")
		(net "P52V_FAN")
	)
	(segment
		(start 12.39012 -74.319892)
		(end 13.177774 -75.107546)
		(width 0.508)
		(layer "In2.Cu")
		(net "P52V_FAN")
	)
	(segment
		(start 11.602466 -75.23226)
		(end 12.39012 -76.019914)
		(width 0.508)
		(layer "In2.Cu")
		(net "P52V_FAN")
	)
	(segment
		(start 12.39012 -70.939914)
		(end 13.177774 -70.15226)
		(width 0.508)
		(layer "In2.Cu")
		(net "P52V_FAN")
	)
	(segment
		(start 12.39012 -74.319892)
		(end 13.177774 -73.532238)
		(width 0.508)
		(layer "In2.Cu")
		(net "P52V_FAN")
	)
	(segment
		(start 9.062466 -73.532238)
		(end 9.85012 -74.319892)
		(width 0.508)
		(layer "In2.Cu")
		(net "P52V_FAN")
	)
	(segment
		(start 9.062466 -70.15226)
		(end 9.85012 -70.939914)
		(width 0.508)
		(layer "In2.Cu")
		(net "P52V_FAN")
	)
	(segment
		(start 12.39012 -76.019914)
		(end 13.177774 -75.23226)
		(width 0.508)
		(layer "In2.Cu")
		(net "P52V_FAN")
	)
	(segment
		(start 11.602466 -76.807568)
		(end 12.39012 -76.019914)
		(width 0.508)
		(layer "In2.Cu")
		(net "P52V_FAN")
	)
	(segment
		(start 9.85012 -74.319892)
		(end 10.637774 -73.532238)
		(width 0.508)
		(layer "In2.Cu")
		(net "P52V_FAN")
	)
	(segment
		(start 12.39012 -76.019914)
		(end 13.177774 -76.807568)
		(width 0.508)
		(layer "In2.Cu")
		(net "P52V_FAN")
	)
	(segment
		(start 12.39012 -69.239892)
		(end 13.177774 -70.027546)
		(width 0.508)
		(layer "In2.Cu")
		(net "P52V_FAN")
	)
	(segment
		(start 9.062466 -75.23226)
		(end 9.85012 -76.019914)
		(width 0.508)
		(layer "In2.Cu")
		(net "P52V_FAN")
	)
	(segment
		(start 11.602466 -70.027546)
		(end 12.39012 -69.239892)
		(width 0.508)
		(layer "In2.Cu")
		(net "P52V_FAN")
	)
	(segment
		(start 11.602466 -75.107546)
		(end 12.39012 -74.319892)
		(width 0.508)
		(layer "In2.Cu")
		(net "P52V_FAN")
	)
	(segment
		(start 12.39012 -69.239892)
		(end 13.177774 -68.452238)
		(width 0.508)
		(layer "In2.Cu")
		(net "P52V_FAN")
	)
	(segment
		(start 9.062466 -75.107546)
		(end 9.85012 -74.319892)
		(width 0.508)
		(layer "In7.Cu")
		(net "P52V_FAN")
	)
	(segment
		(start 11.602466 -71.727568)
		(end 12.39012 -70.939914)
		(width 0.508)
		(layer "In7.Cu")
		(net "P52V_FAN")
	)
	(segment
		(start 9.062466 -75.23226)
		(end 9.85012 -76.019914)
		(width 0.508)
		(layer "In7.Cu")
		(net "P52V_FAN")
	)
	(segment
		(start 9.062466 -71.727568)
		(end 9.85012 -70.939914)
		(width 0.508)
		(layer "In7.Cu")
		(net "P52V_FAN")
	)
	(segment
		(start 9.85012 -76.019914)
		(end 10.637774 -75.23226)
		(width 0.508)
		(layer "In7.Cu")
		(net "P52V_FAN")
	)
	(segment
		(start 11.602466 -75.107546)
		(end 12.39012 -74.319892)
		(width 0.508)
		(layer "In7.Cu")
		(net "P52V_FAN")
	)
	(segment
		(start 9.85012 -76.019914)
		(end 10.637774 -76.807568)
		(width 0.508)
		(layer "In7.Cu")
		(net "P52V_FAN")
	)
	(segment
		(start 12.39012 -70.939914)
		(end 13.177774 -71.727568)
		(width 0.508)
		(layer "In7.Cu")
		(net "P52V_FAN")
	)
	(segment
		(start 9.85012 -70.939914)
		(end 10.637774 -70.15226)
		(width 0.508)
		(layer "In7.Cu")
		(net "P52V_FAN")
	)
	(segment
		(start 9.062466 -73.532238)
		(end 9.85012 -74.319892)
		(width 0.508)
		(layer "In7.Cu")
		(net "P52V_FAN")
	)
	(segment
		(start 9.85012 -74.319892)
		(end 10.637774 -73.532238)
		(width 0.508)
		(layer "In7.Cu")
		(net "P52V_FAN")
	)
	(segment
		(start 12.39012 -76.019914)
		(end 13.177774 -76.807568)
		(width 0.508)
		(layer "In7.Cu")
		(net "P52V_FAN")
	)
	(segment
		(start 12.39012 -74.319892)
		(end 13.177774 -75.107546)
		(width 0.508)
		(layer "In7.Cu")
		(net "P52V_FAN")
	)
	(segment
		(start 9.85012 -69.239892)
		(end 10.637774 -68.452238)
		(width 0.508)
		(layer "In7.Cu")
		(net "P52V_FAN")
	)
	(segment
		(start 9.062466 -76.807568)
		(end 9.85012 -76.019914)
		(width 0.508)
		(layer "In7.Cu")
		(net "P52V_FAN")
	)
	(segment
		(start 11.602466 -73.532238)
		(end 12.39012 -74.319892)
		(width 0.508)
		(layer "In7.Cu")
		(net "P52V_FAN")
	)
	(segment
		(start 9.062466 -70.15226)
		(end 9.85012 -70.939914)
		(width 0.508)
		(layer "In7.Cu")
		(net "P52V_FAN")
	)
	(segment
		(start 12.39012 -69.239892)
		(end 13.177774 -70.027546)
		(width 0.508)
		(layer "In7.Cu")
		(net "P52V_FAN")
	)
	(segment
		(start 9.85012 -70.939914)
		(end 10.637774 -71.727568)
		(width 0.508)
		(layer "In7.Cu")
		(net "P52V_FAN")
	)
	(segment
		(start 11.602466 -76.807568)
		(end 12.39012 -76.019914)
		(width 0.508)
		(layer "In7.Cu")
		(net "P52V_FAN")
	)
	(segment
		(start 12.39012 -76.019914)
		(end 13.177774 -75.23226)
		(width 0.508)
		(layer "In7.Cu")
		(net "P52V_FAN")
	)
	(segment
		(start 11.602466 -70.027546)
		(end 12.39012 -69.239892)
		(width 0.508)
		(layer "In7.Cu")
		(net "P52V_FAN")
	)
	(segment
		(start 12.39012 -74.319892)
		(end 13.177774 -73.532238)
		(width 0.508)
		(layer "In7.Cu")
		(net "P52V_FAN")
	)
	(segment
		(start 12.39012 -70.939914)
		(end 13.177774 -70.15226)
		(width 0.508)
		(layer "In7.Cu")
		(net "P52V_FAN")
	)
	(segment
		(start 9.062466 -70.027546)
		(end 9.85012 -69.239892)
		(width 0.508)
		(layer "In7.Cu")
		(net "P52V_FAN")
	)
	(segment
		(start 12.39012 -69.239892)
		(end 13.177774 -68.452238)
		(width 0.508)
		(layer "In7.Cu")
		(net "P52V_FAN")
	)
	(segment
		(start 11.602466 -68.452238)
		(end 12.39012 -69.239892)
		(width 0.508)
		(layer "In7.Cu")
		(net "P52V_FAN")
	)
	(segment
		(start 9.85012 -74.319892)
		(end 10.637774 -75.107546)
		(width 0.508)
		(layer "In7.Cu")
		(net "P52V_FAN")
	)
	(segment
		(start 9.062466 -68.452238)
		(end 9.85012 -69.239892)
		(width 0.508)
		(layer "In7.Cu")
		(net "P52V_FAN")
	)
	(segment
		(start 9.85012 -69.239892)
		(end 10.637774 -70.027546)
		(width 0.508)
		(layer "In7.Cu")
		(net "P52V_FAN")
	)
	(segment
		(start 11.602466 -70.15226)
		(end 12.39012 -70.939914)
		(width 0.508)
		(layer "In7.Cu")
		(net "P52V_FAN")
	)
	(segment
		(start 11.602466 -75.23226)
		(end 12.39012 -76.019914)
		(width 0.508)
		(layer "In7.Cu")
		(net "P52V_FAN")
	)
	(segment
		(start 269.875 -45.974)
		(end 269.875 -47.22495)
		(width 0.17272)
		(layer "F.Cu")
		(net "SMB_P52V_VPDB_SCL_R3")
	)
	(segment
		(start 268.525752 -42.592752)
		(end 269.875 -43.942)
		(width 0.17272)
		(layer "F.Cu")
		(net "SMB_P52V_VPDB_SCL_R3")
	)
	(segment
		(start 269.875 -43.942)
		(end 269.875 -45.974)
		(width 0.17272)
		(layer "F.Cu")
		(net "SMB_P52V_VPDB_SCL_R3")
	)
	(segment
		(start 267.19276 -42.592752)
		(end 268.525752 -42.592752)
		(width 0.17272)
		(layer "F.Cu")
		(net "SMB_P52V_VPDB_SCL_R3")
	)
	(via
		(at 269.875 -45.974)
		(size 0.762)
		(drill 0.381)
		(layers "F.Cu" "B.Cu")
		(net "SMB_P52V_VPDB_SCL_R3")
	)
	(segment
		(start 282.38196 -57.457086)
		(end 282.66136 -57.736486)
		(width 0.254)
		(layer "F.Cu")
		(net "P52V_HS1_TEMPN_R")
	)
	(segment
		(start 282.66136 -57.736486)
		(end 284.053026 -57.736486)
		(width 0.254)
		(layer "F.Cu")
		(net "P52V_HS1_TEMPN_R")
	)
	(segment
		(start 282.38196 -56.957214)
		(end 282.38196 -57.457086)
		(width 0.254)
		(layer "F.Cu")
		(net "P52V_HS1_TEMPN_R")
	)
	(segment
		(start 288.29 -56.0324)
		(end 287.41116 -56.91124)
		(width 0.254)
		(layer "F.Cu")
		(net "P52V_HS1_TEMPN_R")
	)
	(segment
		(start 284.053026 -57.736486)
		(end 284.878272 -56.91124)
		(width 0.254)
		(layer "F.Cu")
		(net "P52V_HS1_TEMPN_R")
	)
	(segment
		(start 287.41116 -56.91124)
		(end 284.878272 -56.91124)
		(width 0.254)
		(layer "F.Cu")
		(net "P52V_HS1_TEMPN_R")
	)
	(via
		(at 288.29 -56.0324)
		(size 0.762)
		(drill 0.381)
		(layers "F.Cu" "B.Cu")
		(net "P52V_HS1_TEMPN_R")
	)
	(segment
		(start 284.052518 -58.117486)
		(end 284.878272 -58.94324)
		(width 0.254)
		(layer "F.Cu")
		(net "P52V_HS1_TEMP_R")
	)
	(segment
		(start 282.360624 -58.371486)
		(end 282.614624 -58.117486)
		(width 0.254)
		(layer "F.Cu")
		(net "P52V_HS1_TEMP_R")
	)
	(segment
		(start 287.113472 -57.92724)
		(end 288.6964 -57.92724)
		(width 0.254)
		(layer "F.Cu")
		(net "P52V_HS1_TEMP_R")
	)
	(segment
		(start 287.113472 -57.92724)
		(end 285.894272 -57.92724)
		(width 0.254)
		(layer "F.Cu")
		(net "P52V_HS1_TEMP_R")
	)
	(segment
		(start 282.360624 -58.862214)
		(end 282.360624 -58.371486)
		(width 0.254)
		(layer "F.Cu")
		(net "P52V_HS1_TEMP_R")
	)
	(segment
		(start 282.614624 -58.117486)
		(end 284.052518 -58.117486)
		(width 0.254)
		(layer "F.Cu")
		(net "P52V_HS1_TEMP_R")
	)
	(segment
		(start 285.894272 -57.92724)
		(end 284.878272 -58.94324)
		(width 0.254)
		(layer "F.Cu")
		(net "P52V_HS1_TEMP_R")
	)
	(via
		(at 288.6964 -57.92724)
		(size 0.762)
		(drill 0.381)
		(layers "F.Cu" "B.Cu")
		(net "P52V_HS1_TEMP_R")
	)
	(segment
		(start 291.494972 -43.090846)
		(end 291.89299 -43.090846)
		(width 0.3048)
		(layer "F.Cu")
		(net "P52V_HS1_1272_GATE")
	)
	(segment
		(start 292.735 -43.932856)
		(end 292.735 -47.371)
		(width 0.381)
		(layer "F.Cu")
		(net "P52V_HS1_1272_GATE")
	)
	(segment
		(start 291.89299 -43.090846)
		(end 292.735 -43.932856)
		(width 0.3048)
		(layer "F.Cu")
		(net "P52V_HS1_1272_GATE")
	)
	(via
		(at 292.735 -47.371)
		(size 0.508)
		(drill 0.254)
		(layers "F.Cu" "B.Cu")
		(net "P52V_HS1_1272_GATE")
	)
	(via
		(at 274.426172 -94.8944)
		(size 0.508)
		(drill 0.254)
		(layers "F.Cu" "B.Cu")
		(net "P52V_HS1_1272_GATE")
	)
	(via
		(at 272.876264 -103.35895)
		(size 0.508)
		(drill 0.254)
		(layers "F.Cu" "B.Cu")
		(net "P52V_HS1_1272_GATE")
	)
	(segment
		(start 274.426172 -92.314522)
		(end 274.426172 -94.8944)
		(width 0.508)
		(layer "B.Cu")
		(net "P52V_HS1_1272_GATE")
	)
	(segment
		(start 273.5072 -103.35895)
		(end 272.876264 -103.35895)
		(width 0.17272)
		(layer "B.Cu")
		(net "P52V_HS1_1272_GATE")
	)
	(segment
		(start 290.296092 -46.473872)
		(end 290.296092 -45.790866)
		(width 0.254)
		(layer "F.Cu")
		(net "P52V_HS_1272_S_N")
	)
	(segment
		(start 298.2976 -119.6975)
		(end 299.06214 -119.6975)
		(width 0.4572)
		(layer "F.Cu")
		(net "P52V_HS_1272_S_N")
	)
	(segment
		(start 299.189394 -83.5025)
		(end 299.570394 -83.1215)
		(width 0.4572)
		(layer "F.Cu")
		(net "P52V_HS_1272_S_N")
	)
	(segment
		(start 290.44646 -46.62424)
		(end 290.296092 -46.473872)
		(width 0.254)
		(layer "F.Cu")
		(net "P52V_HS_1272_S_N")
	)
	(segment
		(start 299.06214 -119.6975)
		(end 299.57014 -120.2055)
		(width 0.4572)
		(layer "F.Cu")
		(net "P52V_HS_1272_S_N")
	)
	(segment
		(start 298.274994 -83.5025)
		(end 299.189394 -83.5025)
		(width 0.4572)
		(layer "F.Cu")
		(net "P52V_HS_1272_S_N")
	)
	(segment
		(start 299.57014 -120.2055)
		(end 299.593 -120.2055)
		(width 0.4572)
		(layer "F.Cu")
		(net "P52V_HS_1272_S_N")
	)
	(via
		(at 299.593 -120.2055)
		(size 0.508)
		(drill 0.254)
		(layers "F.Cu" "B.Cu")
		(net "P52V_HS_1272_S_N")
	)
	(via
		(at 290.44646 -46.62424)
		(size 0.508)
		(drill 0.254)
		(layers "F.Cu" "B.Cu")
		(net "P52V_HS_1272_S_N")
	)
	(via
		(at 299.570394 -83.1215)
		(size 0.508)
		(drill 0.254)
		(layers "F.Cu" "B.Cu")
		(net "P52V_HS_1272_S_N")
	)
	(segment
		(start 290.30676 -46.76394)
		(end 290.44646 -46.62424)
		(width 0.381)
		(layer "In2.Cu")
		(net "P52V_HS_1272_S_N")
	)
	(segment
		(start 299.570394 -83.1215)
		(end 299.336206 -83.1215)
		(width 0.381)
		(layer "In2.Cu")
		(net "P52V_HS_1272_S_N")
	)
	(segment
		(start 300.420024 -119.90197)
		(end 302.72482 -117.597174)
		(width 0.381)
		(layer "In2.Cu")
		(net "P52V_HS_1272_S_N")
	)
	(segment
		(start 298.955206 -58.739786)
		(end 290.30676 -50.09134)
		(width 0.381)
		(layer "In2.Cu")
		(net "P52V_HS_1272_S_N")
	)
	(segment
		(start 299.336206 -83.1215)
		(end 298.955206 -82.7405)
		(width 0.381)
		(layer "In2.Cu")
		(net "P52V_HS_1272_S_N")
	)
	(segment
		(start 299.94479 -119.90197)
		(end 300.420024 -119.90197)
		(width 0.381)
		(layer "In2.Cu")
		(net "P52V_HS_1272_S_N")
	)
	(segment
		(start 298.955206 -82.7405)
		(end 298.955206 -58.739786)
		(width 0.381)
		(layer "In2.Cu")
		(net "P52V_HS_1272_S_N")
	)
	(segment
		(start 301.124366 -83.30692)
		(end 299.755814 -83.30692)
		(width 0.381)
		(layer "In2.Cu")
		(net "P52V_HS_1272_S_N")
	)
	(segment
		(start 302.72482 -117.597174)
		(end 302.72482 -85.221064)
		(width 0.381)
		(layer "In2.Cu")
		(net "P52V_HS_1272_S_N")
	)
	(segment
		(start 301.812198 -83.994752)
		(end 301.124366 -83.30692)
		(width 0.381)
		(layer "In2.Cu")
		(net "P52V_HS_1272_S_N")
	)
	(segment
		(start 290.30676 -50.09134)
		(end 290.30676 -46.76394)
		(width 0.381)
		(layer "In2.Cu")
		(net "P52V_HS_1272_S_N")
	)
	(segment
		(start 299.64126 -120.2055)
		(end 299.94479 -119.90197)
		(width 0.381)
		(layer "In2.Cu")
		(net "P52V_HS_1272_S_N")
	)
	(segment
		(start 299.593 -120.2055)
		(end 299.64126 -120.2055)
		(width 0.381)
		(layer "In2.Cu")
		(net "P52V_HS_1272_S_N")
	)
	(segment
		(start 301.812198 -84.308442)
		(end 301.812198 -83.994752)
		(width 0.381)
		(layer "In2.Cu")
		(net "P52V_HS_1272_S_N")
	)
	(segment
		(start 302.72482 -85.221064)
		(end 301.812198 -84.308442)
		(width 0.381)
		(layer "In2.Cu")
		(net "P52V_HS_1272_S_N")
	)
	(segment
		(start 299.755814 -83.30692)
		(end 299.570394 -83.1215)
		(width 0.381)
		(layer "In2.Cu")
		(net "P52V_HS_1272_S_N")
	)
	(segment
		(start 289.645344 -46.62424)
		(end 289.795712 -46.473872)
		(width 0.254)
		(layer "F.Cu")
		(net "P52V_HS_1272_S_P")
	)
	(segment
		(start 299.974 -119.6975)
		(end 300.8884 -119.6975)
		(width 0.4572)
		(layer "F.Cu")
		(net "P52V_HS_1272_S_P")
	)
	(segment
		(start 300.865794 -83.5025)
		(end 300.098714 -83.5025)
		(width 0.4572)
		(layer "F.Cu")
		(net "P52V_HS_1272_S_P")
	)
	(segment
		(start 299.590714 -84.0105)
		(end 299.570394 -84.0105)
		(width 0.4572)
		(layer "F.Cu")
		(net "P52V_HS_1272_S_P")
	)
	(segment
		(start 289.795712 -46.473872)
		(end 289.795712 -45.790866)
		(width 0.254)
		(layer "F.Cu")
		(net "P52V_HS_1272_S_P")
	)
	(segment
		(start 300.098714 -83.5025)
		(end 299.590714 -84.0105)
		(width 0.4572)
		(layer "F.Cu")
		(net "P52V_HS_1272_S_P")
	)
	(segment
		(start 299.593 -119.3165)
		(end 299.974 -119.6975)
		(width 0.4572)
		(layer "F.Cu")
		(net "P52V_HS_1272_S_P")
	)
	(via
		(at 299.593 -119.3165)
		(size 0.508)
		(drill 0.254)
		(layers "F.Cu" "B.Cu")
		(net "P52V_HS_1272_S_P")
	)
	(via
		(at 299.570394 -84.0105)
		(size 0.508)
		(drill 0.254)
		(layers "F.Cu" "B.Cu")
		(net "P52V_HS_1272_S_P")
	)
	(via
		(at 289.645344 -46.62424)
		(size 0.508)
		(drill 0.254)
		(layers "F.Cu" "B.Cu")
		(net "P52V_HS_1272_S_P")
	)
	(segment
		(start 299.593 -119.3165)
		(end 299.67047 -119.39397)
		(width 0.381)
		(layer "In2.Cu")
		(net "P52V_HS_1272_S_P")
	)
	(segment
		(start 299.270674 -83.82)
		(end 298.447206 -82.996532)
		(width 0.381)
		(layer "In2.Cu")
		(net "P52V_HS_1272_S_P")
	)
	(segment
		(start 299.765974 -83.81492)
		(end 299.570394 -84.0105)
		(width 0.381)
		(layer "In2.Cu")
		(net "P52V_HS_1272_S_P")
	)
	(segment
		(start 300.9138 -83.81492)
		(end 299.765974 -83.81492)
		(width 0.381)
		(layer "In2.Cu")
		(net "P52V_HS_1272_S_P")
	)
	(segment
		(start 302.21682 -117.386608)
		(end 302.21682 -85.43163)
		(width 0.381)
		(layer "In2.Cu")
		(net "P52V_HS_1272_S_P")
	)
	(segment
		(start 299.570394 -84.0105)
		(end 299.379894 -83.82)
		(width 0.381)
		(layer "In2.Cu")
		(net "P52V_HS_1272_S_P")
	)
	(segment
		(start 298.447206 -58.950352)
		(end 289.79876 -50.301906)
		(width 0.381)
		(layer "In2.Cu")
		(net "P52V_HS_1272_S_P")
	)
	(segment
		(start 298.447206 -82.996532)
		(end 298.447206 -58.950352)
		(width 0.381)
		(layer "In2.Cu")
		(net "P52V_HS_1272_S_P")
	)
	(segment
		(start 301.304198 -84.519008)
		(end 301.304198 -84.205318)
		(width 0.381)
		(layer "In2.Cu")
		(net "P52V_HS_1272_S_P")
	)
	(segment
		(start 299.379894 -83.82)
		(end 299.270674 -83.82)
		(width 0.381)
		(layer "In2.Cu")
		(net "P52V_HS_1272_S_P")
	)
	(segment
		(start 289.79876 -46.777656)
		(end 289.645344 -46.62424)
		(width 0.381)
		(layer "In2.Cu")
		(net "P52V_HS_1272_S_P")
	)
	(segment
		(start 301.304198 -84.205318)
		(end 300.9138 -83.81492)
		(width 0.381)
		(layer "In2.Cu")
		(net "P52V_HS_1272_S_P")
	)
	(segment
		(start 299.67047 -119.39397)
		(end 300.209458 -119.39397)
		(width 0.381)
		(layer "In2.Cu")
		(net "P52V_HS_1272_S_P")
	)
	(segment
		(start 300.209458 -119.39397)
		(end 302.21682 -117.386608)
		(width 0.381)
		(layer "In2.Cu")
		(net "P52V_HS_1272_S_P")
	)
	(segment
		(start 289.79876 -50.301906)
		(end 289.79876 -46.777656)
		(width 0.381)
		(layer "In2.Cu")
		(net "P52V_HS_1272_S_P")
	)
	(segment
		(start 302.21682 -85.43163)
		(end 301.304198 -84.519008)
		(width 0.381)
		(layer "In2.Cu")
		(net "P52V_HS_1272_S_P")
	)
	(via
		(at 288.341562 -66.25844)
		(size 0.508)
		(drill 0.254)
		(layers "F.Cu" "B.Cu")
		(net "P52V_HS1_DRAIN_2")
	)
	(via
		(at 281.917648 -84.246974)
		(size 0.508)
		(drill 0.254)
		(layers "F.Cu" "B.Cu")
		(net "P52V_HS1_DRAIN_2")
	)
	(via
		(at 288.392362 -91.180666)
		(size 0.508)
		(drill 0.254)
		(layers "F.Cu" "B.Cu")
		(net "P52V_HS1_DRAIN_2")
	)
	(via
		(at 289.154362 -88.894666)
		(size 0.508)
		(drill 0.254)
		(layers "F.Cu" "B.Cu")
		(net "P52V_HS1_DRAIN_2")
	)
	(via
		(at 294.56634 -81.543398)
		(size 0.508)
		(drill 0.254)
		(layers "F.Cu" "B.Cu")
		(net "P52V_HS1_DRAIN_2")
	)
	(via
		(at 293.80434 -80.019398)
		(size 0.508)
		(drill 0.254)
		(layers "F.Cu" "B.Cu")
		(net "P52V_HS1_DRAIN_2")
	)
	(via
		(at 289.154362 -77.56144)
		(size 0.508)
		(drill 0.254)
		(layers "F.Cu" "B.Cu")
		(net "P52V_HS1_DRAIN_2")
	)
	(via
		(at 288.341562 -65.49644)
		(size 0.508)
		(drill 0.254)
		(layers "F.Cu" "B.Cu")
		(net "P52V_HS1_DRAIN_2")
	)
	(via
		(at 289.154362 -79.84744)
		(size 0.508)
		(drill 0.254)
		(layers "F.Cu" "B.Cu")
		(net "P52V_HS1_DRAIN_2")
	)
	(via
		(at 295.32834 -78.495398)
		(size 0.508)
		(drill 0.254)
		(layers "F.Cu" "B.Cu")
		(net "P52V_HS1_DRAIN_2")
	)
	(via
		(at 289.154362 -76.79944)
		(size 0.508)
		(drill 0.254)
		(layers "F.Cu" "B.Cu")
		(net "P52V_HS1_DRAIN_2")
	)
	(via
		(at 293.80434 -79.257398)
		(size 0.508)
		(drill 0.254)
		(layers "F.Cu" "B.Cu")
		(net "P52V_HS1_DRAIN_2")
	)
	(via
		(at 289.103562 -65.49644)
		(size 0.508)
		(drill 0.254)
		(layers "F.Cu" "B.Cu")
		(net "P52V_HS1_DRAIN_2")
	)
	(via
		(at 288.392362 -91.942666)
		(size 0.508)
		(drill 0.254)
		(layers "F.Cu" "B.Cu")
		(net "P52V_HS1_DRAIN_2")
	)
	(via
		(at 280.588466 -84.273898)
		(size 0.508)
		(drill 0.254)
		(layers "F.Cu" "B.Cu")
		(net "P52V_HS1_DRAIN_2")
	)
	(via
		(at 294.56634 -76.209398)
		(size 0.508)
		(drill 0.254)
		(layers "F.Cu" "B.Cu")
		(net "P52V_HS1_DRAIN_2")
	)
	(via
		(at 294.56634 -79.257398)
		(size 0.508)
		(drill 0.254)
		(layers "F.Cu" "B.Cu")
		(net "P52V_HS1_DRAIN_2")
	)
	(via
		(at 295.32834 -81.543398)
		(size 0.508)
		(drill 0.254)
		(layers "F.Cu" "B.Cu")
		(net "P52V_HS1_DRAIN_2")
	)
	(via
		(at 294.56634 -80.781398)
		(size 0.508)
		(drill 0.254)
		(layers "F.Cu" "B.Cu")
		(net "P52V_HS1_DRAIN_2")
	)
	(via
		(at 279.856184 -84.301076)
		(size 0.508)
		(drill 0.254)
		(layers "F.Cu" "B.Cu")
		(net "P52V_HS1_DRAIN_2")
	)
	(via
		(at 295.32834 -80.019398)
		(size 0.508)
		(drill 0.254)
		(layers "F.Cu" "B.Cu")
		(net "P52V_HS1_DRAIN_2")
	)
	(via
		(at 295.32834 -77.733398)
		(size 0.508)
		(drill 0.254)
		(layers "F.Cu" "B.Cu")
		(net "P52V_HS1_DRAIN_2")
	)
	(via
		(at 293.80434 -80.781398)
		(size 0.508)
		(drill 0.254)
		(layers "F.Cu" "B.Cu")
		(net "P52V_HS1_DRAIN_2")
	)
	(via
		(at 288.392362 -88.894666)
		(size 0.508)
		(drill 0.254)
		(layers "F.Cu" "B.Cu")
		(net "P52V_HS1_DRAIN_2")
	)
	(via
		(at 289.154362 -79.08544)
		(size 0.508)
		(drill 0.254)
		(layers "F.Cu" "B.Cu")
		(net "P52V_HS1_DRAIN_2")
	)
	(via
		(at 281.944826 -72.340724)
		(size 0.508)
		(drill 0.254)
		(layers "F.Cu" "B.Cu")
		(net "P52V_HS1_DRAIN_2")
	)
	(via
		(at 288.341562 -67.78244)
		(size 0.508)
		(drill 0.254)
		(layers "F.Cu" "B.Cu")
		(net "P52V_HS1_DRAIN_2")
	)
	(via
		(at 289.103562 -67.78244)
		(size 0.508)
		(drill 0.254)
		(layers "F.Cu" "B.Cu")
		(net "P52V_HS1_DRAIN_2")
	)
	(via
		(at 294.56634 -74.685398)
		(size 0.508)
		(drill 0.254)
		(layers "F.Cu" "B.Cu")
		(net "P52V_HS1_DRAIN_2")
	)
	(via
		(at 288.341562 -64.73444)
		(size 0.508)
		(drill 0.254)
		(layers "F.Cu" "B.Cu")
		(net "P52V_HS1_DRAIN_2")
	)
	(via
		(at 289.154362 -90.418666)
		(size 0.508)
		(drill 0.254)
		(layers "F.Cu" "B.Cu")
		(net "P52V_HS1_DRAIN_2")
	)
	(via
		(at 295.32834 -76.971398)
		(size 0.508)
		(drill 0.254)
		(layers "F.Cu" "B.Cu")
		(net "P52V_HS1_DRAIN_2")
	)
	(via
		(at 294.56634 -75.447398)
		(size 0.508)
		(drill 0.254)
		(layers "F.Cu" "B.Cu")
		(net "P52V_HS1_DRAIN_2")
	)
	(via
		(at 294.56634 -80.019398)
		(size 0.508)
		(drill 0.254)
		(layers "F.Cu" "B.Cu")
		(net "P52V_HS1_DRAIN_2")
	)
	(via
		(at 288.392362 -79.84744)
		(size 0.508)
		(drill 0.254)
		(layers "F.Cu" "B.Cu")
		(net "P52V_HS1_DRAIN_2")
	)
	(via
		(at 289.154362 -78.32344)
		(size 0.508)
		(drill 0.254)
		(layers "F.Cu" "B.Cu")
		(net "P52V_HS1_DRAIN_2")
	)
	(via
		(at 288.392362 -78.32344)
		(size 0.508)
		(drill 0.254)
		(layers "F.Cu" "B.Cu")
		(net "P52V_HS1_DRAIN_2")
	)
	(via
		(at 293.80434 -81.543398)
		(size 0.508)
		(drill 0.254)
		(layers "F.Cu" "B.Cu")
		(net "P52V_HS1_DRAIN_2")
	)
	(via
		(at 284.141418 -84.219796)
		(size 0.508)
		(drill 0.254)
		(layers "F.Cu" "B.Cu")
		(net "P52V_HS1_DRAIN_2")
	)
	(via
		(at 282.64993 -84.219796)
		(size 0.508)
		(drill 0.254)
		(layers "F.Cu" "B.Cu")
		(net "P52V_HS1_DRAIN_2")
	)
	(via
		(at 295.32834 -75.447398)
		(size 0.508)
		(drill 0.254)
		(layers "F.Cu" "B.Cu")
		(net "P52V_HS1_DRAIN_2")
	)
	(via
		(at 295.32834 -76.209398)
		(size 0.508)
		(drill 0.254)
		(layers "F.Cu" "B.Cu")
		(net "P52V_HS1_DRAIN_2")
	)
	(via
		(at 294.56634 -77.733398)
		(size 0.508)
		(drill 0.254)
		(layers "F.Cu" "B.Cu")
		(net "P52V_HS1_DRAIN_2")
	)
	(via
		(at 284.8737 -84.192618)
		(size 0.508)
		(drill 0.254)
		(layers "F.Cu" "B.Cu")
		(net "P52V_HS1_DRAIN_2")
	)
	(via
		(at 288.341562 -67.02044)
		(size 0.508)
		(drill 0.254)
		(layers "F.Cu" "B.Cu")
		(net "P52V_HS1_DRAIN_2")
	)
	(via
		(at 284.168596 -72.313546)
		(size 0.508)
		(drill 0.254)
		(layers "F.Cu" "B.Cu")
		(net "P52V_HS1_DRAIN_2")
	)
	(via
		(at 288.392362 -77.56144)
		(size 0.508)
		(drill 0.254)
		(layers "F.Cu" "B.Cu")
		(net "P52V_HS1_DRAIN_2")
	)
	(via
		(at 293.80434 -77.733398)
		(size 0.508)
		(drill 0.254)
		(layers "F.Cu" "B.Cu")
		(net "P52V_HS1_DRAIN_2")
	)
	(via
		(at 288.392362 -79.08544)
		(size 0.508)
		(drill 0.254)
		(layers "F.Cu" "B.Cu")
		(net "P52V_HS1_DRAIN_2")
	)
	(via
		(at 288.392362 -90.418666)
		(size 0.508)
		(drill 0.254)
		(layers "F.Cu" "B.Cu")
		(net "P52V_HS1_DRAIN_2")
	)
	(via
		(at 288.392362 -89.656666)
		(size 0.508)
		(drill 0.254)
		(layers "F.Cu" "B.Cu")
		(net "P52V_HS1_DRAIN_2")
	)
	(via
		(at 293.80434 -74.685398)
		(size 0.508)
		(drill 0.254)
		(layers "F.Cu" "B.Cu")
		(net "P52V_HS1_DRAIN_2")
	)
	(via
		(at 289.154362 -91.180666)
		(size 0.508)
		(drill 0.254)
		(layers "F.Cu" "B.Cu")
		(net "P52V_HS1_DRAIN_2")
	)
	(via
		(at 294.56634 -78.495398)
		(size 0.508)
		(drill 0.254)
		(layers "F.Cu" "B.Cu")
		(net "P52V_HS1_DRAIN_2")
	)
	(via
		(at 294.56634 -76.971398)
		(size 0.508)
		(drill 0.254)
		(layers "F.Cu" "B.Cu")
		(net "P52V_HS1_DRAIN_2")
	)
	(via
		(at 293.80434 -75.447398)
		(size 0.508)
		(drill 0.254)
		(layers "F.Cu" "B.Cu")
		(net "P52V_HS1_DRAIN_2")
	)
	(via
		(at 293.80434 -78.495398)
		(size 0.508)
		(drill 0.254)
		(layers "F.Cu" "B.Cu")
		(net "P52V_HS1_DRAIN_2")
	)
	(via
		(at 289.103562 -67.02044)
		(size 0.508)
		(drill 0.254)
		(layers "F.Cu" "B.Cu")
		(net "P52V_HS1_DRAIN_2")
	)
	(via
		(at 279.883362 -72.394826)
		(size 0.508)
		(drill 0.254)
		(layers "F.Cu" "B.Cu")
		(net "P52V_HS1_DRAIN_2")
	)
	(via
		(at 282.677108 -72.313546)
		(size 0.508)
		(drill 0.254)
		(layers "F.Cu" "B.Cu")
		(net "P52V_HS1_DRAIN_2")
	)
	(via
		(at 295.32834 -74.685398)
		(size 0.508)
		(drill 0.254)
		(layers "F.Cu" "B.Cu")
		(net "P52V_HS1_DRAIN_2")
	)
	(via
		(at 280.615644 -72.367648)
		(size 0.508)
		(drill 0.254)
		(layers "F.Cu" "B.Cu")
		(net "P52V_HS1_DRAIN_2")
	)
	(via
		(at 289.154362 -89.656666)
		(size 0.508)
		(drill 0.254)
		(layers "F.Cu" "B.Cu")
		(net "P52V_HS1_DRAIN_2")
	)
	(via
		(at 289.103562 -66.25844)
		(size 0.508)
		(drill 0.254)
		(layers "F.Cu" "B.Cu")
		(net "P52V_HS1_DRAIN_2")
	)
	(via
		(at 289.154362 -91.942666)
		(size 0.508)
		(drill 0.254)
		(layers "F.Cu" "B.Cu")
		(net "P52V_HS1_DRAIN_2")
	)
	(via
		(at 284.900878 -72.286368)
		(size 0.508)
		(drill 0.254)
		(layers "F.Cu" "B.Cu")
		(net "P52V_HS1_DRAIN_2")
	)
	(via
		(at 293.80434 -76.971398)
		(size 0.508)
		(drill 0.254)
		(layers "F.Cu" "B.Cu")
		(net "P52V_HS1_DRAIN_2")
	)
	(via
		(at 295.32834 -79.257398)
		(size 0.508)
		(drill 0.254)
		(layers "F.Cu" "B.Cu")
		(net "P52V_HS1_DRAIN_2")
	)
	(via
		(at 289.103562 -64.73444)
		(size 0.508)
		(drill 0.254)
		(layers "F.Cu" "B.Cu")
		(net "P52V_HS1_DRAIN_2")
	)
	(via
		(at 288.392362 -76.79944)
		(size 0.508)
		(drill 0.254)
		(layers "F.Cu" "B.Cu")
		(net "P52V_HS1_DRAIN_2")
	)
	(via
		(at 295.32834 -80.781398)
		(size 0.508)
		(drill 0.254)
		(layers "F.Cu" "B.Cu")
		(net "P52V_HS1_DRAIN_2")
	)
	(via
		(at 293.80434 -76.209398)
		(size 0.508)
		(drill 0.254)
		(layers "F.Cu" "B.Cu")
		(net "P52V_HS1_DRAIN_2")
	)
	(via
		(at 289.10026 -103.87711)
		(size 0.508)
		(drill 0.254)
		(layers "F.Cu" "B.Cu")
		(net "P52V_HS1_DRAIN_1")
	)
	(via
		(at 294.588946 -111.642398)
		(size 0.508)
		(drill 0.254)
		(layers "F.Cu" "B.Cu")
		(net "P52V_HS1_DRAIN_1")
	)
	(via
		(at 295.350946 -110.880398)
		(size 0.508)
		(drill 0.254)
		(layers "F.Cu" "B.Cu")
		(net "P52V_HS1_DRAIN_1")
	)
	(via
		(at 288.392616 -116.135912)
		(size 0.508)
		(drill 0.254)
		(layers "F.Cu" "B.Cu")
		(net "P52V_HS1_DRAIN_1")
	)
	(via
		(at 294.588946 -113.928398)
		(size 0.508)
		(drill 0.254)
		(layers "F.Cu" "B.Cu")
		(net "P52V_HS1_DRAIN_1")
	)
	(via
		(at 280.3652 -120.482106)
		(size 0.508)
		(drill 0.254)
		(layers "F.Cu" "B.Cu")
		(net "P52V_HS1_DRAIN_1")
	)
	(via
		(at 295.350946 -112.404398)
		(size 0.508)
		(drill 0.254)
		(layers "F.Cu" "B.Cu")
		(net "P52V_HS1_DRAIN_1")
	)
	(via
		(at 294.588946 -115.452398)
		(size 0.508)
		(drill 0.254)
		(layers "F.Cu" "B.Cu")
		(net "P52V_HS1_DRAIN_1")
	)
	(via
		(at 289.10026 -103.11511)
		(size 0.508)
		(drill 0.254)
		(layers "F.Cu" "B.Cu")
		(net "P52V_HS1_DRAIN_1")
	)
	(via
		(at 289.209988 -121.089928)
		(size 0.508)
		(drill 0.254)
		(layers "F.Cu" "B.Cu")
		(net "P52V_HS1_DRAIN_1")
	)
	(via
		(at 295.350946 -113.166398)
		(size 0.508)
		(drill 0.254)
		(layers "F.Cu" "B.Cu")
		(net "P52V_HS1_DRAIN_1")
	)
	(via
		(at 281.150568 -108.493052)
		(size 0.508)
		(drill 0.254)
		(layers "F.Cu" "B.Cu")
		(net "P52V_HS1_DRAIN_1")
	)
	(via
		(at 284.650434 -120.400826)
		(size 0.508)
		(drill 0.254)
		(layers "F.Cu" "B.Cu")
		(net "P52V_HS1_DRAIN_1")
	)
	(via
		(at 295.350946 -114.690398)
		(size 0.508)
		(drill 0.254)
		(layers "F.Cu" "B.Cu")
		(net "P52V_HS1_DRAIN_1")
	)
	(via
		(at 289.10026 -100.82911)
		(size 0.508)
		(drill 0.254)
		(layers "F.Cu" "B.Cu")
		(net "P52V_HS1_DRAIN_1")
	)
	(via
		(at 288.33826 -102.35311)
		(size 0.508)
		(drill 0.254)
		(layers "F.Cu" "B.Cu")
		(net "P52V_HS1_DRAIN_1")
	)
	(via
		(at 289.209988 -118.803928)
		(size 0.508)
		(drill 0.254)
		(layers "F.Cu" "B.Cu")
		(net "P52V_HS1_DRAIN_1")
	)
	(via
		(at 288.447988 -121.851928)
		(size 0.508)
		(drill 0.254)
		(layers "F.Cu" "B.Cu")
		(net "P52V_HS1_DRAIN_1")
	)
	(via
		(at 293.826946 -113.166398)
		(size 0.508)
		(drill 0.254)
		(layers "F.Cu" "B.Cu")
		(net "P52V_HS1_DRAIN_1")
	)
	(via
		(at 288.447988 -121.089928)
		(size 0.508)
		(drill 0.254)
		(layers "F.Cu" "B.Cu")
		(net "P52V_HS1_DRAIN_1")
	)
	(via
		(at 288.33826 -103.11511)
		(size 0.508)
		(drill 0.254)
		(layers "F.Cu" "B.Cu")
		(net "P52V_HS1_DRAIN_1")
	)
	(via
		(at 293.826946 -113.928398)
		(size 0.508)
		(drill 0.254)
		(layers "F.Cu" "B.Cu")
		(net "P52V_HS1_DRAIN_1")
	)
	(via
		(at 295.350946 -116.214398)
		(size 0.508)
		(drill 0.254)
		(layers "F.Cu" "B.Cu")
		(net "P52V_HS1_DRAIN_1")
	)
	(via
		(at 294.588946 -116.214398)
		(size 0.508)
		(drill 0.254)
		(layers "F.Cu" "B.Cu")
		(net "P52V_HS1_DRAIN_1")
	)
	(via
		(at 293.826946 -116.214398)
		(size 0.508)
		(drill 0.254)
		(layers "F.Cu" "B.Cu")
		(net "P52V_HS1_DRAIN_1")
	)
	(via
		(at 289.209988 -121.851928)
		(size 0.508)
		(drill 0.254)
		(layers "F.Cu" "B.Cu")
		(net "P52V_HS1_DRAIN_1")
	)
	(via
		(at 289.209988 -119.565928)
		(size 0.508)
		(drill 0.254)
		(layers "F.Cu" "B.Cu")
		(net "P52V_HS1_DRAIN_1")
	)
	(via
		(at 285.382716 -120.373648)
		(size 0.508)
		(drill 0.254)
		(layers "F.Cu" "B.Cu")
		(net "P52V_HS1_DRAIN_1")
	)
	(via
		(at 288.33826 -100.82911)
		(size 0.508)
		(drill 0.254)
		(layers "F.Cu" "B.Cu")
		(net "P52V_HS1_DRAIN_1")
	)
	(via
		(at 293.826946 -115.452398)
		(size 0.508)
		(drill 0.254)
		(layers "F.Cu" "B.Cu")
		(net "P52V_HS1_DRAIN_1")
	)
	(via
		(at 288.392616 -114.611912)
		(size 0.508)
		(drill 0.254)
		(layers "F.Cu" "B.Cu")
		(net "P52V_HS1_DRAIN_1")
	)
	(via
		(at 282.426664 -120.428004)
		(size 0.508)
		(drill 0.254)
		(layers "F.Cu" "B.Cu")
		(net "P52V_HS1_DRAIN_1")
	)
	(via
		(at 294.588946 -113.166398)
		(size 0.508)
		(drill 0.254)
		(layers "F.Cu" "B.Cu")
		(net "P52V_HS1_DRAIN_1")
	)
	(via
		(at 293.826946 -116.976398)
		(size 0.508)
		(drill 0.254)
		(layers "F.Cu" "B.Cu")
		(net "P52V_HS1_DRAIN_1")
	)
	(via
		(at 289.154616 -116.135912)
		(size 0.508)
		(drill 0.254)
		(layers "F.Cu" "B.Cu")
		(net "P52V_HS1_DRAIN_1")
	)
	(via
		(at 295.350946 -117.738398)
		(size 0.508)
		(drill 0.254)
		(layers "F.Cu" "B.Cu")
		(net "P52V_HS1_DRAIN_1")
	)
	(via
		(at 283.158946 -120.400826)
		(size 0.508)
		(drill 0.254)
		(layers "F.Cu" "B.Cu")
		(net "P52V_HS1_DRAIN_1")
	)
	(via
		(at 293.826946 -114.690398)
		(size 0.508)
		(drill 0.254)
		(layers "F.Cu" "B.Cu")
		(net "P52V_HS1_DRAIN_1")
	)
	(via
		(at 289.209988 -123.375928)
		(size 0.508)
		(drill 0.254)
		(layers "F.Cu" "B.Cu")
		(net "P52V_HS1_DRAIN_1")
	)
	(via
		(at 288.33826 -101.59111)
		(size 0.508)
		(drill 0.254)
		(layers "F.Cu" "B.Cu")
		(net "P52V_HS1_DRAIN_1")
	)
	(via
		(at 288.447988 -122.613928)
		(size 0.508)
		(drill 0.254)
		(layers "F.Cu" "B.Cu")
		(net "P52V_HS1_DRAIN_1")
	)
	(via
		(at 295.350946 -115.452398)
		(size 0.508)
		(drill 0.254)
		(layers "F.Cu" "B.Cu")
		(net "P52V_HS1_DRAIN_1")
	)
	(via
		(at 289.209988 -122.613928)
		(size 0.508)
		(drill 0.254)
		(layers "F.Cu" "B.Cu")
		(net "P52V_HS1_DRAIN_1")
	)
	(via
		(at 295.350946 -113.928398)
		(size 0.508)
		(drill 0.254)
		(layers "F.Cu" "B.Cu")
		(net "P52V_HS1_DRAIN_1")
	)
	(via
		(at 285.435802 -108.411772)
		(size 0.508)
		(drill 0.254)
		(layers "F.Cu" "B.Cu")
		(net "P52V_HS1_DRAIN_1")
	)
	(via
		(at 280.418286 -108.52023)
		(size 0.508)
		(drill 0.254)
		(layers "F.Cu" "B.Cu")
		(net "P52V_HS1_DRAIN_1")
	)
	(via
		(at 283.212032 -108.43895)
		(size 0.508)
		(drill 0.254)
		(layers "F.Cu" "B.Cu")
		(net "P52V_HS1_DRAIN_1")
	)
	(via
		(at 289.10026 -101.59111)
		(size 0.508)
		(drill 0.254)
		(layers "F.Cu" "B.Cu")
		(net "P52V_HS1_DRAIN_1")
	)
	(via
		(at 288.447988 -119.565928)
		(size 0.508)
		(drill 0.254)
		(layers "F.Cu" "B.Cu")
		(net "P52V_HS1_DRAIN_1")
	)
	(via
		(at 288.392616 -115.373912)
		(size 0.508)
		(drill 0.254)
		(layers "F.Cu" "B.Cu")
		(net "P52V_HS1_DRAIN_1")
	)
	(via
		(at 294.588946 -110.880398)
		(size 0.508)
		(drill 0.254)
		(layers "F.Cu" "B.Cu")
		(net "P52V_HS1_DRAIN_1")
	)
	(via
		(at 281.097482 -120.454928)
		(size 0.508)
		(drill 0.254)
		(layers "F.Cu" "B.Cu")
		(net "P52V_HS1_DRAIN_1")
	)
	(via
		(at 294.588946 -114.690398)
		(size 0.508)
		(drill 0.254)
		(layers "F.Cu" "B.Cu")
		(net "P52V_HS1_DRAIN_1")
	)
	(via
		(at 293.826946 -111.642398)
		(size 0.508)
		(drill 0.254)
		(layers "F.Cu" "B.Cu")
		(net "P52V_HS1_DRAIN_1")
	)
	(via
		(at 294.588946 -116.976398)
		(size 0.508)
		(drill 0.254)
		(layers "F.Cu" "B.Cu")
		(net "P52V_HS1_DRAIN_1")
	)
	(via
		(at 289.154616 -113.087912)
		(size 0.508)
		(drill 0.254)
		(layers "F.Cu" "B.Cu")
		(net "P52V_HS1_DRAIN_1")
	)
	(via
		(at 294.588946 -112.404398)
		(size 0.508)
		(drill 0.254)
		(layers "F.Cu" "B.Cu")
		(net "P52V_HS1_DRAIN_1")
	)
	(via
		(at 284.70352 -108.43895)
		(size 0.508)
		(drill 0.254)
		(layers "F.Cu" "B.Cu")
		(net "P52V_HS1_DRAIN_1")
	)
	(via
		(at 293.826946 -117.738398)
		(size 0.508)
		(drill 0.254)
		(layers "F.Cu" "B.Cu")
		(net "P52V_HS1_DRAIN_1")
	)
	(via
		(at 295.350946 -111.642398)
		(size 0.508)
		(drill 0.254)
		(layers "F.Cu" "B.Cu")
		(net "P52V_HS1_DRAIN_1")
	)
	(via
		(at 288.392616 -113.087912)
		(size 0.508)
		(drill 0.254)
		(layers "F.Cu" "B.Cu")
		(net "P52V_HS1_DRAIN_1")
	)
	(via
		(at 288.447988 -118.803928)
		(size 0.508)
		(drill 0.254)
		(layers "F.Cu" "B.Cu")
		(net "P52V_HS1_DRAIN_1")
	)
	(via
		(at 288.447988 -120.327928)
		(size 0.508)
		(drill 0.254)
		(layers "F.Cu" "B.Cu")
		(net "P52V_HS1_DRAIN_1")
	)
	(via
		(at 295.350946 -116.976398)
		(size 0.508)
		(drill 0.254)
		(layers "F.Cu" "B.Cu")
		(net "P52V_HS1_DRAIN_1")
	)
	(via
		(at 289.154616 -113.849912)
		(size 0.508)
		(drill 0.254)
		(layers "F.Cu" "B.Cu")
		(net "P52V_HS1_DRAIN_1")
	)
	(via
		(at 294.588946 -117.738398)
		(size 0.508)
		(drill 0.254)
		(layers "F.Cu" "B.Cu")
		(net "P52V_HS1_DRAIN_1")
	)
	(via
		(at 288.392616 -113.849912)
		(size 0.508)
		(drill 0.254)
		(layers "F.Cu" "B.Cu")
		(net "P52V_HS1_DRAIN_1")
	)
	(via
		(at 289.154616 -114.611912)
		(size 0.508)
		(drill 0.254)
		(layers "F.Cu" "B.Cu")
		(net "P52V_HS1_DRAIN_1")
	)
	(via
		(at 289.154616 -115.373912)
		(size 0.508)
		(drill 0.254)
		(layers "F.Cu" "B.Cu")
		(net "P52V_HS1_DRAIN_1")
	)
	(via
		(at 282.47975 -108.466128)
		(size 0.508)
		(drill 0.254)
		(layers "F.Cu" "B.Cu")
		(net "P52V_HS1_DRAIN_1")
	)
	(via
		(at 293.826946 -110.880398)
		(size 0.508)
		(drill 0.254)
		(layers "F.Cu" "B.Cu")
		(net "P52V_HS1_DRAIN_1")
	)
	(via
		(at 293.826946 -112.404398)
		(size 0.508)
		(drill 0.254)
		(layers "F.Cu" "B.Cu")
		(net "P52V_HS1_DRAIN_1")
	)
	(via
		(at 288.447988 -123.375928)
		(size 0.508)
		(drill 0.254)
		(layers "F.Cu" "B.Cu")
		(net "P52V_HS1_DRAIN_1")
	)
	(via
		(at 288.33826 -103.87711)
		(size 0.508)
		(drill 0.254)
		(layers "F.Cu" "B.Cu")
		(net "P52V_HS1_DRAIN_1")
	)
	(via
		(at 289.10026 -102.35311)
		(size 0.508)
		(drill 0.254)
		(layers "F.Cu" "B.Cu")
		(net "P52V_HS1_DRAIN_1")
	)
	(via
		(at 289.209988 -120.327928)
		(size 0.508)
		(drill 0.254)
		(layers "F.Cu" "B.Cu")
		(net "P52V_HS1_DRAIN_1")
	)
	(segment
		(start 258.684268 -39.03345)
		(end 259.88645 -39.03345)
		(width 0.254)
		(layer "F.Cu")
		(net "P52V_HS_4287_S2N")
	)
	(segment
		(start 299.2755 -87.969344)
		(end 299.2755 -87.06104)
		(width 0.4572)
		(layer "F.Cu")
		(net "P52V_HS_4287_S2N")
	)
	(segment
		(start 299.170344 -88.705436)
		(end 299.170344 -88.0745)
		(width 0.4572)
		(layer "F.Cu")
		(net "P52V_HS_4287_S2N")
	)
	(segment
		(start 258.530598 -39.18712)
		(end 258.684268 -39.03345)
		(width 0.254)
		(layer "F.Cu")
		(net "P52V_HS_4287_S2N")
	)
	(segment
		(start 299.01896 -86.8045)
		(end 298.274994 -86.8045)
		(width 0.4572)
		(layer "F.Cu")
		(net "P52V_HS_4287_S2N")
	)
	(segment
		(start 259.88645 -39.03345)
		(end 259.945886 -39.092886)
		(width 0.254)
		(layer "F.Cu")
		(net "P52V_HS_4287_S2N")
	)
	(segment
		(start 299.2755 -87.06104)
		(end 299.01896 -86.8045)
		(width 0.4572)
		(layer "F.Cu")
		(net "P52V_HS_4287_S2N")
	)
	(segment
		(start 259.945886 -39.092886)
		(end 260.392672 -39.092886)
		(width 0.254)
		(layer "F.Cu")
		(net "P52V_HS_4287_S2N")
	)
	(segment
		(start 299.170344 -88.0745)
		(end 299.2755 -87.969344)
		(width 0.4572)
		(layer "F.Cu")
		(net "P52V_HS_4287_S2N")
	)
	(via
		(at 258.530598 -39.18712)
		(size 0.508)
		(drill 0.254)
		(layers "F.Cu" "B.Cu")
		(net "P52V_HS_4287_S2N")
	)
	(via
		(at 299.170344 -88.705436)
		(size 0.508)
		(drill 0.254)
		(layers "F.Cu" "B.Cu")
		(net "P52V_HS_4287_S2N")
	)
	(segment
		(start 293.410894 -53.50002)
		(end 266.479274 -53.50002)
		(width 0.381)
		(layer "In7.Cu")
		(net "P52V_HS_4287_S2N")
	)
	(segment
		(start 260.639052 -38.99154)
		(end 258.726178 -38.99154)
		(width 0.254)
		(layer "In7.Cu")
		(net "P52V_HS_4287_S2N")
	)
	(segment
		(start 299.32122 -87.546434)
		(end 300.65472 -86.212934)
		(width 0.381)
		(layer "In7.Cu")
		(net "P52V_HS_4287_S2N")
	)
	(segment
		(start 261.08533 -39.437818)
		(end 260.639052 -38.99154)
		(width 0.254)
		(layer "In7.Cu")
		(net "P52V_HS_4287_S2N")
	)
	(segment
		(start 299.170344 -88.705436)
		(end 299.32122 -88.55456)
		(width 0.381)
		(layer "In7.Cu")
		(net "P52V_HS_4287_S2N")
	)
	(segment
		(start 261.08533 -39.475156)
		(end 261.08533 -39.437818)
		(width 0.254)
		(layer "In7.Cu")
		(net "P52V_HS_4287_S2N")
	)
	(segment
		(start 266.479274 -53.50002)
		(end 262.0518 -49.072546)
		(width 0.381)
		(layer "In7.Cu")
		(net "P52V_HS_4287_S2N")
	)
	(segment
		(start 262.0518 -49.072546)
		(end 262.0518 -40.441626)
		(width 0.381)
		(layer "In7.Cu")
		(net "P52V_HS_4287_S2N")
	)
	(segment
		(start 262.0518 -40.441626)
		(end 261.08533 -39.475156)
		(width 0.381)
		(layer "In7.Cu")
		(net "P52V_HS_4287_S2N")
	)
	(segment
		(start 300.65472 -60.743846)
		(end 293.410894 -53.50002)
		(width 0.381)
		(layer "In7.Cu")
		(net "P52V_HS_4287_S2N")
	)
	(segment
		(start 258.726178 -38.99154)
		(end 258.530598 -39.18712)
		(width 0.254)
		(layer "In7.Cu")
		(net "P52V_HS_4287_S2N")
	)
	(segment
		(start 300.65472 -86.212934)
		(end 300.65472 -60.743846)
		(width 0.381)
		(layer "In7.Cu")
		(net "P52V_HS_4287_S2N")
	)
	(segment
		(start 299.32122 -88.55456)
		(end 299.32122 -87.546434)
		(width 0.381)
		(layer "In7.Cu")
		(net "P52V_HS_4287_S2N")
	)
	(segment
		(start 299.87494 -87.06358)
		(end 300.13402 -86.8045)
		(width 0.4572)
		(layer "F.Cu")
		(net "P52V_HS_4287_S2P")
	)
	(segment
		(start 299.970444 -88.705436)
		(end 299.970444 -88.0745)
		(width 0.4572)
		(layer "F.Cu")
		(net "P52V_HS_4287_S2P")
	)
	(segment
		(start 258.7244 -38.63721)
		(end 259.913374 -38.63721)
		(width 0.254)
		(layer "F.Cu")
		(net "P52V_HS_4287_S2P")
	)
	(segment
		(start 259.913374 -38.63721)
		(end 259.957824 -38.59276)
		(width 0.254)
		(layer "F.Cu")
		(net "P52V_HS_4287_S2P")
	)
	(segment
		(start 299.87494 -87.978996)
		(end 299.87494 -87.06358)
		(width 0.4572)
		(layer "F.Cu")
		(net "P52V_HS_4287_S2P")
	)
	(segment
		(start 258.548886 -38.461696)
		(end 258.7244 -38.63721)
		(width 0.254)
		(layer "F.Cu")
		(net "P52V_HS_4287_S2P")
	)
	(segment
		(start 299.970444 -88.0745)
		(end 299.87494 -87.978996)
		(width 0.4572)
		(layer "F.Cu")
		(net "P52V_HS_4287_S2P")
	)
	(segment
		(start 300.13402 -86.8045)
		(end 300.865794 -86.8045)
		(width 0.4572)
		(layer "F.Cu")
		(net "P52V_HS_4287_S2P")
	)
	(segment
		(start 259.957824 -38.59276)
		(end 260.367272 -38.59276)
		(width 0.254)
		(layer "F.Cu")
		(net "P52V_HS_4287_S2P")
	)
	(via
		(at 258.548886 -38.461696)
		(size 0.508)
		(drill 0.254)
		(layers "F.Cu" "B.Cu")
		(net "P52V_HS_4287_S2P")
	)
	(via
		(at 299.970444 -88.705436)
		(size 0.508)
		(drill 0.254)
		(layers "F.Cu" "B.Cu")
		(net "P52V_HS_4287_S2P")
	)
	(segment
		(start 262.5598 -40.23106)
		(end 261.44474 -39.116)
		(width 0.381)
		(layer "In7.Cu")
		(net "P52V_HS_4287_S2P")
	)
	(segment
		(start 299.82922 -87.757)
		(end 301.16272 -86.4235)
		(width 0.381)
		(layer "In7.Cu")
		(net "P52V_HS_4287_S2P")
	)
	(segment
		(start 301.16272 -86.4235)
		(end 301.16272 -60.53328)
		(width 0.381)
		(layer "In7.Cu")
		(net "P52V_HS_4287_S2P")
	)
	(segment
		(start 301.16272 -60.53328)
		(end 293.62146 -52.99202)
		(width 0.381)
		(layer "In7.Cu")
		(net "P52V_HS_4287_S2P")
	)
	(segment
		(start 299.82922 -88.564212)
		(end 299.82922 -87.757)
		(width 0.381)
		(layer "In7.Cu")
		(net "P52V_HS_4287_S2P")
	)
	(segment
		(start 261.3025 -39.116)
		(end 260.79704 -38.61054)
		(width 0.254)
		(layer "In7.Cu")
		(net "P52V_HS_4287_S2P")
	)
	(segment
		(start 262.5598 -48.86198)
		(end 262.5598 -40.23106)
		(width 0.381)
		(layer "In7.Cu")
		(net "P52V_HS_4287_S2P")
	)
	(segment
		(start 293.62146 -52.99202)
		(end 266.68984 -52.99202)
		(width 0.381)
		(layer "In7.Cu")
		(net "P52V_HS_4287_S2P")
	)
	(segment
		(start 299.970444 -88.705436)
		(end 299.82922 -88.564212)
		(width 0.381)
		(layer "In7.Cu")
		(net "P52V_HS_4287_S2P")
	)
	(segment
		(start 261.44474 -39.116)
		(end 261.3025 -39.116)
		(width 0.254)
		(layer "In7.Cu")
		(net "P52V_HS_4287_S2P")
	)
	(segment
		(start 258.69773 -38.61054)
		(end 258.548886 -38.461696)
		(width 0.254)
		(layer "In7.Cu")
		(net "P52V_HS_4287_S2P")
	)
	(segment
		(start 260.79704 -38.61054)
		(end 258.69773 -38.61054)
		(width 0.254)
		(layer "In7.Cu")
		(net "P52V_HS_4287_S2P")
	)
	(segment
		(start 266.68984 -52.99202)
		(end 262.5598 -48.86198)
		(width 0.381)
		(layer "In7.Cu")
		(net "P52V_HS_4287_S2P")
	)
	(segment
		(start 299.57522 -121.9835)
		(end 299.06722 -121.4755)
		(width 0.4572)
		(layer "F.Cu")
		(net "P52V_HS_4287_ADC_N")
	)
	(segment
		(start 299.593 -121.9835)
		(end 299.57522 -121.9835)
		(width 0.4572)
		(layer "F.Cu")
		(net "P52V_HS_4287_ADC_N")
	)
	(segment
		(start 260.392672 -41.092882)
		(end 259.630672 -41.092882)
		(width 0.254)
		(layer "F.Cu")
		(net "P52V_HS_4287_ADC_N")
	)
	(segment
		(start 299.547026 -85.7885)
		(end 299.039026 -85.2805)
		(width 0.4572)
		(layer "F.Cu")
		(net "P52V_HS_4287_ADC_N")
	)
	(segment
		(start 299.039026 -85.2805)
		(end 298.274994 -85.2805)
		(width 0.4572)
		(layer "F.Cu")
		(net "P52V_HS_4287_ADC_N")
	)
	(segment
		(start 299.06722 -121.4755)
		(end 298.2976 -121.4755)
		(width 0.4572)
		(layer "F.Cu")
		(net "P52V_HS_4287_ADC_N")
	)
	(segment
		(start 299.570394 -85.7885)
		(end 299.547026 -85.7885)
		(width 0.4572)
		(layer "F.Cu")
		(net "P52V_HS_4287_ADC_N")
	)
	(via
		(at 299.593 -121.9835)
		(size 0.508)
		(drill 0.254)
		(layers "F.Cu" "B.Cu")
		(net "P52V_HS_4287_ADC_N")
	)
	(via
		(at 299.570394 -85.7885)
		(size 0.508)
		(drill 0.254)
		(layers "F.Cu" "B.Cu")
		(net "P52V_HS_4287_ADC_N")
	)
	(via
		(at 259.630672 -41.092882)
		(size 0.508)
		(drill 0.254)
		(layers "F.Cu" "B.Cu")
		(net "P52V_HS_4287_ADC_N")
	)
	(segment
		(start 300.530514 -85.59038)
		(end 299.768514 -85.59038)
		(width 0.381)
		(layer "In2.Cu")
		(net "P52V_HS_4287_ADC_N")
	)
	(segment
		(start 298.948094 -121.6025)
		(end 298.26966 -120.924066)
		(width 0.381)
		(layer "In2.Cu")
		(net "P52V_HS_4287_ADC_N")
	)
	(segment
		(start 299.768514 -85.59038)
		(end 299.570394 -85.7885)
		(width 0.381)
		(layer "In2.Cu")
		(net "P52V_HS_4287_ADC_N")
	)
	(segment
		(start 300.912276 -115.952778)
		(end 300.912276 -85.972142)
		(width 0.381)
		(layer "In2.Cu")
		(net "P52V_HS_4287_ADC_N")
	)
	(segment
		(start 299.593 -121.9835)
		(end 299.212 -121.6025)
		(width 0.381)
		(layer "In2.Cu")
		(net "P52V_HS_4287_ADC_N")
	)
	(segment
		(start 298.26966 -118.595394)
		(end 300.912276 -115.952778)
		(width 0.381)
		(layer "In2.Cu")
		(net "P52V_HS_4287_ADC_N")
	)
	(segment
		(start 298.26966 -120.924066)
		(end 298.26966 -118.595394)
		(width 0.381)
		(layer "In2.Cu")
		(net "P52V_HS_4287_ADC_N")
	)
	(segment
		(start 299.212 -121.6025)
		(end 298.948094 -121.6025)
		(width 0.381)
		(layer "In2.Cu")
		(net "P52V_HS_4287_ADC_N")
	)
	(segment
		(start 300.912276 -85.972142)
		(end 300.530514 -85.59038)
		(width 0.381)
		(layer "In2.Cu")
		(net "P52V_HS_4287_ADC_N")
	)
	(segment
		(start 297.92676 -84.88426)
		(end 298.63542 -85.59292)
		(width 0.381)
		(layer "In7.Cu")
		(net "P52V_HS_4287_ADC_N")
	)
	(segment
		(start 260.7691 -41.42486)
		(end 260.75386 -41.4401)
		(width 0.254)
		(layer "In7.Cu")
		(net "P52V_HS_4287_ADC_N")
	)
	(segment
		(start 259.630672 -41.092882)
		(end 259.630672 -40.83558)
		(width 0.254)
		(layer "In7.Cu")
		(net "P52V_HS_4287_ADC_N")
	)
	(segment
		(start 265.798554 -55.03418)
		(end 292.608254 -55.03418)
		(width 0.381)
		(layer "In7.Cu")
		(net "P52V_HS_4287_ADC_N")
	)
	(segment
		(start 260.75386 -41.4401)
		(end 260.75386 -49.989486)
		(width 0.381)
		(layer "In7.Cu")
		(net "P52V_HS_4287_ADC_N")
	)
	(segment
		(start 298.63542 -85.59292)
		(end 299.374814 -85.59292)
		(width 0.381)
		(layer "In7.Cu")
		(net "P52V_HS_4287_ADC_N")
	)
	(segment
		(start 260.7691 -41.003728)
		(end 260.7691 -41.42486)
		(width 0.254)
		(layer "In7.Cu")
		(net "P52V_HS_4287_ADC_N")
	)
	(segment
		(start 260.316472 -40.5511)
		(end 260.7691 -41.003728)
		(width 0.254)
		(layer "In7.Cu")
		(net "P52V_HS_4287_ADC_N")
	)
	(segment
		(start 259.630672 -40.83558)
		(end 259.915152 -40.5511)
		(width 0.254)
		(layer "In7.Cu")
		(net "P52V_HS_4287_ADC_N")
	)
	(segment
		(start 297.92676 -60.352686)
		(end 297.92676 -84.88426)
		(width 0.381)
		(layer "In7.Cu")
		(net "P52V_HS_4287_ADC_N")
	)
	(segment
		(start 299.374814 -85.59292)
		(end 299.570394 -85.7885)
		(width 0.381)
		(layer "In7.Cu")
		(net "P52V_HS_4287_ADC_N")
	)
	(segment
		(start 292.608254 -55.03418)
		(end 297.92676 -60.352686)
		(width 0.381)
		(layer "In7.Cu")
		(net "P52V_HS_4287_ADC_N")
	)
	(segment
		(start 260.75386 -49.989486)
		(end 265.798554 -55.03418)
		(width 0.381)
		(layer "In7.Cu")
		(net "P52V_HS_4287_ADC_N")
	)
	(segment
		(start 259.915152 -40.5511)
		(end 260.316472 -40.5511)
		(width 0.254)
		(layer "In7.Cu")
		(net "P52V_HS_4287_ADC_N")
	)
	(segment
		(start 260.392672 -39.592758)
		(end 259.630672 -39.592758)
		(width 0.254)
		(layer "F.Cu")
		(net "P52V_HS_4287_ADC_P")
	)
	(segment
		(start 299.951394 -85.2805)
		(end 299.570394 -84.8995)
		(width 0.4572)
		(layer "F.Cu")
		(net "P52V_HS_4287_ADC_P")
	)
	(segment
		(start 299.593 -121.0945)
		(end 299.974 -121.4755)
		(width 0.4572)
		(layer "F.Cu")
		(net "P52V_HS_4287_ADC_P")
	)
	(segment
		(start 299.974 -121.4755)
		(end 300.8884 -121.4755)
		(width 0.4572)
		(layer "F.Cu")
		(net "P52V_HS_4287_ADC_P")
	)
	(segment
		(start 300.865794 -85.2805)
		(end 299.951394 -85.2805)
		(width 0.4572)
		(layer "F.Cu")
		(net "P52V_HS_4287_ADC_P")
	)
	(via
		(at 299.593 -121.0945)
		(size 0.508)
		(drill 0.254)
		(layers "F.Cu" "B.Cu")
		(net "P52V_HS_4287_ADC_P")
	)
	(via
		(at 299.570394 -84.8995)
		(size 0.508)
		(drill 0.254)
		(layers "F.Cu" "B.Cu")
		(net "P52V_HS_4287_ADC_P")
	)
	(via
		(at 259.630672 -39.592758)
		(size 0.508)
		(drill 0.254)
		(layers "F.Cu" "B.Cu")
		(net "P52V_HS_4287_ADC_P")
	)
	(segment
		(start 301.420276 -116.163344)
		(end 301.420276 -85.761576)
		(width 0.381)
		(layer "In2.Cu")
		(net "P52V_HS_4287_ADC_P")
	)
	(segment
		(start 300.74108 -85.08238)
		(end 299.753274 -85.08238)
		(width 0.381)
		(layer "In2.Cu")
		(net "P52V_HS_4287_ADC_P")
	)
	(segment
		(start 298.77766 -120.7135)
		(end 298.77766 -118.80596)
		(width 0.381)
		(layer "In2.Cu")
		(net "P52V_HS_4287_ADC_P")
	)
	(segment
		(start 299.753274 -85.08238)
		(end 299.570394 -84.8995)
		(width 0.381)
		(layer "In2.Cu")
		(net "P52V_HS_4287_ADC_P")
	)
	(segment
		(start 298.77766 -118.80596)
		(end 301.420276 -116.163344)
		(width 0.381)
		(layer "In2.Cu")
		(net "P52V_HS_4287_ADC_P")
	)
	(segment
		(start 299.15866 -121.0945)
		(end 298.77766 -120.7135)
		(width 0.381)
		(layer "In2.Cu")
		(net "P52V_HS_4287_ADC_P")
	)
	(segment
		(start 299.593 -121.0945)
		(end 299.15866 -121.0945)
		(width 0.381)
		(layer "In2.Cu")
		(net "P52V_HS_4287_ADC_P")
	)
	(segment
		(start 301.420276 -85.761576)
		(end 300.74108 -85.08238)
		(width 0.381)
		(layer "In2.Cu")
		(net "P52V_HS_4287_ADC_P")
	)
	(segment
		(start 299.384974 -85.08492)
		(end 299.570394 -84.8995)
		(width 0.381)
		(layer "In7.Cu")
		(net "P52V_HS_4287_ADC_P")
	)
	(segment
		(start 261.1501 -41.236646)
		(end 261.26186 -41.348406)
		(width 0.254)
		(layer "In7.Cu")
		(net "P52V_HS_4287_ADC_P")
	)
	(segment
		(start 259.630672 -39.9161)
		(end 259.884672 -40.1701)
		(width 0.254)
		(layer "In7.Cu")
		(net "P52V_HS_4287_ADC_P")
	)
	(segment
		(start 259.630672 -39.592758)
		(end 259.630672 -39.9161)
		(width 0.254)
		(layer "In7.Cu")
		(net "P52V_HS_4287_ADC_P")
	)
	(segment
		(start 298.43476 -84.673694)
		(end 298.845986 -85.08492)
		(width 0.381)
		(layer "In7.Cu")
		(net "P52V_HS_4287_ADC_P")
	)
	(segment
		(start 266.00912 -54.52618)
		(end 292.81882 -54.52618)
		(width 0.381)
		(layer "In7.Cu")
		(net "P52V_HS_4287_ADC_P")
	)
	(segment
		(start 260.47446 -40.1701)
		(end 261.1501 -40.84574)
		(width 0.254)
		(layer "In7.Cu")
		(net "P52V_HS_4287_ADC_P")
	)
	(segment
		(start 298.845986 -85.08492)
		(end 299.384974 -85.08492)
		(width 0.381)
		(layer "In7.Cu")
		(net "P52V_HS_4287_ADC_P")
	)
	(segment
		(start 298.43476 -60.14212)
		(end 298.43476 -84.673694)
		(width 0.381)
		(layer "In7.Cu")
		(net "P52V_HS_4287_ADC_P")
	)
	(segment
		(start 261.26186 -41.4401)
		(end 261.26186 -49.77892)
		(width 0.381)
		(layer "In7.Cu")
		(net "P52V_HS_4287_ADC_P")
	)
	(segment
		(start 261.26186 -41.348406)
		(end 261.26186 -41.4401)
		(width 0.254)
		(layer "In7.Cu")
		(net "P52V_HS_4287_ADC_P")
	)
	(segment
		(start 259.884672 -40.1701)
		(end 260.47446 -40.1701)
		(width 0.254)
		(layer "In7.Cu")
		(net "P52V_HS_4287_ADC_P")
	)
	(segment
		(start 292.81882 -54.52618)
		(end 298.43476 -60.14212)
		(width 0.381)
		(layer "In7.Cu")
		(net "P52V_HS_4287_ADC_P")
	)
	(segment
		(start 261.26186 -49.77892)
		(end 266.00912 -54.52618)
		(width 0.381)
		(layer "In7.Cu")
		(net "P52V_HS_4287_ADC_P")
	)
	(segment
		(start 261.1501 -40.84574)
		(end 261.1501 -41.236646)
		(width 0.254)
		(layer "In7.Cu")
		(net "P52V_HS_4287_ADC_P")
	)
	(segment
		(start 299.19295 -124.2695)
		(end 299.30852 -124.15393)
		(width 0.4572)
		(layer "F.Cu")
		(net "P52V_HS_4287_S1N")
	)
	(segment
		(start 299.30852 -123.30176)
		(end 299.00626 -122.9995)
		(width 0.4572)
		(layer "F.Cu")
		(net "P52V_HS_4287_S1N")
	)
	(segment
		(start 299.00626 -122.9995)
		(end 298.2976 -122.9995)
		(width 0.4572)
		(layer "F.Cu")
		(net "P52V_HS_4287_S1N")
	)
	(segment
		(start 259.8674 -40.50792)
		(end 259.952236 -40.592756)
		(width 0.254)
		(layer "F.Cu")
		(net "P52V_HS_4287_S1N")
	)
	(segment
		(start 299.30852 -124.15393)
		(end 299.30852 -123.30176)
		(width 0.4572)
		(layer "F.Cu")
		(net "P52V_HS_4287_S1N")
	)
	(segment
		(start 299.19295 -124.2695)
		(end 299.19295 -124.900436)
		(width 0.4572)
		(layer "F.Cu")
		(net "P52V_HS_4287_S1N")
	)
	(segment
		(start 258.83362 -40.72382)
		(end 259.04952 -40.50792)
		(width 0.254)
		(layer "F.Cu")
		(net "P52V_HS_4287_S1N")
	)
	(segment
		(start 259.04952 -40.50792)
		(end 259.8674 -40.50792)
		(width 0.254)
		(layer "F.Cu")
		(net "P52V_HS_4287_S1N")
	)
	(segment
		(start 259.952236 -40.592756)
		(end 260.392672 -40.592756)
		(width 0.254)
		(layer "F.Cu")
		(net "P52V_HS_4287_S1N")
	)
	(via
		(at 258.83362 -40.72382)
		(size 0.508)
		(drill 0.254)
		(layers "F.Cu" "B.Cu")
		(net "P52V_HS_4287_S1N")
	)
	(via
		(at 299.19295 -124.900436)
		(size 0.508)
		(drill 0.254)
		(layers "F.Cu" "B.Cu")
		(net "P52V_HS_4287_S1N")
	)
	(segment
		(start 260.68782 -40.61206)
		(end 260.635242 -40.559482)
		(width 0.254)
		(layer "In2.Cu")
		(net "P52V_HS_4287_S1N")
	)
	(segment
		(start 296.118026 -60.210192)
		(end 270.730726 -60.210192)
		(width 0.381)
		(layer "In2.Cu")
		(net "P52V_HS_4287_S1N")
	)
	(segment
		(start 299.34662 -124.207778)
		(end 296.98188 -121.843038)
		(width 0.381)
		(layer "In2.Cu")
		(net "P52V_HS_4287_S1N")
	)
	(segment
		(start 296.98188 -121.843038)
		(end 296.98188 -61.074046)
		(width 0.381)
		(layer "In2.Cu")
		(net "P52V_HS_4287_S1N")
	)
	(segment
		(start 260.898894 -40.61206)
		(end 260.68782 -40.61206)
		(width 0.381)
		(layer "In2.Cu")
		(net "P52V_HS_4287_S1N")
	)
	(segment
		(start 261.52348 -51.002946)
		(end 261.52348 -41.236646)
		(width 0.381)
		(layer "In2.Cu")
		(net "P52V_HS_4287_S1N")
	)
	(segment
		(start 270.730726 -60.210192)
		(end 261.52348 -51.002946)
		(width 0.381)
		(layer "In2.Cu")
		(net "P52V_HS_4287_S1N")
	)
	(segment
		(start 299.19295 -124.900436)
		(end 299.34662 -124.746766)
		(width 0.381)
		(layer "In2.Cu")
		(net "P52V_HS_4287_S1N")
	)
	(segment
		(start 258.997958 -40.559482)
		(end 258.83362 -40.72382)
		(width 0.254)
		(layer "In2.Cu")
		(net "P52V_HS_4287_S1N")
	)
	(segment
		(start 261.52348 -41.236646)
		(end 260.898894 -40.61206)
		(width 0.381)
		(layer "In2.Cu")
		(net "P52V_HS_4287_S1N")
	)
	(segment
		(start 296.98188 -61.074046)
		(end 296.118026 -60.210192)
		(width 0.381)
		(layer "In2.Cu")
		(net "P52V_HS_4287_S1N")
	)
	(segment
		(start 299.34662 -124.746766)
		(end 299.34662 -124.207778)
		(width 0.381)
		(layer "In2.Cu")
		(net "P52V_HS_4287_S1N")
	)
	(segment
		(start 260.635242 -40.559482)
		(end 258.997958 -40.559482)
		(width 0.254)
		(layer "In2.Cu")
		(net "P52V_HS_4287_S1N")
	)
	(segment
		(start 258.83616 -39.95674)
		(end 259.00634 -40.12692)
		(width 0.254)
		(layer "F.Cu")
		(net "P52V_HS_4287_S1P")
	)
	(segment
		(start 259.891276 -40.092884)
		(end 260.392672 -40.092884)
		(width 0.254)
		(layer "F.Cu")
		(net "P52V_HS_4287_S1P")
	)
	(segment
		(start 300.15434 -122.9995)
		(end 300.8884 -122.9995)
		(width 0.4572)
		(layer "F.Cu")
		(net "P52V_HS_4287_S1P")
	)
	(segment
		(start 259.85724 -40.12692)
		(end 259.891276 -40.092884)
		(width 0.254)
		(layer "F.Cu")
		(net "P52V_HS_4287_S1P")
	)
	(segment
		(start 259.00634 -40.12692)
		(end 259.85724 -40.12692)
		(width 0.254)
		(layer "F.Cu")
		(net "P52V_HS_4287_S1P")
	)
	(segment
		(start 299.90034 -123.2535)
		(end 300.15434 -122.9995)
		(width 0.4572)
		(layer "F.Cu")
		(net "P52V_HS_4287_S1P")
	)
	(segment
		(start 299.90034 -124.17679)
		(end 299.90034 -123.2535)
		(width 0.4572)
		(layer "F.Cu")
		(net "P52V_HS_4287_S1P")
	)
	(segment
		(start 299.99305 -124.2695)
		(end 299.99305 -124.900436)
		(width 0.4572)
		(layer "F.Cu")
		(net "P52V_HS_4287_S1P")
	)
	(segment
		(start 299.99305 -124.2695)
		(end 299.90034 -124.17679)
		(width 0.4572)
		(layer "F.Cu")
		(net "P52V_HS_4287_S1P")
	)
	(via
		(at 258.83616 -39.95674)
		(size 0.508)
		(drill 0.254)
		(layers "F.Cu" "B.Cu")
		(net "P52V_HS_4287_S1P")
	)
	(via
		(at 299.99305 -124.900436)
		(size 0.508)
		(drill 0.254)
		(layers "F.Cu" "B.Cu")
		(net "P52V_HS_4287_S1P")
	)
	(segment
		(start 296.328592 -59.702192)
		(end 270.941292 -59.702192)
		(width 0.381)
		(layer "In2.Cu")
		(net "P52V_HS_4287_S1P")
	)
	(segment
		(start 259.057902 -40.178482)
		(end 258.83616 -39.95674)
		(width 0.254)
		(layer "In2.Cu")
		(net "P52V_HS_4287_S1P")
	)
	(segment
		(start 261.10946 -40.10406)
		(end 260.68782 -40.10406)
		(width 0.381)
		(layer "In2.Cu")
		(net "P52V_HS_4287_S1P")
	)
	(segment
		(start 297.48988 -121.632472)
		(end 297.48988 -60.86348)
		(width 0.381)
		(layer "In2.Cu")
		(net "P52V_HS_4287_S1P")
	)
	(segment
		(start 299.85462 -123.997212)
		(end 297.48988 -121.632472)
		(width 0.381)
		(layer "In2.Cu")
		(net "P52V_HS_4287_S1P")
	)
	(segment
		(start 260.537452 -40.178482)
		(end 259.057902 -40.178482)
		(width 0.254)
		(layer "In2.Cu")
		(net "P52V_HS_4287_S1P")
	)
	(segment
		(start 299.85462 -124.762006)
		(end 299.85462 -123.997212)
		(width 0.381)
		(layer "In2.Cu")
		(net "P52V_HS_4287_S1P")
	)
	(segment
		(start 270.941292 -59.702192)
		(end 262.03148 -50.79238)
		(width 0.381)
		(layer "In2.Cu")
		(net "P52V_HS_4287_S1P")
	)
	(segment
		(start 262.03148 -50.79238)
		(end 262.03148 -41.02608)
		(width 0.381)
		(layer "In2.Cu")
		(net "P52V_HS_4287_S1P")
	)
	(segment
		(start 299.99305 -124.900436)
		(end 299.85462 -124.762006)
		(width 0.381)
		(layer "In2.Cu")
		(net "P52V_HS_4287_S1P")
	)
	(segment
		(start 262.03148 -41.02608)
		(end 261.10946 -40.10406)
		(width 0.381)
		(layer "In2.Cu")
		(net "P52V_HS_4287_S1P")
	)
	(segment
		(start 297.48988 -60.86348)
		(end 296.328592 -59.702192)
		(width 0.381)
		(layer "In2.Cu")
		(net "P52V_HS_4287_S1P")
	)
	(segment
		(start 260.611874 -40.10406)
		(end 260.537452 -40.178482)
		(width 0.254)
		(layer "In2.Cu")
		(net "P52V_HS_4287_S1P")
	)
	(segment
		(start 260.68782 -40.10406)
		(end 260.611874 -40.10406)
		(width 0.254)
		(layer "In2.Cu")
		(net "P52V_HS_4287_S1P")
	)
	(segment
		(start 259.3594 -42.3164)
		(end 260.135878 -43.092878)
		(width 0.2794)
		(layer "F.Cu")
		(net "P52V_HS1_4287_GATE_R")
	)
	(segment
		(start 259.0038 -42.3164)
		(end 259.3594 -42.3164)
		(width 0.2794)
		(layer "F.Cu")
		(net "P52V_HS1_4287_GATE_R")
	)
	(segment
		(start 260.135878 -43.092878)
		(end 260.392672 -43.092878)
		(width 0.2794)
		(layer "F.Cu")
		(net "P52V_HS1_4287_GATE_R")
	)
	(via
		(at 259.0038 -42.3164)
		(size 0.508)
		(drill 0.254)
		(layers "F.Cu" "B.Cu")
		(net "P52V_HS1_4287_GATE_R")
	)
	(via
		(at 275.971 -102.489)
		(size 0.508)
		(drill 0.254)
		(layers "F.Cu" "B.Cu")
		(net "P52V_HS1_4287_GATE_R")
	)
	(via
		(at 278.27605 -91.09456)
		(size 0.6604)
		(drill 0.3302)
		(layers "F.Cu" "B.Cu")
		(net "P52V_HS1_GATE2_R1")
	)
	(segment
		(start 277.709122 -92.466922)
		(end 278.27605 -91.899994)
		(width 0.635)
		(layer "B.Cu")
		(net "P52V_HS1_GATE2_R1")
	)
	(segment
		(start 278.27605 -91.899994)
		(end 278.27605 -91.09456)
		(width 0.635)
		(layer "B.Cu")
		(net "P52V_HS1_GATE2_R1")
	)
	(segment
		(start 276.997922 -92.466922)
		(end 275.931122 -93.533722)
		(width 0.635)
		(layer "B.Cu")
		(net "P52V_HS1_GATE2_R1")
	)
	(segment
		(start 277.709122 -92.466922)
		(end 276.997922 -92.466922)
		(width 0.635)
		(layer "B.Cu")
		(net "P52V_HS1_GATE2_R1")
	)
	(segment
		(start 278.27605 -91.09456)
		(end 278.27605 -89.916)
		(width 0.4572)
		(layer "B.Cu")
		(net "P52V_HS1_GATE2_R1")
	)
	(segment
		(start 270.383 -70.165468)
		(end 269.6464 -70.165468)
		(width 0.381)
		(layer "F.Cu")
		(net "P52V_HS1_GATE2_R")
	)
	(segment
		(start 270.383 -91.349068)
		(end 269.6464 -91.349068)
		(width 0.381)
		(layer "F.Cu")
		(net "P52V_HS1_GATE2_R")
	)
	(segment
		(start 270.383 -82.230468)
		(end 269.6464 -82.230468)
		(width 0.381)
		(layer "F.Cu")
		(net "P52V_HS1_GATE2_R")
	)
	(via
		(at 269.6464 -82.230468)
		(size 0.508)
		(drill 0.254)
		(layers "F.Cu" "B.Cu")
		(net "P52V_HS1_GATE2_R")
	)
	(via
		(at 269.6464 -91.349068)
		(size 0.508)
		(drill 0.254)
		(layers "F.Cu" "B.Cu")
		(net "P52V_HS1_GATE2_R")
	)
	(via
		(at 269.6464 -70.165468)
		(size 0.508)
		(drill 0.254)
		(layers "F.Cu" "B.Cu")
		(net "P52V_HS1_GATE2_R")
	)
	(segment
		(start 273.626072 -91.298522)
		(end 273.575526 -91.349068)
		(width 0.508)
		(layer "B.Cu")
		(net "P52V_HS1_GATE2_R")
	)
	(segment
		(start 273.575526 -91.349068)
		(end 269.6464 -91.349068)
		(width 0.635)
		(layer "B.Cu")
		(net "P52V_HS1_GATE2_R")
	)
	(segment
		(start 273.626072 -91.298522)
		(end 273.626072 -92.314522)
		(width 0.381)
		(layer "B.Cu")
		(net "P52V_HS1_GATE2_R")
	)
	(segment
		(start 270.383 -130.490468)
		(end 269.6464 -130.490468)
		(width 0.381)
		(layer "F.Cu")
		(net "P52V_HS1_GATE1_R")
	)
	(segment
		(start 270.383 -118.425468)
		(end 269.6464 -118.425468)
		(width 0.381)
		(layer "F.Cu")
		(net "P52V_HS1_GATE1_R")
	)
	(segment
		(start 270.383 -106.360468)
		(end 269.489936 -106.360468)
		(width 0.381)
		(layer "F.Cu")
		(net "P52V_HS1_GATE1_R")
	)
	(via
		(at 269.6464 -130.490468)
		(size 0.508)
		(drill 0.254)
		(layers "F.Cu" "B.Cu")
		(net "P52V_HS1_GATE1_R")
	)
	(via
		(at 269.489936 -106.360468)
		(size 0.508)
		(drill 0.254)
		(layers "F.Cu" "B.Cu")
		(net "P52V_HS1_GATE1_R")
	)
	(via
		(at 269.6464 -118.425468)
		(size 0.508)
		(drill 0.254)
		(layers "F.Cu" "B.Cu")
		(net "P52V_HS1_GATE1_R")
	)
	(segment
		(start 271.305782 -106.360468)
		(end 269.489936 -106.360468)
		(width 0.635)
		(layer "B.Cu")
		(net "P52V_HS1_GATE1_R")
	)
	(segment
		(start 273.5072 -104.15905)
		(end 271.305782 -106.360468)
		(width 0.635)
		(layer "B.Cu")
		(net "P52V_HS1_GATE1_R")
	)
	(segment
		(start 273.5072 -104.15905)
		(end 274.3962 -104.15905)
		(width 0.381)
		(layer "B.Cu")
		(net "P52V_HS1_GATE1_R")
	)
	(via
		(at 277.368 -86.0552)
		(size 0.6604)
		(drill 0.3302)
		(layers "F.Cu" "B.Cu")
		(net "P52V_HS1_4287_GATE2_RC")
	)
	(segment
		(start 277.368 -86.0552)
		(end 277.368 -87.376)
		(width 0.381)
		(layer "B.Cu")
		(net "P52V_HS1_4287_GATE2_RC")
	)
	(segment
		(start 259.69595 -43.59275)
		(end 260.392672 -43.59275)
		(width 0.2794)
		(layer "F.Cu")
		(net "P52V_HS1_4287_GATE2_R")
	)
	(segment
		(start 259.588 -43.4848)
		(end 259.69595 -43.59275)
		(width 0.2794)
		(layer "F.Cu")
		(net "P52V_HS1_4287_GATE2_R")
	)
	(via
		(at 275.971 -90.424)
		(size 0.508)
		(drill 0.254)
		(layers "F.Cu" "B.Cu")
		(net "P52V_HS1_4287_GATE2_R")
	)
	(via
		(at 259.588 -43.4848)
		(size 0.508)
		(drill 0.254)
		(layers "F.Cu" "B.Cu")
		(net "P52V_HS1_4287_GATE2_R")
	)
	(segment
		(start 264.634218 -46.00956)
		(end 264.634218 -45.373544)
		(width 0.254)
		(layer "F.Cu")
		(net "P52V_HS1_TEMP")
	)
	(segment
		(start 264.542778 -46.101)
		(end 264.634218 -46.00956)
		(width 0.254)
		(layer "F.Cu")
		(net "P52V_HS1_TEMP")
	)
	(segment
		(start 264.634218 -45.373544)
		(end 264.542778 -45.282104)
		(width 0.254)
		(layer "F.Cu")
		(net "P52V_HS1_TEMP")
	)
	(segment
		(start 264.542778 -47.223172)
		(end 264.542778 -46.101)
		(width 0.254)
		(layer "F.Cu")
		(net "P52V_HS1_TEMP")
	)
	(segment
		(start 264.541 -47.22495)
		(end 264.542778 -47.223172)
		(width 0.254)
		(layer "F.Cu")
		(net "P52V_HS1_TEMP")
	)
	(segment
		(start 281.560524 -58.862214)
		(end 280.950924 -58.862214)
		(width 0.254)
		(layer "F.Cu")
		(net "P52V_HS1_TEMP")
	)
	(segment
		(start 264.541 -47.22495)
		(end 263.910064 -47.22495)
		(width 0.381)
		(layer "F.Cu")
		(net "P52V_HS1_TEMP")
	)
	(segment
		(start 264.542778 -45.282104)
		(end 264.542778 -44.742862)
		(width 0.254)
		(layer "F.Cu")
		(net "P52V_HS1_TEMP")
	)
	(via
		(at 280.950924 -58.862214)
		(size 0.508)
		(drill 0.254)
		(layers "F.Cu" "B.Cu")
		(net "P52V_HS1_TEMP")
	)
	(via
		(at 263.910064 -47.22495)
		(size 0.508)
		(drill 0.254)
		(layers "F.Cu" "B.Cu")
		(net "P52V_HS1_TEMP")
	)
	(segment
		(start 280.950924 -58.862214)
		(end 273.746214 -58.862214)
		(width 0.254)
		(layer "In2.Cu")
		(net "P52V_HS1_TEMP")
	)
	(segment
		(start 264.6934 -49.8094)
		(end 264.6934 -48.008286)
		(width 0.254)
		(layer "In2.Cu")
		(net "P52V_HS1_TEMP")
	)
	(segment
		(start 273.746214 -58.862214)
		(end 264.6934 -49.8094)
		(width 0.254)
		(layer "In2.Cu")
		(net "P52V_HS1_TEMP")
	)
	(segment
		(start 264.6934 -48.008286)
		(end 263.910064 -47.22495)
		(width 0.254)
		(layer "In2.Cu")
		(net "P52V_HS1_TEMP")
	)
	(via
		(at 262.70966 -50.28946)
		(size 0.762)
		(drill 0.381)
		(layers "F.Cu" "B.Cu")
		(net "P52V_HS1_FB")
	)
	(segment
		(start 270.764 -43.942)
		(end 268.91488 -42.09288)
		(width 0.17272)
		(layer "F.Cu")
		(net "P52V_HS1_CS")
	)
	(segment
		(start 273.911822 -45.606462)
		(end 273.911822 -44.39539)
		(width 0.17272)
		(layer "F.Cu")
		(net "P52V_HS1_CS")
	)
	(segment
		(start 272.293334 -47.22495)
		(end 273.911822 -45.606462)
		(width 0.17272)
		(layer "F.Cu")
		(net "P52V_HS1_CS")
	)
	(segment
		(start 271.018 -44.831)
		(end 270.764 -44.577)
		(width 0.17272)
		(layer "F.Cu")
		(net "P52V_HS1_CS")
	)
	(segment
		(start 271.018 -47.22495)
		(end 272.293334 -47.22495)
		(width 0.17272)
		(layer "F.Cu")
		(net "P52V_HS1_CS")
	)
	(segment
		(start 270.764 -44.577)
		(end 270.764 -43.942)
		(width 0.17272)
		(layer "F.Cu")
		(net "P52V_HS1_CS")
	)
	(segment
		(start 271.018 -47.22495)
		(end 271.018 -44.831)
		(width 0.17272)
		(layer "F.Cu")
		(net "P52V_HS1_CS")
	)
	(segment
		(start 268.91488 -42.09288)
		(end 267.19276 -42.09288)
		(width 0.17272)
		(layer "F.Cu")
		(net "P52V_HS1_CS")
	)
	(via
		(at 270.764 -44.577)
		(size 0.762)
		(drill 0.381)
		(layers "F.Cu" "B.Cu")
		(net "P52V_HS1_CS")
	)
	(segment
		(start 270.539972 -41.092882)
		(end 271.96161 -39.671244)
		(width 0.17272)
		(layer "F.Cu")
		(net "P52V_HS1_SIO")
	)
	(segment
		(start 271.96161 -39.671244)
		(end 271.96161 -38.290246)
		(width 0.17272)
		(layer "F.Cu")
		(net "P52V_HS1_SIO")
	)
	(segment
		(start 271.96161 -38.290246)
		(end 271.96161 -37.211)
		(width 0.17272)
		(layer "F.Cu")
		(net "P52V_HS1_SIO")
	)
	(segment
		(start 267.19276 -41.092882)
		(end 270.539972 -41.092882)
		(width 0.17272)
		(layer "F.Cu")
		(net "P52V_HS1_SIO")
	)
	(segment
		(start 274.828 -39.878254)
		(end 273.261836 -41.444418)
		(width 0.17272)
		(layer "F.Cu")
		(net "P52V_HS1_SIO")
	)
	(segment
		(start 274.828 -36.4744)
		(end 274.828 -39.878254)
		(width 0.17272)
		(layer "F.Cu")
		(net "P52V_HS1_SIO")
	)
	(segment
		(start 273.261836 -41.444418)
		(end 273.261836 -44.39539)
		(width 0.17272)
		(layer "F.Cu")
		(net "P52V_HS1_SIO")
	)
	(via
		(at 271.96161 -37.211)
		(size 0.508)
		(drill 0.254)
		(layers "F.Cu" "B.Cu")
		(net "P52V_HS1_SIO")
	)
	(via
		(at 274.828 -36.4744)
		(size 0.508)
		(drill 0.254)
		(layers "F.Cu" "B.Cu")
		(net "P52V_HS1_SIO")
	)
	(segment
		(start 271.018 -36.26739)
		(end 271.018 -33.782)
		(width 0.17272)
		(layer "B.Cu")
		(net "P52V_HS1_SIO")
	)
	(segment
		(start 270.383 -33.147)
		(end 270.02105 -33.147)
		(width 0.17272)
		(layer "B.Cu")
		(net "P52V_HS1_SIO")
	)
	(segment
		(start 274.0914 -37.211)
		(end 271.96161 -37.211)
		(width 0.17272)
		(layer "B.Cu")
		(net "P52V_HS1_SIO")
	)
	(segment
		(start 270.02105 -33.038796)
		(end 269.547594 -32.56534)
		(width 0.17272)
		(layer "B.Cu")
		(net "P52V_HS1_SIO")
	)
	(segment
		(start 274.828 -36.4744)
		(end 274.0914 -37.211)
		(width 0.17272)
		(layer "B.Cu")
		(net "P52V_HS1_SIO")
	)
	(segment
		(start 271.96161 -37.211)
		(end 271.018 -36.26739)
		(width 0.17272)
		(layer "B.Cu")
		(net "P52V_HS1_SIO")
	)
	(segment
		(start 271.018 -33.782)
		(end 270.383 -33.147)
		(width 0.17272)
		(layer "B.Cu")
		(net "P52V_HS1_SIO")
	)
	(segment
		(start 270.02105 -33.147)
		(end 270.02105 -33.038796)
		(width 0.17272)
		(layer "B.Cu")
		(net "P52V_HS1_SIO")
	)
	(segment
		(start 267.28039 -32.56534)
		(end 266.59205 -31.877)
		(width 0.17272)
		(layer "B.Cu")
		(net "P52V_HS1_SIO")
	)
	(segment
		(start 269.547594 -32.56534)
		(end 267.28039 -32.56534)
		(width 0.17272)
		(layer "B.Cu")
		(net "P52V_HS1_SIO")
	)
	(segment
		(start 264.042652 -44.742862)
		(end 264.042652 -45.518832)
		(width 0.17272)
		(layer "F.Cu")
		(net "P52V_HS1_FLT")
	)
	(segment
		(start 282.575 -35.28695)
		(end 283.31795 -35.28695)
		(width 0.17272)
		(layer "F.Cu")
		(net "P52V_HS1_FLT")
	)
	(via
		(at 283.31795 -35.28695)
		(size 0.508)
		(drill 0.254)
		(layers "F.Cu" "B.Cu")
		(net "P52V_HS1_FLT")
	)
	(via
		(at 211.2645 -80.8355)
		(size 0.762)
		(drill 0.254)
		(layers "F.Cu" "B.Cu")
		(net "P52V_HS1_FLT")
	)
	(via
		(at 264.042652 -45.518832)
		(size 0.508)
		(drill 0.254)
		(layers "F.Cu" "B.Cu")
		(net "P52V_HS1_FLT")
	)
	(via
		(at 220.472 -68.961)
		(size 0.508)
		(drill 0.254)
		(layers "F.Cu" "B.Cu")
		(net "P52V_HS1_FLT")
	)
	(segment
		(start 221.234 -69.723)
		(end 221.234 -70.531228)
		(width 0.17272)
		(layer "B.Cu")
		(net "P52V_HS1_FLT")
	)
	(segment
		(start 213.7156 -81.28)
		(end 213.2711 -80.8355)
		(width 0.17272)
		(layer "B.Cu")
		(net "P52V_HS1_FLT")
	)
	(segment
		(start 213.2711 -80.8355)
		(end 211.2645 -80.8355)
		(width 0.17272)
		(layer "B.Cu")
		(net "P52V_HS1_FLT")
	)
	(segment
		(start 218.186 -73.579228)
		(end 218.186 -78.3336)
		(width 0.17272)
		(layer "B.Cu")
		(net "P52V_HS1_FLT")
	)
	(segment
		(start 210.210908 -78.994)
		(end 210.210908 -79.781908)
		(width 0.17272)
		(layer "B.Cu")
		(net "P52V_HS1_FLT")
	)
	(segment
		(start 215.2396 -81.28)
		(end 213.7156 -81.28)
		(width 0.17272)
		(layer "B.Cu")
		(net "P52V_HS1_FLT")
	)
	(segment
		(start 282.956 -36.04895)
		(end 283.31795 -35.687)
		(width 0.17272)
		(layer "B.Cu")
		(net "P52V_HS1_FLT")
	)
	(segment
		(start 283.31795 -35.687)
		(end 283.31795 -35.28695)
		(width 0.17272)
		(layer "B.Cu")
		(net "P52V_HS1_FLT")
	)
	(segment
		(start 218.186 -78.3336)
		(end 215.2396 -81.28)
		(width 0.17272)
		(layer "B.Cu")
		(net "P52V_HS1_FLT")
	)
	(segment
		(start 221.234 -70.531228)
		(end 218.186 -73.579228)
		(width 0.17272)
		(layer "B.Cu")
		(net "P52V_HS1_FLT")
	)
	(segment
		(start 220.472 -68.961)
		(end 221.234 -69.723)
		(width 0.17272)
		(layer "B.Cu")
		(net "P52V_HS1_FLT")
	)
	(segment
		(start 210.210908 -79.781908)
		(end 211.2645 -80.8355)
		(width 0.17272)
		(layer "B.Cu")
		(net "P52V_HS1_FLT")
	)
	(segment
		(start 261.962392 -36.817808)
		(end 261.962392 -38.442392)
		(width 0.12954)
		(layer "In7.Cu")
		(net "P52V_HS1_FLT")
	)
	(segment
		(start 264.042652 -45.518832)
		(end 263.381236 -46.180248)
		(width 0.12954)
		(layer "In7.Cu")
		(net "P52V_HS1_FLT")
	)
	(segment
		(start 282.046934 -47.772066)
		(end 283.972 -45.847)
		(width 0.12954)
		(layer "In7.Cu")
		(net "P52V_HS1_FLT")
	)
	(segment
		(start 226.472496 -49.144936)
		(end 248.670064 -49.144936)
		(width 0.12954)
		(layer "In7.Cu")
		(net "P52V_HS1_FLT")
	)
	(segment
		(start 259.312918 -36.216082)
		(end 261.360666 -36.216082)
		(width 0.12954)
		(layer "In7.Cu")
		(net "P52V_HS1_FLT")
	)
	(segment
		(start 264.042652 -40.522652)
		(end 264.042652 -45.518832)
		(width 0.12954)
		(layer "In7.Cu")
		(net "P52V_HS1_FLT")
	)
	(segment
		(start 220.472 -68.961)
		(end 221.8817 -67.5513)
		(width 0.12954)
		(layer "In7.Cu")
		(net "P52V_HS1_FLT")
	)
	(segment
		(start 283.972 -45.847)
		(end 283.972 -35.941)
		(width 0.12954)
		(layer "In7.Cu")
		(net "P52V_HS1_FLT")
	)
	(segment
		(start 263.381236 -48.624236)
		(end 264.795 -50.038)
		(width 0.12954)
		(layer "In7.Cu")
		(net "P52V_HS1_FLT")
	)
	(segment
		(start 263.381236 -46.180248)
		(end 263.381236 -48.624236)
		(width 0.12954)
		(layer "In7.Cu")
		(net "P52V_HS1_FLT")
	)
	(segment
		(start 261.962392 -38.442392)
		(end 264.042652 -40.522652)
		(width 0.12954)
		(layer "In7.Cu")
		(net "P52V_HS1_FLT")
	)
	(segment
		(start 264.795 -50.038)
		(end 273.304 -50.038)
		(width 0.12954)
		(layer "In7.Cu")
		(net "P52V_HS1_FLT")
	)
	(segment
		(start 248.670064 -49.144936)
		(end 257.81 -40.005)
		(width 0.12954)
		(layer "In7.Cu")
		(net "P52V_HS1_FLT")
	)
	(segment
		(start 275.569934 -47.772066)
		(end 282.046934 -47.772066)
		(width 0.12954)
		(layer "In7.Cu")
		(net "P52V_HS1_FLT")
	)
	(segment
		(start 257.81 -40.005)
		(end 257.81 -37.719)
		(width 0.12954)
		(layer "In7.Cu")
		(net "P52V_HS1_FLT")
	)
	(segment
		(start 257.81 -37.719)
		(end 259.312918 -36.216082)
		(width 0.12954)
		(layer "In7.Cu")
		(net "P52V_HS1_FLT")
	)
	(segment
		(start 221.8817 -53.735732)
		(end 226.472496 -49.144936)
		(width 0.12954)
		(layer "In7.Cu")
		(net "P52V_HS1_FLT")
	)
	(segment
		(start 261.360666 -36.216082)
		(end 261.962392 -36.817808)
		(width 0.12954)
		(layer "In7.Cu")
		(net "P52V_HS1_FLT")
	)
	(segment
		(start 283.972 -35.941)
		(end 283.31795 -35.28695)
		(width 0.12954)
		(layer "In7.Cu")
		(net "P52V_HS1_FLT")
	)
	(segment
		(start 273.304 -50.038)
		(end 275.569934 -47.772066)
		(width 0.12954)
		(layer "In7.Cu")
		(net "P52V_HS1_FLT")
	)
	(segment
		(start 221.8817 -67.5513)
		(end 221.8817 -53.735732)
		(width 0.12954)
		(layer "In7.Cu")
		(net "P52V_HS1_FLT")
	)
	(via
		(at 277.1394 -98.1456)
		(size 0.6604)
		(drill 0.3302)
		(layers "F.Cu" "B.Cu")
		(net "P52V_HS1_GATE_RC")
	)
	(segment
		(start 277.1394 -98.1456)
		(end 277.1394 -99.441)
		(width 0.381)
		(layer "B.Cu")
		(net "P52V_HS1_GATE_RC")
	)
	(via
		(at 266.75588 -32.13354)
		(size 0.762)
		(drill 0.381)
		(layers "F.Cu" "B.Cu")
		(net "HS1_TMR2")
	)
	(segment
		(start 267.462 -34.290254)
		(end 266.986766 -33.81502)
		(width 0.17272)
		(layer "F.Cu")
		(net "HS1_TMR1")
	)
	(segment
		(start 266.553696 -34.39795)
		(end 266.826746 -34.671)
		(width 0.17272)
		(layer "F.Cu")
		(net "HS1_TMR1")
	)
	(segment
		(start 266.192 -34.39795)
		(end 266.553696 -34.39795)
		(width 0.17272)
		(layer "F.Cu")
		(net "HS1_TMR1")
	)
	(segment
		(start 265.208766 -34.357818)
		(end 266.151868 -34.357818)
		(width 0.17272)
		(layer "F.Cu")
		(net "HS1_TMR1")
	)
	(segment
		(start 266.986766 -33.81502)
		(end 266.986766 -33.341818)
		(width 0.17272)
		(layer "F.Cu")
		(net "HS1_TMR1")
	)
	(segment
		(start 267.462 -34.671)
		(end 267.462 -34.290254)
		(width 0.17272)
		(layer "F.Cu")
		(net "HS1_TMR1")
	)
	(segment
		(start 266.151868 -34.357818)
		(end 266.192 -34.39795)
		(width 0.17272)
		(layer "F.Cu")
		(net "HS1_TMR1")
	)
	(segment
		(start 266.826746 -34.671)
		(end 267.462 -34.671)
		(width 0.17272)
		(layer "F.Cu")
		(net "HS1_TMR1")
	)
	(via
		(at 267.462 -34.671)
		(size 0.762)
		(drill 0.381)
		(layers "F.Cu" "B.Cu")
		(net "HS1_TMR1")
	)
	(segment
		(start 263.54278 -46.121574)
		(end 263.54278 -44.742862)
		(width 0.17272)
		(layer "F.Cu")
		(net "PWRGD_P52V_HS1_PG_N")
	)
	(segment
		(start 263.910064 -46.488858)
		(end 263.54278 -46.121574)
		(width 0.17272)
		(layer "F.Cu")
		(net "PWRGD_P52V_HS1_PG_N")
	)
	(via
		(at 179.7685 -91.1225)
		(size 0.508)
		(drill 0.254)
		(layers "F.Cu" "B.Cu")
		(net "PWRGD_P52V_HS1_PG_N")
	)
	(via
		(at 263.910064 -46.488858)
		(size 0.508)
		(drill 0.254)
		(layers "F.Cu" "B.Cu")
		(net "PWRGD_P52V_HS1_PG_N")
	)
	(segment
		(start 151.765 -114.427)
		(end 149.987 -116.205)
		(width 0.17272)
		(layer "B.Cu")
		(net "PWRGD_P52V_HS1_PG_N")
	)
	(segment
		(start 151.765 -96.687132)
		(end 151.765 -114.427)
		(width 0.17272)
		(layer "B.Cu")
		(net "PWRGD_P52V_HS1_PG_N")
	)
	(segment
		(start 149.987 -116.205)
		(end 146.95805 -116.205)
		(width 0.17272)
		(layer "B.Cu")
		(net "PWRGD_P52V_HS1_PG_N")
	)
	(segment
		(start 179.31384 -91.57716)
		(end 156.874972 -91.57716)
		(width 0.17272)
		(layer "B.Cu")
		(net "PWRGD_P52V_HS1_PG_N")
	)
	(segment
		(start 156.874972 -91.57716)
		(end 151.765 -96.687132)
		(width 0.17272)
		(layer "B.Cu")
		(net "PWRGD_P52V_HS1_PG_N")
	)
	(segment
		(start 179.7685 -91.1225)
		(end 179.31384 -91.57716)
		(width 0.17272)
		(layer "B.Cu")
		(net "PWRGD_P52V_HS1_PG_N")
	)
	(segment
		(start 248.426732 -48.558196)
		(end 226.229164 -48.558196)
		(width 0.12954)
		(layer "In7.Cu")
		(net "PWRGD_P52V_HS1_PG_N")
	)
	(segment
		(start 219.65539 -70.739)
		(end 220.22689 -71.3105)
		(width 0.12954)
		(layer "In7.Cu")
		(net "PWRGD_P52V_HS1_PG_N")
	)
	(segment
		(start 226.229164 -48.558196)
		(end 221.29496 -53.4924)
		(width 0.12954)
		(layer "In7.Cu")
		(net "PWRGD_P52V_HS1_PG_N")
	)
	(segment
		(start 264.467086 -29.76626)
		(end 257.22326 -37.010086)
		(width 0.12954)
		(layer "In7.Cu")
		(net "PWRGD_P52V_HS1_PG_N")
	)
	(segment
		(start 226.187 -71.628)
		(end 226.187 -80.077818)
		(width 0.12954)
		(layer "In7.Cu")
		(net "PWRGD_P52V_HS1_PG_N")
	)
	(segment
		(start 265.201146 -46.7106)
		(end 273.69897 -38.212776)
		(width 0.12954)
		(layer "In7.Cu")
		(net "PWRGD_P52V_HS1_PG_N")
	)
	(segment
		(start 271.906238 -29.76626)
		(end 264.467086 -29.76626)
		(width 0.12954)
		(layer "In7.Cu")
		(net "PWRGD_P52V_HS1_PG_N")
	)
	(segment
		(start 273.69897 -38.212776)
		(end 273.69897 -31.558992)
		(width 0.12954)
		(layer "In7.Cu")
		(net "PWRGD_P52V_HS1_PG_N")
	)
	(segment
		(start 226.187 -80.077818)
		(end 223.509078 -82.75574)
		(width 0.12954)
		(layer "In7.Cu")
		(net "PWRGD_P52V_HS1_PG_N")
	)
	(segment
		(start 219.65539 -65.104518)
		(end 219.65539 -70.739)
		(width 0.12954)
		(layer "In7.Cu")
		(net "PWRGD_P52V_HS1_PG_N")
	)
	(segment
		(start 205.180946 -82.423)
		(end 203.68641 -83.917536)
		(width 0.12954)
		(layer "In7.Cu")
		(net "PWRGD_P52V_HS1_PG_N")
	)
	(segment
		(start 180.556916 -90.334084)
		(end 179.7685 -91.1225)
		(width 0.12954)
		(layer "In7.Cu")
		(net "PWRGD_P52V_HS1_PG_N")
	)
	(segment
		(start 257.22326 -37.010086)
		(end 257.22326 -39.761668)
		(width 0.12954)
		(layer "In7.Cu")
		(net "PWRGD_P52V_HS1_PG_N")
	)
	(segment
		(start 257.22326 -39.761668)
		(end 248.426732 -48.558196)
		(width 0.12954)
		(layer "In7.Cu")
		(net "PWRGD_P52V_HS1_PG_N")
	)
	(segment
		(start 211.88426 -82.423)
		(end 205.180946 -82.423)
		(width 0.12954)
		(layer "In7.Cu")
		(net "PWRGD_P52V_HS1_PG_N")
	)
	(segment
		(start 189.700916 -90.334084)
		(end 180.556916 -90.334084)
		(width 0.12954)
		(layer "In7.Cu")
		(net "PWRGD_P52V_HS1_PG_N")
	)
	(segment
		(start 223.509078 -82.75574)
		(end 212.217 -82.75574)
		(width 0.12954)
		(layer "In7.Cu")
		(net "PWRGD_P52V_HS1_PG_N")
	)
	(segment
		(start 221.29496 -63.464948)
		(end 219.65539 -65.104518)
		(width 0.12954)
		(layer "In7.Cu")
		(net "PWRGD_P52V_HS1_PG_N")
	)
	(segment
		(start 221.29496 -53.4924)
		(end 221.29496 -63.464948)
		(width 0.12954)
		(layer "In7.Cu")
		(net "PWRGD_P52V_HS1_PG_N")
	)
	(segment
		(start 273.69897 -31.558992)
		(end 271.906238 -29.76626)
		(width 0.12954)
		(layer "In7.Cu")
		(net "PWRGD_P52V_HS1_PG_N")
	)
	(segment
		(start 220.22689 -71.3105)
		(end 225.8695 -71.3105)
		(width 0.12954)
		(layer "In7.Cu")
		(net "PWRGD_P52V_HS1_PG_N")
	)
	(segment
		(start 263.910064 -46.488858)
		(end 264.131806 -46.7106)
		(width 0.12954)
		(layer "In7.Cu")
		(net "PWRGD_P52V_HS1_PG_N")
	)
	(segment
		(start 212.217 -82.75574)
		(end 211.88426 -82.423)
		(width 0.12954)
		(layer "In7.Cu")
		(net "PWRGD_P52V_HS1_PG_N")
	)
	(segment
		(start 264.131806 -46.7106)
		(end 265.201146 -46.7106)
		(width 0.12954)
		(layer "In7.Cu")
		(net "PWRGD_P52V_HS1_PG_N")
	)
	(segment
		(start 225.8695 -71.3105)
		(end 226.187 -71.628)
		(width 0.12954)
		(layer "In7.Cu")
		(net "PWRGD_P52V_HS1_PG_N")
	)
	(segment
		(start 196.117464 -83.917536)
		(end 189.700916 -90.334084)
		(width 0.12954)
		(layer "In7.Cu")
		(net "PWRGD_P52V_HS1_PG_N")
	)
	(segment
		(start 203.68641 -83.917536)
		(end 196.117464 -83.917536)
		(width 0.12954)
		(layer "In7.Cu")
		(net "PWRGD_P52V_HS1_PG_N")
	)
	(segment
		(start 268.351 -44.196)
		(end 268.351 -45.339)
		(width 0.17272)
		(layer "F.Cu")
		(net "SMB_P52V_HS1_SDAO")
	)
	(segment
		(start 267.74775 -43.59275)
		(end 268.351 -44.196)
		(width 0.17272)
		(layer "F.Cu")
		(net "SMB_P52V_HS1_SDAO")
	)
	(segment
		(start 267.19276 -43.59275)
		(end 267.74775 -43.59275)
		(width 0.17272)
		(layer "F.Cu")
		(net "SMB_P52V_HS1_SDAO")
	)
	(segment
		(start 267.589 -47.22495)
		(end 267.589 -46.101)
		(width 0.17272)
		(layer "F.Cu")
		(net "SMB_P52V_HS1_SDAO")
	)
	(segment
		(start 268.351 -45.339)
		(end 267.716 -45.974)
		(width 0.17272)
		(layer "F.Cu")
		(net "SMB_P52V_HS1_SDAO")
	)
	(segment
		(start 267.589 -46.101)
		(end 267.716 -45.974)
		(width 0.17272)
		(layer "F.Cu")
		(net "SMB_P52V_HS1_SDAO")
	)
	(via
		(at 267.716 -45.974)
		(size 0.762)
		(drill 0.381)
		(layers "F.Cu" "B.Cu")
		(net "SMB_P52V_HS1_SDAO")
	)
	(segment
		(start 268.136878 -43.092878)
		(end 267.19276 -43.092878)
		(width 0.17272)
		(layer "F.Cu")
		(net "SMB_P52V_HS1_SDAI")
	)
	(segment
		(start 269.113 -44.577)
		(end 269.113 -44.069)
		(width 0.17272)
		(layer "F.Cu")
		(net "SMB_P52V_HS1_SDAI")
	)
	(segment
		(start 269.113 -44.577)
		(end 269.113 -45.974254)
		(width 0.17272)
		(layer "F.Cu")
		(net "SMB_P52V_HS1_SDAI")
	)
	(segment
		(start 269.113 -45.974254)
		(end 268.732 -46.355254)
		(width 0.17272)
		(layer "F.Cu")
		(net "SMB_P52V_HS1_SDAI")
	)
	(segment
		(start 269.113 -44.069)
		(end 268.136878 -43.092878)
		(width 0.17272)
		(layer "F.Cu")
		(net "SMB_P52V_HS1_SDAI")
	)
	(segment
		(start 268.732 -46.355254)
		(end 268.732 -47.22495)
		(width 0.17272)
		(layer "F.Cu")
		(net "SMB_P52V_HS1_SDAI")
	)
	(via
		(at 269.113 -44.577)
		(size 0.762)
		(drill 0.381)
		(layers "F.Cu" "B.Cu")
		(net "SMB_P52V_HS1_SDAI")
	)
	(segment
		(start 267.19276 -39.592758)
		(end 268.605 -39.592758)
		(width 0.17272)
		(layer "F.Cu")
		(net "P52V_HS1_CLKIN")
	)
	(via
		(at 268.605 -39.592758)
		(size 0.508)
		(drill 0.254)
		(layers "F.Cu" "B.Cu")
		(net "P52V_HS1_CLKIN")
	)
	(segment
		(start 269.38605 -38.811708)
		(end 269.38605 -36.068)
		(width 0.17272)
		(layer "B.Cu")
		(net "P52V_HS1_CLKIN")
	)
	(segment
		(start 268.605 -39.592758)
		(end 269.38605 -38.811708)
		(width 0.17272)
		(layer "B.Cu")
		(net "P52V_HS1_CLKIN")
	)
	(via
		(at 261.35076 -46.26102)
		(size 0.762)
		(drill 0.381)
		(layers "F.Cu" "B.Cu")
		(net "P52V_HS1_VDSFB")
	)
	(segment
		(start 273.261836 -38.290246)
		(end 273.261836 -40.478964)
		(width 0.381)
		(layer "F.Cu")
		(net "P52V_HS1_DVCC")
	)
	(segment
		(start 273.261836 -40.478964)
		(end 272.611596 -41.129204)
		(width 0.381)
		(layer "F.Cu")
		(net "P52V_HS1_DVCC")
	)
	(segment
		(start 272.611596 -41.129204)
		(end 272.611596 -44.39539)
		(width 0.381)
		(layer "F.Cu")
		(net "P52V_HS1_DVCC")
	)
	(via
		(at 272.581116 -35.7632)
		(size 0.508)
		(drill 0.254)
		(layers "F.Cu" "B.Cu")
		(net "P52V_HS1_DVCC")
	)
	(via
		(at 272.581116 -35.0012)
		(size 0.508)
		(drill 0.254)
		(layers "F.Cu" "B.Cu")
		(net "P52V_HS1_DVCC")
	)
	(via
		(at 273.6596 -35.8902)
		(size 0.762)
		(drill 0.381)
		(layers "F.Cu" "B.Cu")
		(net "P52V_HS1_DVCC")
	)
	(via
		(at 265.159744 -37.01923)
		(size 0.508)
		(drill 0.254)
		(layers "F.Cu" "B.Cu")
		(net "P52V_HS1_DVCC")
	)
	(via
		(at 278.27605 -103.20274)
		(size 0.6604)
		(drill 0.3302)
		(layers "F.Cu" "B.Cu")
		(net "P52V_HS1_GATE_R1")
	)
	(segment
		(start 277.709122 -104.531922)
		(end 278.27605 -103.964994)
		(width 0.635)
		(layer "B.Cu")
		(net "P52V_HS1_GATE_R1")
	)
	(segment
		(start 278.27605 -103.20274)
		(end 278.27605 -101.981)
		(width 0.4572)
		(layer "B.Cu")
		(net "P52V_HS1_GATE_R1")
	)
	(segment
		(start 277.709122 -104.531922)
		(end 276.997922 -104.531922)
		(width 0.635)
		(layer "B.Cu")
		(net "P52V_HS1_GATE_R1")
	)
	(segment
		(start 278.27605 -103.964994)
		(end 278.27605 -103.20274)
		(width 0.635)
		(layer "B.Cu")
		(net "P52V_HS1_GATE_R1")
	)
	(segment
		(start 276.997922 -104.531922)
		(end 275.931122 -105.598722)
		(width 0.635)
		(layer "B.Cu")
		(net "P52V_HS1_GATE_R1")
	)
	(segment
		(start 266.016232 -35.373818)
		(end 266.192 -35.19805)
		(width 0.17272)
		(layer "F.Cu")
		(net "P52V_HS1_TMR")
	)
	(segment
		(start 266.192 -35.19805)
		(end 267.59027 -36.59632)
		(width 0.17272)
		(layer "F.Cu")
		(net "P52V_HS1_TMR")
	)
	(segment
		(start 268.351 -37.35705)
		(end 268.351 -38.735)
		(width 0.17272)
		(layer "F.Cu")
		(net "P52V_HS1_TMR")
	)
	(segment
		(start 267.993114 -39.092886)
		(end 267.19276 -39.092886)
		(width 0.17272)
		(layer "F.Cu")
		(net "P52V_HS1_TMR")
	)
	(segment
		(start 268.351 -38.735)
		(end 267.993114 -39.092886)
		(width 0.17272)
		(layer "F.Cu")
		(net "P52V_HS1_TMR")
	)
	(segment
		(start 267.59027 -36.59632)
		(end 268.351 -37.35705)
		(width 0.17272)
		(layer "F.Cu")
		(net "P52V_HS1_TMR")
	)
	(segment
		(start 265.208766 -35.373818)
		(end 266.016232 -35.373818)
		(width 0.17272)
		(layer "F.Cu")
		(net "P52V_HS1_TMR")
	)
	(via
		(at 267.59027 -36.59632)
		(size 0.762)
		(drill 0.381)
		(layers "F.Cu" "B.Cu")
		(net "P52V_HS1_TMR")
	)
	(segment
		(start 269.748 -42.164)
		(end 270.383 -42.164)
		(width 0.17272)
		(layer "F.Cu")
		(net "P52V_HS1_SCK")
	)
	(segment
		(start 270.383 -42.164)
		(end 272.611596 -39.935404)
		(width 0.17272)
		(layer "F.Cu")
		(net "P52V_HS1_SCK")
	)
	(segment
		(start 269.176754 -41.592754)
		(end 269.367 -41.783)
		(width 0.17272)
		(layer "F.Cu")
		(net "P52V_HS1_SCK")
	)
	(segment
		(start 267.19276 -41.592754)
		(end 269.176754 -41.592754)
		(width 0.17272)
		(layer "F.Cu")
		(net "P52V_HS1_SCK")
	)
	(segment
		(start 269.367 -41.783)
		(end 269.748 -42.164)
		(width 0.17272)
		(layer "F.Cu")
		(net "P52V_HS1_SCK")
	)
	(segment
		(start 272.611596 -39.935404)
		(end 272.611596 -38.290246)
		(width 0.17272)
		(layer "F.Cu")
		(net "P52V_HS1_SCK")
	)
	(via
		(at 269.367 -41.783)
		(size 0.508)
		(drill 0.254)
		(layers "F.Cu" "B.Cu")
		(net "P52V_HS1_SCK")
	)
	(via
		(at 270.383 -42.164)
		(size 0.762)
		(drill 0.381)
		(layers "F.Cu" "B.Cu")
		(net "P52V_HS1_SCK")
	)
	(segment
		(start 269.801086 -34.61766)
		(end 270.02105 -34.397696)
		(width 0.17272)
		(layer "B.Cu")
		(net "P52V_HS1_SCK")
	)
	(segment
		(start 270.383 -34.29)
		(end 270.383 -38.608)
		(width 0.17272)
		(layer "B.Cu")
		(net "P52V_HS1_SCK")
	)
	(segment
		(start 270.129 -34.036)
		(end 270.383 -34.29)
		(width 0.17272)
		(layer "B.Cu")
		(net "P52V_HS1_SCK")
	)
	(segment
		(start 269.367 -39.624)
		(end 269.367 -41.783)
		(width 0.17272)
		(layer "B.Cu")
		(net "P52V_HS1_SCK")
	)
	(segment
		(start 270.383 -38.608)
		(end 269.367 -39.624)
		(width 0.17272)
		(layer "B.Cu")
		(net "P52V_HS1_SCK")
	)
	(segment
		(start 266.59205 -32.766)
		(end 268.44371 -34.61766)
		(width 0.17272)
		(layer "B.Cu")
		(net "P52V_HS1_SCK")
	)
	(segment
		(start 270.02105 -34.397696)
		(end 270.02105 -34.036)
		(width 0.17272)
		(layer "B.Cu")
		(net "P52V_HS1_SCK")
	)
	(segment
		(start 270.02105 -34.036)
		(end 270.129 -34.036)
		(width 0.17272)
		(layer "B.Cu")
		(net "P52V_HS1_SCK")
	)
	(segment
		(start 268.44371 -34.61766)
		(end 269.801086 -34.61766)
		(width 0.17272)
		(layer "B.Cu")
		(net "P52V_HS1_SCK")
	)
	(segment
		(start 280.543 -35.28695)
		(end 280.543 -34.677096)
		(width 0.381)
		(layer "F.Cu")
		(net "GND_FIELD_SIGNAL")
	)
	(segment
		(start 287.782 -49.67605)
		(end 287.782 -50.292)
		(width 0.381)
		(layer "F.Cu")
		(net "GND_FIELD_SIGNAL")
	)
	(segment
		(start 271.018 -48.02505)
		(end 271.018 -48.641)
		(width 0.381)
		(layer "F.Cu")
		(net "GND_FIELD_SIGNAL")
	)
	(segment
		(start 281.58186 -56.957214)
		(end 280.972006 -56.957214)
		(width 0.381)
		(layer "F.Cu")
		(net "GND_FIELD_SIGNAL")
	)
	(segment
		(start 264.541 -48.02505)
		(end 263.910064 -48.02505)
		(width 0.381)
		(layer "F.Cu")
		(net "GND_FIELD_SIGNAL")
	)
	(segment
		(start 285.22295 -35.168078)
		(end 284.613096 -35.168078)
		(width 0.381)
		(layer "F.Cu")
		(net "GND_FIELD_SIGNAL")
	)
	(via
		(at 263.271 -43.688)
		(size 0.508)
		(drill 0.254)
		(layers "F.Cu" "B.Cu")
		(net "GND_FIELD_SIGNAL")
	)
	(via
		(at 275.72335 -41.656)
		(size 0.508)
		(drill 0.254)
		(layers "F.Cu" "B.Cu")
		(net "GND_FIELD_SIGNAL")
	)
	(via
		(at 272.669 -48.641)
		(size 0.508)
		(drill 0.254)
		(layers "F.Cu" "B.Cu")
		(net "GND_FIELD_SIGNAL")
	)
	(via
		(at 268.61135 -35.2044)
		(size 0.508)
		(drill 0.254)
		(layers "F.Cu" "B.Cu")
		(net "GND_FIELD_SIGNAL")
	)
	(via
		(at 263.910064 -48.02505)
		(size 0.508)
		(drill 0.254)
		(layers "F.Cu" "B.Cu")
		(net "GND_FIELD_SIGNAL")
	)
	(via
		(at 263.271 -38.989)
		(size 0.508)
		(drill 0.254)
		(layers "F.Cu" "B.Cu")
		(net "GND_FIELD_SIGNAL")
	)
	(via
		(at 268.61135 -34.036)
		(size 0.508)
		(drill 0.254)
		(layers "F.Cu" "B.Cu")
		(net "GND_FIELD_SIGNAL")
	)
	(via
		(at 284.5308 -39.878)
		(size 0.508)
		(drill 0.254)
		(layers "F.Cu" "B.Cu")
		(net "GND_FIELD_SIGNAL")
	)
	(via
		(at 280.543 -34.677096)
		(size 0.508)
		(drill 0.254)
		(layers "F.Cu" "B.Cu")
		(net "GND_FIELD_SIGNAL")
	)
	(via
		(at 284.5308 -44.831)
		(size 0.508)
		(drill 0.254)
		(layers "F.Cu" "B.Cu")
		(net "GND_FIELD_SIGNAL")
	)
	(via
		(at 275.72335 -44.323)
		(size 0.508)
		(drill 0.254)
		(layers "F.Cu" "B.Cu")
		(net "GND_FIELD_SIGNAL")
	)
	(via
		(at 286.766 -44.831)
		(size 0.508)
		(drill 0.254)
		(layers "F.Cu" "B.Cu")
		(net "GND_FIELD_SIGNAL")
	)
	(via
		(at 275.72335 -42.545)
		(size 0.508)
		(drill 0.254)
		(layers "F.Cu" "B.Cu")
		(net "GND_FIELD_SIGNAL")
	)
	(via
		(at 284.613096 -35.168078)
		(size 0.508)
		(drill 0.254)
		(layers "F.Cu" "B.Cu")
		(net "GND_FIELD_SIGNAL")
	)
	(via
		(at 275.72335 -43.434)
		(size 0.508)
		(drill 0.254)
		(layers "F.Cu" "B.Cu")
		(net "GND_FIELD_SIGNAL")
	)
	(via
		(at 263.271 -41.402)
		(size 0.508)
		(drill 0.254)
		(layers "F.Cu" "B.Cu")
		(net "GND_FIELD_SIGNAL")
	)
	(via
		(at 286.766 -39.878)
		(size 0.508)
		(drill 0.254)
		(layers "F.Cu" "B.Cu")
		(net "GND_FIELD_SIGNAL")
	)
	(via
		(at 266.192 -43.688)
		(size 0.508)
		(drill 0.254)
		(layers "F.Cu" "B.Cu")
		(net "GND_FIELD_SIGNAL")
	)
	(via
		(at 268.61135 -33.147)
		(size 0.508)
		(drill 0.254)
		(layers "F.Cu" "B.Cu")
		(net "GND_FIELD_SIGNAL")
	)
	(via
		(at 287.782 -50.292)
		(size 0.508)
		(drill 0.254)
		(layers "F.Cu" "B.Cu")
		(net "GND_FIELD_SIGNAL")
	)
	(via
		(at 266.192 -38.989)
		(size 0.508)
		(drill 0.254)
		(layers "F.Cu" "B.Cu")
		(net "GND_FIELD_SIGNAL")
	)
	(via
		(at 286.766 -42.291)
		(size 0.508)
		(drill 0.254)
		(layers "F.Cu" "B.Cu")
		(net "GND_FIELD_SIGNAL")
	)
	(via
		(at 275.59 -46.88205)
		(size 0.508)
		(drill 0.254)
		(layers "F.Cu" "B.Cu")
		(net "GND_FIELD_SIGNAL")
	)
	(via
		(at 280.972006 -56.957214)
		(size 0.508)
		(drill 0.254)
		(layers "F.Cu" "B.Cu")
		(net "GND_FIELD_SIGNAL")
	)
	(via
		(at 274.193 -46.88205)
		(size 0.508)
		(drill 0.254)
		(layers "F.Cu" "B.Cu")
		(net "GND_FIELD_SIGNAL")
	)
	(via
		(at 266.192 -41.402)
		(size 0.508)
		(drill 0.254)
		(layers "F.Cu" "B.Cu")
		(net "GND_FIELD_SIGNAL")
	)
	(via
		(at 271.78 -48.641)
		(size 0.508)
		(drill 0.254)
		(layers "F.Cu" "B.Cu")
		(net "GND_FIELD_SIGNAL")
	)
	(via
		(at 271.018 -48.641)
		(size 0.508)
		(drill 0.254)
		(layers "F.Cu" "B.Cu")
		(net "GND_FIELD_SIGNAL")
	)
	(via
		(at 284.5308 -42.291)
		(size 0.508)
		(drill 0.254)
		(layers "F.Cu" "B.Cu")
		(net "GND_FIELD_SIGNAL")
	)
	(segment
		(start 272.669 -48.641)
		(end 272.669 -48.02505)
		(width 0.381)
		(layer "B.Cu")
		(net "GND_FIELD_SIGNAL")
	)
	(segment
		(start 276.33295 -42.545)
		(end 275.72335 -42.545)
		(width 0.381)
		(layer "B.Cu")
		(net "GND_FIELD_SIGNAL")
	)
	(segment
		(start 288.163 -49.911)
		(end 288.90595 -49.911)
		(width 0.381)
		(layer "B.Cu")
		(net "GND_FIELD_SIGNAL")
	)
	(segment
		(start 276.33295 -41.656)
		(end 275.72335 -41.656)
		(width 0.381)
		(layer "B.Cu")
		(net "GND_FIELD_SIGNAL")
	)
	(segment
		(start 269.22095 -33.147)
		(end 268.61135 -33.147)
		(width 0.381)
		(layer "B.Cu")
		(net "GND_FIELD_SIGNAL")
	)
	(segment
		(start 287.782 -50.292)
		(end 288.163 -49.911)
		(width 0.381)
		(layer "B.Cu")
		(net "GND_FIELD_SIGNAL")
	)
	(segment
		(start 274.193 -46.88205)
		(end 273.558 -46.88205)
		(width 0.381)
		(layer "B.Cu")
		(net "GND_FIELD_SIGNAL")
	)
	(segment
		(start 268.61135 -36.0426)
		(end 268.61135 -35.2044)
		(width 0.381)
		(layer "B.Cu")
		(net "GND_FIELD_SIGNAL")
	)
	(segment
		(start 269.22095 -34.036)
		(end 268.61135 -34.036)
		(width 0.381)
		(layer "B.Cu")
		(net "GND_FIELD_SIGNAL")
	)
	(segment
		(start 268.58595 -36.068)
		(end 268.61135 -36.0426)
		(width 0.381)
		(layer "B.Cu")
		(net "GND_FIELD_SIGNAL")
	)
	(segment
		(start 276.33295 -44.323)
		(end 275.72335 -44.323)
		(width 0.381)
		(layer "B.Cu")
		(net "GND_FIELD_SIGNAL")
	)
	(segment
		(start 271.78 -48.641)
		(end 271.78 -48.02505)
		(width 0.381)
		(layer "B.Cu")
		(net "GND_FIELD_SIGNAL")
	)
	(segment
		(start 274.955 -46.88205)
		(end 275.59 -46.88205)
		(width 0.381)
		(layer "B.Cu")
		(net "GND_FIELD_SIGNAL")
	)
	(segment
		(start 288.90595 -49.911)
		(end 288.90595 -50.927)
		(width 0.381)
		(layer "B.Cu")
		(net "GND_FIELD_SIGNAL")
	)
	(segment
		(start 276.33295 -43.434)
		(end 275.72335 -43.434)
		(width 0.381)
		(layer "B.Cu")
		(net "GND_FIELD_SIGNAL")
	)
	(segment
		(start 263.525 -36.449)
		(end 264.042652 -36.966652)
		(width 0.17272)
		(layer "F.Cu")
		(net "P52V_HS1_INTVCC")
	)
	(segment
		(start 263.525 -36.068)
		(end 263.525 -36.449)
		(width 0.17272)
		(layer "F.Cu")
		(net "P52V_HS1_INTVCC")
	)
	(segment
		(start 264.042652 -36.966652)
		(end 264.042652 -37.942774)
		(width 0.17272)
		(layer "F.Cu")
		(net "P52V_HS1_INTVCC")
	)
	(via
		(at 263.525 -36.068)
		(size 0.508)
		(drill 0.254)
		(layers "F.Cu" "B.Cu")
		(net "P52V_HS1_INTVCC")
	)
	(via
		(at 264.033 -34.163)
		(size 0.6604)
		(drill 0.3302)
		(layers "F.Cu" "B.Cu")
		(net "P52V_HS1_INTVCC")
	)
	(segment
		(start 267.60424 -38.59276)
		(end 267.21816 -38.59276)
		(width 0.17272)
		(layer "F.Cu")
		(net "P52V_HS1_MODE")
	)
	(segment
		(start 267.843 -38.354)
		(end 267.60424 -38.59276)
		(width 0.17272)
		(layer "F.Cu")
		(net "P52V_HS1_MODE")
	)
	(segment
		(start 267.843 -37.719)
		(end 267.843 -38.354)
		(width 0.17272)
		(layer "F.Cu")
		(net "P52V_HS1_MODE")
	)
	(via
		(at 267.843 -37.719)
		(size 0.508)
		(drill 0.254)
		(layers "F.Cu" "B.Cu")
		(net "P52V_HS1_MODE")
	)
	(segment
		(start 267.843 -37.719)
		(end 267.843 -34.93135)
		(width 0.17272)
		(layer "B.Cu")
		(net "P52V_HS1_MODE")
	)
	(segment
		(start 267.843 -34.93135)
		(end 266.84605 -33.9344)
		(width 0.17272)
		(layer "B.Cu")
		(net "P52V_HS1_MODE")
	)
	(segment
		(start 266.84605 -33.9344)
		(end 266.59205 -33.9344)
		(width 0.17272)
		(layer "B.Cu")
		(net "P52V_HS1_MODE")
	)
	(via
		(at 167.6654 -10.1346)
		(size 0.762)
		(drill 0.381)
		(layers "F.Cu" "B.Cu")
		(net "SW_P12V_FILT__P3V3_AUX")
	)
	(segment
		(start 176.38395 -8.128)
		(end 176.39284 -8.13689)
		(width 0.254)
		(layer "F.Cu")
		(net "P3V3_AUX_FB")
	)
	(segment
		(start 176.38395 -8.128)
		(end 176.38395 -7.493)
		(width 0.254)
		(layer "F.Cu")
		(net "P3V3_AUX_FB")
	)
	(segment
		(start 177.39868 -9.9822)
		(end 177.550064 -10.133584)
		(width 0.254)
		(layer "F.Cu")
		(net "P3V3_AUX_FB")
	)
	(segment
		(start 176.39284 -9.53008)
		(end 176.84496 -9.9822)
		(width 0.254)
		(layer "F.Cu")
		(net "P3V3_AUX_FB")
	)
	(segment
		(start 176.39284 -8.13689)
		(end 176.39284 -9.32053)
		(width 0.254)
		(layer "F.Cu")
		(net "P3V3_AUX_FB")
	)
	(segment
		(start 176.84496 -9.9822)
		(end 177.39868 -9.9822)
		(width 0.254)
		(layer "F.Cu")
		(net "P3V3_AUX_FB")
	)
	(segment
		(start 177.550064 -10.133584)
		(end 177.550064 -10.564114)
		(width 0.254)
		(layer "F.Cu")
		(net "P3V3_AUX_FB")
	)
	(segment
		(start 176.39284 -9.32053)
		(end 176.39284 -9.53008)
		(width 0.254)
		(layer "F.Cu")
		(net "P3V3_AUX_FB")
	)
	(segment
		(start 176.38395 -7.493)
		(end 176.38395 -6.858)
		(width 0.254)
		(layer "F.Cu")
		(net "P3V3_AUX_FB")
	)
	(via
		(at 176.38395 -7.493)
		(size 0.508)
		(drill 0.254)
		(layers "F.Cu" "B.Cu")
		(net "P3V3_AUX_FB")
	)
	(segment
		(start 180.34 -11.79195)
		(end 180.34 -10.68705)
		(width 0.254)
		(layer "F.Cu")
		(net "SW_P3V3_AUX_BT_R")
	)
	(segment
		(start 179.832 -10.39495)
		(end 180.34 -9.88695)
		(width 0.17272)
		(layer "F.Cu")
		(net "SW_P3V3_AUX_BT")
	)
	(segment
		(start 179.3748 -12.0142)
		(end 179.832 -11.557)
		(width 0.17272)
		(layer "F.Cu")
		(net "SW_P3V3_AUX_BT")
	)
	(segment
		(start 178.649884 -12.0142)
		(end 179.3748 -12.0142)
		(width 0.17272)
		(layer "F.Cu")
		(net "SW_P3V3_AUX_BT")
	)
	(segment
		(start 179.832 -11.557)
		(end 179.832 -10.39495)
		(width 0.17272)
		(layer "F.Cu")
		(net "SW_P3V3_AUX_BT")
	)
	(segment
		(start 179.578 -8.128)
		(end 178.96205 -8.128)
		(width 0.17272)
		(layer "F.Cu")
		(net "P3V3_AUX_PWRGD")
	)
	(segment
		(start 179.34432 -11.341354)
		(end 179.34432 -10.334244)
		(width 0.17272)
		(layer "F.Cu")
		(net "P3V3_AUX_PWRGD")
	)
	(segment
		(start 178.649884 -11.514328)
		(end 179.171346 -11.514328)
		(width 0.17272)
		(layer "F.Cu")
		(net "P3V3_AUX_PWRGD")
	)
	(segment
		(start 179.34432 -10.334244)
		(end 179.578 -10.100564)
		(width 0.17272)
		(layer "F.Cu")
		(net "P3V3_AUX_PWRGD")
	)
	(segment
		(start 179.578 -10.100564)
		(end 179.578 -8.128)
		(width 0.17272)
		(layer "F.Cu")
		(net "P3V3_AUX_PWRGD")
	)
	(segment
		(start 179.171346 -11.514328)
		(end 179.34432 -11.341354)
		(width 0.17272)
		(layer "F.Cu")
		(net "P3V3_AUX_PWRGD")
	)
	(via
		(at 179.578 -8.128)
		(size 0.508)
		(drill 0.254)
		(layers "F.Cu" "B.Cu")
		(net "P3V3_AUX_PWRGD")
	)
	(via
		(at 180.721 -15.5702)
		(size 0.762)
		(drill 0.381)
		(layers "F.Cu" "B.Cu")
		(net "SW_P3V3_AUX_PH")
	)
	(segment
		(start 178.97094 -9.83488)
		(end 178.74996 -10.05586)
		(width 0.254)
		(layer "F.Cu")
		(net "P3V3_AUX_REF")
	)
	(segment
		(start 178.97094 -9.32053)
		(end 178.97094 -9.83488)
		(width 0.254)
		(layer "F.Cu")
		(net "P3V3_AUX_REF")
	)
	(segment
		(start 178.74996 -10.414)
		(end 178.74996 -11.014202)
		(width 0.254)
		(layer "F.Cu")
		(net "P3V3_AUX_REF")
	)
	(segment
		(start 178.74996 -10.05586)
		(end 178.74996 -10.414)
		(width 0.254)
		(layer "F.Cu")
		(net "P3V3_AUX_REF")
	)
	(via
		(at 178.74996 -10.414)
		(size 0.508)
		(drill 0.254)
		(layers "F.Cu" "B.Cu")
		(net "P3V3_AUX_REF")
	)
	(segment
		(start 178.74996 -13.014198)
		(end 178.74996 -13.745972)
		(width 0.254)
		(layer "F.Cu")
		(net "P3V3_AUX_MODE")
	)
	(segment
		(start 178.74996 -13.745972)
		(end 179.324 -14.320012)
		(width 0.254)
		(layer "F.Cu")
		(net "P3V3_AUX_MODE")
	)
	(segment
		(start 179.324 -14.320012)
		(end 179.324 -14.33195)
		(width 0.254)
		(layer "F.Cu")
		(net "P3V3_AUX_MODE")
	)
	(via
		(at 178.74996 -13.745972)
		(size 0.508)
		(drill 0.254)
		(layers "F.Cu" "B.Cu")
		(net "P3V3_AUX_MODE")
	)
	(segment
		(start 175.641 -10.39495)
		(end 175.641 -10.795)
		(width 0.17272)
		(layer "F.Cu")
		(net "P3V3_AUX_CS")
	)
	(segment
		(start 176.360328 -11.514328)
		(end 176.950116 -11.514328)
		(width 0.17272)
		(layer "F.Cu")
		(net "P3V3_AUX_CS")
	)
	(segment
		(start 175.27905 -10.033)
		(end 175.641 -10.39495)
		(width 0.17272)
		(layer "F.Cu")
		(net "P3V3_AUX_CS")
	)
	(segment
		(start 175.641 -10.795)
		(end 176.360328 -11.514328)
		(width 0.17272)
		(layer "F.Cu")
		(net "P3V3_AUX_CS")
	)
	(segment
		(start 175.27905 -9.271)
		(end 175.27905 -10.033)
		(width 0.17272)
		(layer "F.Cu")
		(net "P3V3_AUX_CS")
	)
	(via
		(at 175.27905 -10.033)
		(size 0.508)
		(drill 0.254)
		(layers "F.Cu" "B.Cu")
		(net "P3V3_AUX_CS")
	)
	(via
		(at 212.471 -76.835)
		(size 0.762)
		(drill 0.254)
		(layers "F.Cu" "B.Cu")
		(net "P12V_BRICK3_ALERT_N")
	)
	(via
		(at 56.24195 -79.502)
		(size 0.508)
		(drill 0.254)
		(layers "F.Cu" "B.Cu")
		(net "P12V_BRICK3_ALERT_N")
	)
	(segment
		(start 212.811106 -77.175106)
		(end 212.811106 -78.994)
		(width 0.17272)
		(layer "B.Cu")
		(net "P12V_BRICK3_ALERT_N")
	)
	(segment
		(start 56.24195 -77.47)
		(end 56.24195 -76.327)
		(width 0.17272)
		(layer "B.Cu")
		(net "P12V_BRICK3_ALERT_N")
	)
	(segment
		(start 212.471 -76.835)
		(end 212.811106 -77.175106)
		(width 0.17272)
		(layer "B.Cu")
		(net "P12V_BRICK3_ALERT_N")
	)
	(segment
		(start 56.24195 -78.613)
		(end 56.24195 -77.47)
		(width 0.17272)
		(layer "B.Cu")
		(net "P12V_BRICK3_ALERT_N")
	)
	(segment
		(start 56.24195 -78.613)
		(end 56.24195 -79.502)
		(width 0.17272)
		(layer "B.Cu")
		(net "P12V_BRICK3_ALERT_N")
	)
	(segment
		(start 183.515762 -78.867)
		(end 184.519062 -77.8637)
		(width 0.12954)
		(layer "In7.Cu")
		(net "P12V_BRICK3_ALERT_N")
	)
	(segment
		(start 194.636136 -77.8637)
		(end 198.898256 -73.60158)
		(width 0.12954)
		(layer "In7.Cu")
		(net "P12V_BRICK3_ALERT_N")
	)
	(segment
		(start 180.975762 -76.962762)
		(end 181.61 -77.597)
		(width 0.12954)
		(layer "In7.Cu")
		(net "P12V_BRICK3_ALERT_N")
	)
	(segment
		(start 181.61 -78.232)
		(end 182.245 -78.867)
		(width 0.12954)
		(layer "In7.Cu")
		(net "P12V_BRICK3_ALERT_N")
	)
	(segment
		(start 57.404 -76.708)
		(end 170.561254 -76.708)
		(width 0.12954)
		(layer "In7.Cu")
		(net "P12V_BRICK3_ALERT_N")
	)
	(segment
		(start 198.898256 -73.60158)
		(end 209.23758 -73.60158)
		(width 0.12954)
		(layer "In7.Cu")
		(net "P12V_BRICK3_ALERT_N")
	)
	(segment
		(start 181.61 -77.597)
		(end 181.61 -78.232)
		(width 0.12954)
		(layer "In7.Cu")
		(net "P12V_BRICK3_ALERT_N")
	)
	(segment
		(start 56.24195 -79.502)
		(end 56.642 -79.10195)
		(width 0.12954)
		(layer "In7.Cu")
		(net "P12V_BRICK3_ALERT_N")
	)
	(segment
		(start 209.23758 -73.60158)
		(end 212.471 -76.835)
		(width 0.12954)
		(layer "In7.Cu")
		(net "P12V_BRICK3_ALERT_N")
	)
	(segment
		(start 184.519062 -77.8637)
		(end 194.636136 -77.8637)
		(width 0.12954)
		(layer "In7.Cu")
		(net "P12V_BRICK3_ALERT_N")
	)
	(segment
		(start 170.561254 -76.708)
		(end 170.816016 -76.962762)
		(width 0.12954)
		(layer "In7.Cu")
		(net "P12V_BRICK3_ALERT_N")
	)
	(segment
		(start 170.816016 -76.962762)
		(end 180.975762 -76.962762)
		(width 0.12954)
		(layer "In7.Cu")
		(net "P12V_BRICK3_ALERT_N")
	)
	(segment
		(start 56.642 -77.47)
		(end 57.404 -76.708)
		(width 0.12954)
		(layer "In7.Cu")
		(net "P12V_BRICK3_ALERT_N")
	)
	(segment
		(start 182.245 -78.867)
		(end 183.515762 -78.867)
		(width 0.12954)
		(layer "In7.Cu")
		(net "P12V_BRICK3_ALERT_N")
	)
	(segment
		(start 56.642 -79.10195)
		(end 56.642 -77.47)
		(width 0.12954)
		(layer "In7.Cu")
		(net "P12V_BRICK3_ALERT_N")
	)
	(segment
		(start 163.97605 -8.382)
		(end 164.591746 -8.382)
		(width 0.17272)
		(layer "F.Cu")
		(net "P12V_BRICK0_PWRGD")
	)
	(segment
		(start 175.87468 -9.74471)
		(end 175.87468 -8.87603)
		(width 0.17272)
		(layer "F.Cu")
		(net "P12V_BRICK0_PWRGD")
	)
	(segment
		(start 175.87468 -8.87603)
		(end 175.27905 -8.2804)
		(width 0.17272)
		(layer "F.Cu")
		(net "P12V_BRICK0_PWRGD")
	)
	(segment
		(start 165.480746 -7.493)
		(end 174.51705 -7.493)
		(width 0.17272)
		(layer "F.Cu")
		(net "P12V_BRICK0_PWRGD")
	)
	(segment
		(start 174.51705 -7.493)
		(end 175.27905 -8.255)
		(width 0.17272)
		(layer "F.Cu")
		(net "P12V_BRICK0_PWRGD")
	)
	(segment
		(start 176.622202 -11.014202)
		(end 176.403 -10.795)
		(width 0.17272)
		(layer "F.Cu")
		(net "P12V_BRICK0_PWRGD")
	)
	(segment
		(start 176.403 -10.287)
		(end 175.895 -9.779)
		(width 0.17272)
		(layer "F.Cu")
		(net "P12V_BRICK0_PWRGD")
	)
	(segment
		(start 164.591746 -8.382)
		(end 165.480746 -7.493)
		(width 0.17272)
		(layer "F.Cu")
		(net "P12V_BRICK0_PWRGD")
	)
	(segment
		(start 176.403 -10.795)
		(end 176.403 -10.287)
		(width 0.17272)
		(layer "F.Cu")
		(net "P12V_BRICK0_PWRGD")
	)
	(segment
		(start 175.27905 -8.2804)
		(end 175.27905 -8.255)
		(width 0.17272)
		(layer "F.Cu")
		(net "P12V_BRICK0_PWRGD")
	)
	(segment
		(start 175.895 -9.779)
		(end 175.895 -9.76503)
		(width 0.17272)
		(layer "F.Cu")
		(net "P12V_BRICK0_PWRGD")
	)
	(segment
		(start 176.85004 -11.014202)
		(end 176.622202 -11.014202)
		(width 0.17272)
		(layer "F.Cu")
		(net "P12V_BRICK0_PWRGD")
	)
	(segment
		(start 175.895 -9.76503)
		(end 175.87468 -9.74471)
		(width 0.17272)
		(layer "F.Cu")
		(net "P12V_BRICK0_PWRGD")
	)
	(via
		(at 131.71805 -75.057)
		(size 0.508)
		(drill 0.254)
		(layers "F.Cu" "B.Cu")
		(net "P12V_BRICK0_PWRGD")
	)
	(via
		(at 218.8464 -77.3684)
		(size 0.508)
		(drill 0.254)
		(layers "F.Cu" "B.Cu")
		(net "P12V_BRICK0_PWRGD")
	)
	(via
		(at 216.0905 -63.6905)
		(size 0.508)
		(drill 0.254)
		(layers "F.Cu" "B.Cu")
		(net "P12V_BRICK0_PWRGD")
	)
	(via
		(at 177.2666 -89.535)
		(size 0.508)
		(drill 0.254)
		(layers "F.Cu" "B.Cu")
		(net "P12V_BRICK0_PWRGD")
	)
	(via
		(at 164.591746 -8.382)
		(size 0.508)
		(drill 0.254)
		(layers "F.Cu" "B.Cu")
		(net "P12V_BRICK0_PWRGD")
	)
	(segment
		(start 108.481876 -114.904012)
		(end 108.481876 -116.205)
		(width 0.17272)
		(layer "B.Cu")
		(net "P12V_BRICK0_PWRGD")
	)
	(segment
		(start 154.8892 -89.535)
		(end 130.5052 -113.919)
		(width 0.17272)
		(layer "B.Cu")
		(net "P12V_BRICK0_PWRGD")
	)
	(segment
		(start 167.830246 -5.1435)
		(end 164.591746 -8.382)
		(width 0.17272)
		(layer "B.Cu")
		(net "P12V_BRICK0_PWRGD")
	)
	(segment
		(start 109.142784 -113.919)
		(end 108.319824 -114.74196)
		(width 0.17272)
		(layer "B.Cu")
		(net "P12V_BRICK0_PWRGD")
	)
	(segment
		(start 216.0905 -63.6905)
		(end 215.20404 -62.80404)
		(width 0.17272)
		(layer "B.Cu")
		(net "P12V_BRICK0_PWRGD")
	)
	(segment
		(start 198.0057 -5.1435)
		(end 167.830246 -5.1435)
		(width 0.17272)
		(layer "B.Cu")
		(net "P12V_BRICK0_PWRGD")
	)
	(segment
		(start 109.732826 -116.22405)
		(end 108.500926 -116.22405)
		(width 0.17272)
		(layer "B.Cu")
		(net "P12V_BRICK0_PWRGD")
	)
	(segment
		(start 199.4154 -6.5532)
		(end 198.0057 -5.1435)
		(width 0.17272)
		(layer "B.Cu")
		(net "P12V_BRICK0_PWRGD")
	)
	(segment
		(start 130.5052 -113.919)
		(end 109.142784 -113.919)
		(width 0.17272)
		(layer "B.Cu")
		(net "P12V_BRICK0_PWRGD")
	)
	(segment
		(start 108.500926 -116.22405)
		(end 108.481876 -116.205)
		(width 0.17272)
		(layer "B.Cu")
		(net "P12V_BRICK0_PWRGD")
	)
	(segment
		(start 213.4362 -46.5074)
		(end 207.7974 -46.5074)
		(width 0.17272)
		(layer "B.Cu")
		(net "P12V_BRICK0_PWRGD")
	)
	(segment
		(start 202.819 -41.529)
		(end 202.819 -20.2692)
		(width 0.17272)
		(layer "B.Cu")
		(net "P12V_BRICK0_PWRGD")
	)
	(segment
		(start 218.8464 -73.594214)
		(end 218.8464 -77.3684)
		(width 0.17272)
		(layer "B.Cu")
		(net "P12V_BRICK0_PWRGD")
	)
	(segment
		(start 108.319824 -114.74196)
		(end 108.481876 -114.904012)
		(width 0.17272)
		(layer "B.Cu")
		(net "P12V_BRICK0_PWRGD")
	)
	(segment
		(start 202.819 -20.2692)
		(end 199.4154 -16.8656)
		(width 0.17272)
		(layer "B.Cu")
		(net "P12V_BRICK0_PWRGD")
	)
	(segment
		(start 177.2666 -89.535)
		(end 154.8892 -89.535)
		(width 0.17272)
		(layer "B.Cu")
		(net "P12V_BRICK0_PWRGD")
	)
	(segment
		(start 221.869 -70.571614)
		(end 218.8464 -73.594214)
		(width 0.17272)
		(layer "B.Cu")
		(net "P12V_BRICK0_PWRGD")
	)
	(segment
		(start 216.0905 -63.6905)
		(end 221.869 -69.469)
		(width 0.17272)
		(layer "B.Cu")
		(net "P12V_BRICK0_PWRGD")
	)
	(segment
		(start 131.71805 -68.737734)
		(end 130.850132 -67.869816)
		(width 0.17272)
		(layer "B.Cu")
		(net "P12V_BRICK0_PWRGD")
	)
	(segment
		(start 221.869 -69.469)
		(end 221.869 -70.571614)
		(width 0.17272)
		(layer "B.Cu")
		(net "P12V_BRICK0_PWRGD")
	)
	(segment
		(start 199.4154 -16.8656)
		(end 199.4154 -6.5532)
		(width 0.17272)
		(layer "B.Cu")
		(net "P12V_BRICK0_PWRGD")
	)
	(segment
		(start 131.71805 -75.057)
		(end 131.71805 -68.737734)
		(width 0.17272)
		(layer "B.Cu")
		(net "P12V_BRICK0_PWRGD")
	)
	(segment
		(start 215.20404 -48.27524)
		(end 213.4362 -46.5074)
		(width 0.17272)
		(layer "B.Cu")
		(net "P12V_BRICK0_PWRGD")
	)
	(segment
		(start 207.7974 -46.5074)
		(end 202.819 -41.529)
		(width 0.17272)
		(layer "B.Cu")
		(net "P12V_BRICK0_PWRGD")
	)
	(segment
		(start 215.20404 -62.80404)
		(end 215.20404 -48.27524)
		(width 0.17272)
		(layer "B.Cu")
		(net "P12V_BRICK0_PWRGD")
	)
	(segment
		(start 208.407 -66.675)
		(end 213.868 -66.675)
		(width 0.12954)
		(layer "In7.Cu")
		(net "P12V_BRICK0_PWRGD")
	)
	(segment
		(start 195.075556 -75.764644)
		(end 198.9582 -71.882)
		(width 0.12954)
		(layer "In7.Cu")
		(net "P12V_BRICK0_PWRGD")
	)
	(segment
		(start 198.9582 -71.882)
		(end 205.105 -71.882)
		(width 0.12954)
		(layer "In7.Cu")
		(net "P12V_BRICK0_PWRGD")
	)
	(segment
		(start 214.249 -66.294)
		(end 214.249 -65.532)
		(width 0.12954)
		(layer "In7.Cu")
		(net "P12V_BRICK0_PWRGD")
	)
	(segment
		(start 206.756 -70.231)
		(end 206.756 -68.326)
		(width 0.12954)
		(layer "In7.Cu")
		(net "P12V_BRICK0_PWRGD")
	)
	(segment
		(start 216.1286 -76.3016)
		(end 217.7796 -76.3016)
		(width 0.12954)
		(layer "In7.Cu")
		(net "P12V_BRICK0_PWRGD")
	)
	(segment
		(start 177.2666 -89.535)
		(end 178.9684 -87.8332)
		(width 0.12954)
		(layer "In7.Cu")
		(net "P12V_BRICK0_PWRGD")
	)
	(segment
		(start 205.74 -79.9084)
		(end 206.9592 -78.6892)
		(width 0.12954)
		(layer "In7.Cu")
		(net "P12V_BRICK0_PWRGD")
	)
	(segment
		(start 198.323454 -79.9084)
		(end 205.74 -79.9084)
		(width 0.12954)
		(layer "In7.Cu")
		(net "P12V_BRICK0_PWRGD")
	)
	(segment
		(start 214.249 -65.532)
		(end 216.0905 -63.6905)
		(width 0.12954)
		(layer "In7.Cu")
		(net "P12V_BRICK0_PWRGD")
	)
	(segment
		(start 206.9592 -78.6892)
		(end 213.741 -78.6892)
		(width 0.12954)
		(layer "In7.Cu")
		(net "P12V_BRICK0_PWRGD")
	)
	(segment
		(start 205.105 -71.882)
		(end 206.756 -70.231)
		(width 0.12954)
		(layer "In7.Cu")
		(net "P12V_BRICK0_PWRGD")
	)
	(segment
		(start 173.101 -75.764644)
		(end 195.075556 -75.764644)
		(width 0.12954)
		(layer "In7.Cu")
		(net "P12V_BRICK0_PWRGD")
	)
	(segment
		(start 217.7796 -76.3016)
		(end 218.8464 -77.3684)
		(width 0.12954)
		(layer "In7.Cu")
		(net "P12V_BRICK0_PWRGD")
	)
	(segment
		(start 213.868 -66.675)
		(end 214.249 -66.294)
		(width 0.12954)
		(layer "In7.Cu")
		(net "P12V_BRICK0_PWRGD")
	)
	(segment
		(start 206.756 -68.326)
		(end 208.407 -66.675)
		(width 0.12954)
		(layer "In7.Cu")
		(net "P12V_BRICK0_PWRGD")
	)
	(segment
		(start 213.741 -78.6892)
		(end 216.1286 -76.3016)
		(width 0.12954)
		(layer "In7.Cu")
		(net "P12V_BRICK0_PWRGD")
	)
	(segment
		(start 131.71805 -75.057)
		(end 172.393356 -75.057)
		(width 0.12954)
		(layer "In7.Cu")
		(net "P12V_BRICK0_PWRGD")
	)
	(segment
		(start 178.9684 -87.8332)
		(end 190.398654 -87.8332)
		(width 0.12954)
		(layer "In7.Cu")
		(net "P12V_BRICK0_PWRGD")
	)
	(segment
		(start 172.393356 -75.057)
		(end 173.101 -75.764644)
		(width 0.12954)
		(layer "In7.Cu")
		(net "P12V_BRICK0_PWRGD")
	)
	(segment
		(start 190.398654 -87.8332)
		(end 198.323454 -79.9084)
		(width 0.12954)
		(layer "In7.Cu")
		(net "P12V_BRICK0_PWRGD")
	)
	(via
		(at 153.8224 -113.905284)
		(size 0.6604)
		(drill 0.3302)
		(layers "F.Cu" "B.Cu")
		(net "BRICK_P12V_1_EN_N")
	)
	(segment
		(start 179.832 -92.075)
		(end 158.115 -92.075)
		(width 0.17272)
		(layer "B.Cu")
		(net "BRICK_P12V_1_EN_N")
	)
	(segment
		(start 154.87015 -115.67795)
		(end 176.850294 -115.67795)
		(width 0.17272)
		(layer "B.Cu")
		(net "BRICK_P12V_1_EN_N")
	)
	(segment
		(start 104.652826 -114.44605)
		(end 103.9876 -113.780824)
		(width 0.17272)
		(layer "B.Cu")
		(net "BRICK_P12V_1_EN_N")
	)
	(segment
		(start 134.239254 -107.0356)
		(end 153.238454 -88.0364)
		(width 0.17272)
		(layer "B.Cu")
		(net "BRICK_P12V_1_EN_N")
	)
	(segment
		(start 96.849946 -114.44605)
		(end 96.849946 -115.67795)
		(width 0.17272)
		(layer "B.Cu")
		(net "BRICK_P12V_1_EN_N")
	)
	(segment
		(start 104.652826 -114.44605)
		(end 105.922826 -114.44605)
		(width 0.17272)
		(layer "B.Cu")
		(net "BRICK_P12V_1_EN_N")
	)
	(segment
		(start 178.5112 -88.0364)
		(end 180.467 -89.9922)
		(width 0.17272)
		(layer "B.Cu")
		(net "BRICK_P12V_1_EN_N")
	)
	(segment
		(start 56.850026 -115.67795)
		(end 56.850026 -114.44605)
		(width 0.17272)
		(layer "B.Cu")
		(net "BRICK_P12V_1_EN_N")
	)
	(segment
		(start 153.8224 -113.905284)
		(end 153.8224 -114.6302)
		(width 0.17272)
		(layer "B.Cu")
		(net "BRICK_P12V_1_EN_N")
	)
	(segment
		(start 176.850294 -114.44605)
		(end 176.850294 -115.67795)
		(width 0.17272)
		(layer "B.Cu")
		(net "BRICK_P12V_1_EN_N")
	)
	(segment
		(start 180.467 -91.44)
		(end 179.832 -92.075)
		(width 0.17272)
		(layer "B.Cu")
		(net "BRICK_P12V_1_EN_N")
	)
	(segment
		(start 153.8224 -96.3676)
		(end 153.8224 -113.905284)
		(width 0.17272)
		(layer "B.Cu")
		(net "BRICK_P12V_1_EN_N")
	)
	(segment
		(start 158.115 -92.075)
		(end 153.8224 -96.3676)
		(width 0.17272)
		(layer "B.Cu")
		(net "BRICK_P12V_1_EN_N")
	)
	(segment
		(start 96.849946 -114.44605)
		(end 96.826578 -114.422682)
		(width 0.17272)
		(layer "B.Cu")
		(net "BRICK_P12V_1_EN_N")
	)
	(segment
		(start 96.849946 -114.44605)
		(end 104.652826 -114.44605)
		(width 0.17272)
		(layer "B.Cu")
		(net "BRICK_P12V_1_EN_N")
	)
	(segment
		(start 153.8224 -114.6302)
		(end 154.87015 -115.67795)
		(width 0.17272)
		(layer "B.Cu")
		(net "BRICK_P12V_1_EN_N")
	)
	(segment
		(start 96.826578 -114.422682)
		(end 56.873394 -114.422682)
		(width 0.17272)
		(layer "B.Cu")
		(net "BRICK_P12V_1_EN_N")
	)
	(segment
		(start 105.922826 -114.44605)
		(end 107.681776 -116.205)
		(width 0.17272)
		(layer "B.Cu")
		(net "BRICK_P12V_1_EN_N")
	)
	(segment
		(start 107.45724 -107.0356)
		(end 134.239254 -107.0356)
		(width 0.17272)
		(layer "B.Cu")
		(net "BRICK_P12V_1_EN_N")
	)
	(segment
		(start 153.238454 -88.0364)
		(end 178.5112 -88.0364)
		(width 0.17272)
		(layer "B.Cu")
		(net "BRICK_P12V_1_EN_N")
	)
	(segment
		(start 103.9876 -110.50524)
		(end 107.45724 -107.0356)
		(width 0.17272)
		(layer "B.Cu")
		(net "BRICK_P12V_1_EN_N")
	)
	(segment
		(start 56.873394 -114.422682)
		(end 56.850026 -114.44605)
		(width 0.17272)
		(layer "B.Cu")
		(net "BRICK_P12V_1_EN_N")
	)
	(segment
		(start 180.467 -89.9922)
		(end 180.467 -91.44)
		(width 0.17272)
		(layer "B.Cu")
		(net "BRICK_P12V_1_EN_N")
	)
	(segment
		(start 103.9876 -113.780824)
		(end 103.9876 -110.50524)
		(width 0.17272)
		(layer "B.Cu")
		(net "BRICK_P12V_1_EN_N")
	)
	(segment
		(start 60.850018 -76.30795)
		(end 60.850018 -67.869816)
		(width 0.17272)
		(layer "B.Cu")
		(net "BRICK3_PMBADD")
	)
	(via
		(at 107.084876 -111.34344)
		(size 0.6604)
		(drill 0.3302)
		(layers "F.Cu" "B.Cu")
		(net "BRICK_P12V_EN_R_N")
	)
	(segment
		(start 107.084876 -113.026952)
		(end 106.319828 -113.792)
		(width 0.17272)
		(layer "B.Cu")
		(net "BRICK_P12V_EN_R_N")
	)
	(segment
		(start 106.173778 -113.64595)
		(end 104.652826 -113.64595)
		(width 0.17272)
		(layer "B.Cu")
		(net "BRICK_P12V_EN_R_N")
	)
	(segment
		(start 107.084876 -111.34344)
		(end 107.084876 -113.026952)
		(width 0.17272)
		(layer "B.Cu")
		(net "BRICK_P12V_EN_R_N")
	)
	(segment
		(start 106.319828 -113.792)
		(end 106.173778 -113.64595)
		(width 0.17272)
		(layer "B.Cu")
		(net "BRICK_P12V_EN_R_N")
	)
	(segment
		(start 107.084876 -110.109)
		(end 107.084876 -111.34344)
		(width 0.17272)
		(layer "B.Cu")
		(net "BRICK_P12V_EN_R_N")
	)
	(via
		(at 213.88705 -40.366696)
		(size 0.6604)
		(drill 0.3302)
		(layers "F.Cu" "B.Cu")
		(net "TP_J1_A1")
	)
	(segment
		(start 211.469986 -37.949632)
		(end 213.88705 -40.366696)
		(width 0.17272)
		(layer "B.Cu")
		(net "TP_J1_A1")
	)
	(via
		(at 228.219 -72.564244)
		(size 0.6604)
		(drill 0.3302)
		(layers "F.Cu" "B.Cu")
		(net "P12V_BRICK_PWRGD_N")
	)
	(segment
		(start 228.219 -74.786998)
		(end 228.075998 -74.93)
		(width 0.17272)
		(layer "B.Cu")
		(net "P12V_BRICK_PWRGD_N")
	)
	(segment
		(start 228.219 -71.39305)
		(end 228.219 -72.564244)
		(width 0.17272)
		(layer "B.Cu")
		(net "P12V_BRICK_PWRGD_N")
	)
	(segment
		(start 228.219 -72.564244)
		(end 228.219 -74.786998)
		(width 0.17272)
		(layer "B.Cu")
		(net "P12V_BRICK_PWRGD_N")
	)
	(segment
		(start 42.17416 -60.649358)
		(end 42.181272 -60.642246)
		(width 0.17272)
		(layer "F.Cu")
		(net "P12V_HPDB_PWRGD")
	)
	(segment
		(start 42.181272 -59.854846)
		(end 42.181272 -60.642246)
		(width 0.17272)
		(layer "F.Cu")
		(net "P12V_HPDB_PWRGD")
	)
	(segment
		(start 42.17416 -61.53277)
		(end 42.17416 -60.649358)
		(width 0.17272)
		(layer "F.Cu")
		(net "P12V_HPDB_PWRGD")
	)
	(via
		(at 42.181272 -60.642246)
		(size 0.508)
		(drill 0.254)
		(layers "F.Cu" "B.Cu")
		(net "P12V_HPDB_PWRGD")
	)
	(via
		(at 202.7936 -82.2706)
		(size 0.508)
		(drill 0.254)
		(layers "F.Cu" "B.Cu")
		(net "P12V_HPDB_PWRGD")
	)
	(via
		(at 40.9956 -82.0928)
		(size 0.508)
		(drill 0.254)
		(layers "F.Cu" "B.Cu")
		(net "P12V_HPDB_PWRGD")
	)
	(via
		(at 216.662 -77.089)
		(size 0.508)
		(drill 0.254)
		(layers "F.Cu" "B.Cu")
		(net "P12V_HPDB_PWRGD")
	)
	(segment
		(start 192.160652 -80.67548)
		(end 193.392552 -81.90738)
		(width 0.17272)
		(layer "B.Cu")
		(net "P12V_HPDB_PWRGD")
	)
	(segment
		(start 151.303736 -82.20964)
		(end 182.668164 -82.20964)
		(width 0.17272)
		(layer "B.Cu")
		(net "P12V_HPDB_PWRGD")
	)
	(segment
		(start 17.8054 -81.6102)
		(end 14.7574 -81.6102)
		(width 0.17272)
		(layer "B.Cu")
		(net "P12V_HPDB_PWRGD")
	)
	(segment
		(start 193.392552 -81.90738)
		(end 199.000618 -81.90738)
		(width 0.17272)
		(layer "B.Cu")
		(net "P12V_HPDB_PWRGD")
	)
	(segment
		(start 35.418014 -84.64296)
		(end 20.83816 -84.64296)
		(width 0.17272)
		(layer "B.Cu")
		(net "P12V_HPDB_PWRGD")
	)
	(segment
		(start 20.83816 -84.64296)
		(end 17.8054 -81.6102)
		(width 0.17272)
		(layer "B.Cu")
		(net "P12V_HPDB_PWRGD")
	)
	(segment
		(start 148.616416 -84.89696)
		(end 151.303736 -82.20964)
		(width 0.17272)
		(layer "B.Cu")
		(net "P12V_HPDB_PWRGD")
	)
	(segment
		(start 14.7574 -81.6102)
		(end 13.087096 -79.939896)
		(width 0.17272)
		(layer "B.Cu")
		(net "P12V_HPDB_PWRGD")
	)
	(segment
		(start 37.968174 -82.0928)
		(end 35.418014 -84.64296)
		(width 0.17272)
		(layer "B.Cu")
		(net "P12V_HPDB_PWRGD")
	)
	(segment
		(start 40.9956 -82.0928)
		(end 37.968174 -82.0928)
		(width 0.17272)
		(layer "B.Cu")
		(net "P12V_HPDB_PWRGD")
	)
	(segment
		(start 199.000618 -81.90738)
		(end 199.851518 -82.75828)
		(width 0.17272)
		(layer "B.Cu")
		(net "P12V_HPDB_PWRGD")
	)
	(segment
		(start 184.202324 -80.67548)
		(end 192.160652 -80.67548)
		(width 0.17272)
		(layer "B.Cu")
		(net "P12V_HPDB_PWRGD")
	)
	(segment
		(start 182.668164 -82.20964)
		(end 184.202324 -80.67548)
		(width 0.17272)
		(layer "B.Cu")
		(net "P12V_HPDB_PWRGD")
	)
	(segment
		(start 43.561 -82.0928)
		(end 46.36516 -84.89696)
		(width 0.17272)
		(layer "B.Cu")
		(net "P12V_HPDB_PWRGD")
	)
	(segment
		(start 40.9956 -82.0928)
		(end 43.561 -82.0928)
		(width 0.17272)
		(layer "B.Cu")
		(net "P12V_HPDB_PWRGD")
	)
	(segment
		(start 202.30592 -82.75828)
		(end 202.7936 -82.2706)
		(width 0.17272)
		(layer "B.Cu")
		(net "P12V_HPDB_PWRGD")
	)
	(segment
		(start 13.087096 -79.939896)
		(end 11.12012 -79.939896)
		(width 0.17272)
		(layer "B.Cu")
		(net "P12V_HPDB_PWRGD")
	)
	(segment
		(start 214.761064 -77.719936)
		(end 215.392 -77.089)
		(width 0.17272)
		(layer "B.Cu")
		(net "P12V_HPDB_PWRGD")
	)
	(segment
		(start 215.392 -77.089)
		(end 216.662 -77.089)
		(width 0.17272)
		(layer "B.Cu")
		(net "P12V_HPDB_PWRGD")
	)
	(segment
		(start 46.36516 -84.89696)
		(end 148.616416 -84.89696)
		(width 0.17272)
		(layer "B.Cu")
		(net "P12V_HPDB_PWRGD")
	)
	(segment
		(start 199.851518 -82.75828)
		(end 202.30592 -82.75828)
		(width 0.17272)
		(layer "B.Cu")
		(net "P12V_HPDB_PWRGD")
	)
	(segment
		(start 214.761064 -78.994)
		(end 214.761064 -77.719936)
		(width 0.17272)
		(layer "B.Cu")
		(net "P12V_HPDB_PWRGD")
	)
	(segment
		(start 40.9956 -62.992254)
		(end 42.181272 -61.806582)
		(width 0.12954)
		(layer "In2.Cu")
		(net "P12V_HPDB_PWRGD")
	)
	(segment
		(start 42.181272 -61.806582)
		(end 42.181272 -60.642246)
		(width 0.12954)
		(layer "In2.Cu")
		(net "P12V_HPDB_PWRGD")
	)
	(segment
		(start 40.9956 -82.0928)
		(end 40.9956 -62.992254)
		(width 0.12954)
		(layer "In2.Cu")
		(net "P12V_HPDB_PWRGD")
	)
	(segment
		(start 214.6046 -79.7052)
		(end 216.662 -77.6478)
		(width 0.12954)
		(layer "In7.Cu")
		(net "P12V_HPDB_PWRGD")
	)
	(segment
		(start 204.40142 -80.66278)
		(end 206.763874 -80.66278)
		(width 0.12954)
		(layer "In7.Cu")
		(net "P12V_HPDB_PWRGD")
	)
	(segment
		(start 216.662 -77.6478)
		(end 216.662 -77.089)
		(width 0.12954)
		(layer "In7.Cu")
		(net "P12V_HPDB_PWRGD")
	)
	(segment
		(start 207.721454 -79.7052)
		(end 214.6046 -79.7052)
		(width 0.12954)
		(layer "In7.Cu")
		(net "P12V_HPDB_PWRGD")
	)
	(segment
		(start 206.763874 -80.66278)
		(end 207.721454 -79.7052)
		(width 0.12954)
		(layer "In7.Cu")
		(net "P12V_HPDB_PWRGD")
	)
	(segment
		(start 202.7936 -82.2706)
		(end 204.40142 -80.66278)
		(width 0.12954)
		(layer "In7.Cu")
		(net "P12V_HPDB_PWRGD")
	)
	(segment
		(start 35.15995 -58.980832)
		(end 35.15995 -61.917072)
		(width 0.254)
		(layer "F.Cu")
		(net "P12V_HPDB")
	)
	(segment
		(start 35.15995 -58.980832)
		(end 35.310572 -58.83021)
		(width 0.254)
		(layer "F.Cu")
		(net "P12V_HPDB")
	)
	(segment
		(start 35.15995 -61.917072)
		(end 36.792662 -63.549784)
		(width 0.254)
		(layer "F.Cu")
		(net "P12V_HPDB")
	)
	(segment
		(start 40.113204 -63.549784)
		(end 40.381428 -63.28156)
		(width 0.254)
		(layer "F.Cu")
		(net "P12V_HPDB")
	)
	(segment
		(start 36.792662 -63.549784)
		(end 40.113204 -63.549784)
		(width 0.254)
		(layer "F.Cu")
		(net "P12V_HPDB")
	)
	(via
		(at 36.8046 -57.023)
		(size 0.762)
		(drill 0.381)
		(layers "F.Cu" "B.Cu")
		(net "P12V_HPDB")
	)
	(via
		(at 28.3464 -64.91224)
		(size 0.508)
		(drill 0.254)
		(layers "F.Cu" "B.Cu")
		(net "P12V_HPDB")
	)
	(via
		(at 25.35174 -74.76998)
		(size 0.762)
		(drill 0.381)
		(layers "F.Cu" "B.Cu")
		(net "P12V_HPDB")
	)
	(via
		(at 27.5844 -66.43624)
		(size 0.508)
		(drill 0.254)
		(layers "F.Cu" "B.Cu")
		(net "P12V_HPDB")
	)
	(via
		(at 38.692836 -57.547002)
		(size 0.508)
		(drill 0.254)
		(layers "F.Cu" "B.Cu")
		(net "P12V_HPDB")
	)
	(via
		(at 39.378636 -57.039002)
		(size 0.508)
		(drill 0.254)
		(layers "F.Cu" "B.Cu")
		(net "P12V_HPDB")
	)
	(via
		(at 21.59 -78.05674)
		(size 0.762)
		(drill 0.381)
		(layers "F.Cu" "B.Cu")
		(net "P12V_HPDB")
	)
	(via
		(at 23.39594 -76.4286)
		(size 0.762)
		(drill 0.381)
		(layers "F.Cu" "B.Cu")
		(net "P12V_HPDB")
	)
	(via
		(at 28.3464 -66.43624)
		(size 0.508)
		(drill 0.254)
		(layers "F.Cu" "B.Cu")
		(net "P12V_HPDB")
	)
	(via
		(at 26.98242 -73.1393)
		(size 0.762)
		(drill 0.381)
		(layers "F.Cu" "B.Cu")
		(net "P12V_HPDB")
	)
	(via
		(at 38.692836 -56.658002)
		(size 0.508)
		(drill 0.254)
		(layers "F.Cu" "B.Cu")
		(net "P12V_HPDB")
	)
	(via
		(at 27.5844 -65.67424)
		(size 0.508)
		(drill 0.254)
		(layers "F.Cu" "B.Cu")
		(net "P12V_HPDB")
	)
	(via
		(at 38.692836 -58.436002)
		(size 0.508)
		(drill 0.254)
		(layers "F.Cu" "B.Cu")
		(net "P12V_HPDB")
	)
	(via
		(at 28.3464 -65.67424)
		(size 0.508)
		(drill 0.254)
		(layers "F.Cu" "B.Cu")
		(net "P12V_HPDB")
	)
	(via
		(at 39.378636 -57.928002)
		(size 0.508)
		(drill 0.254)
		(layers "F.Cu" "B.Cu")
		(net "P12V_HPDB")
	)
	(via
		(at 19.75358 -79.74584)
		(size 0.762)
		(drill 0.381)
		(layers "F.Cu" "B.Cu")
		(net "P12V_HPDB")
	)
	(via
		(at 27.5844 -64.91224)
		(size 0.508)
		(drill 0.254)
		(layers "F.Cu" "B.Cu")
		(net "P12V_HPDB")
	)
	(via
		(at 39.378636 -58.817002)
		(size 0.508)
		(drill 0.254)
		(layers "F.Cu" "B.Cu")
		(net "P12V_HPDB")
	)
	(via
		(at 38.261036 -55.642002)
		(size 0.508)
		(drill 0.254)
		(layers "F.Cu" "B.Cu")
		(net "P12V_HPDB")
	)
	(segment
		(start 62.850014 -76.30795)
		(end 61.8744 -75.332336)
		(width 0.4572)
		(layer "B.Cu")
		(net "P12V_MB3_SENSE+")
	)
	(segment
		(start 61.8744 -75.332336)
		(end 61.8744 -68.84543)
		(width 0.4572)
		(layer "B.Cu")
		(net "P12V_MB3_SENSE+")
	)
	(segment
		(start 63.881 -76.30795)
		(end 62.850014 -76.30795)
		(width 0.4572)
		(layer "B.Cu")
		(net "P12V_MB3_SENSE+")
	)
	(segment
		(start 61.8744 -68.84543)
		(end 62.850014 -67.869816)
		(width 0.4572)
		(layer "B.Cu")
		(net "P12V_MB3_SENSE+")
	)
	(segment
		(start 172.850302 -67.869816)
		(end 172.850302 -76.30795)
		(width 0.4572)
		(layer "B.Cu")
		(net "P12V_MB2_SENSE-")
	)
	(segment
		(start 175.133 -76.087224)
		(end 175.133 -73.923144)
		(width 0.17272)
		(layer "B.Cu")
		(net "SMB_BRICK2_SDA")
	)
	(segment
		(start 175.133 -73.923144)
		(end 174.893224 -73.683368)
		(width 0.17272)
		(layer "B.Cu")
		(net "SMB_BRICK2_SDA")
	)
	(segment
		(start 174.893224 -73.683368)
		(end 174.893224 -67.912742)
		(width 0.17272)
		(layer "B.Cu")
		(net "SMB_BRICK2_SDA")
	)
	(segment
		(start 174.893224 -67.912742)
		(end 174.850298 -67.869816)
		(width 0.17272)
		(layer "B.Cu")
		(net "SMB_BRICK2_SDA")
	)
	(segment
		(start 174.893224 -76.327)
		(end 175.133 -76.087224)
		(width 0.17272)
		(layer "B.Cu")
		(net "SMB_BRICK2_SDA")
	)
	(segment
		(start 180.071776 -72.667876)
		(end 179.04968 -72.667876)
		(width 0.17272)
		(layer "B.Cu")
		(net "SMB_BRICK2_SCL")
	)
	(segment
		(start 178.85029 -67.869816)
		(end 178.85029 -70.426326)
		(width 0.17272)
		(layer "B.Cu")
		(net "SMB_BRICK2_SCL")
	)
	(segment
		(start 179.04968 -73.348596)
		(end 180.071776 -73.348596)
		(width 0.17272)
		(layer "B.Cu")
		(net "SMB_BRICK2_SCL")
	)
	(segment
		(start 179.04968 -74.029316)
		(end 178.85029 -74.228706)
		(width 0.17272)
		(layer "B.Cu")
		(net "SMB_BRICK2_SCL")
	)
	(segment
		(start 179.04968 -71.306436)
		(end 178.85029 -71.505826)
		(width 0.17272)
		(layer "B.Cu")
		(net "SMB_BRICK2_SCL")
	)
	(segment
		(start 180.271166 -73.547986)
		(end 180.271166 -73.829926)
		(width 0.17272)
		(layer "B.Cu")
		(net "SMB_BRICK2_SCL")
	)
	(segment
		(start 180.071776 -74.029316)
		(end 179.04968 -74.029316)
		(width 0.17272)
		(layer "B.Cu")
		(net "SMB_BRICK2_SCL")
	)
	(segment
		(start 180.071776 -73.348596)
		(end 180.271166 -73.547986)
		(width 0.17272)
		(layer "B.Cu")
		(net "SMB_BRICK2_SCL")
	)
	(segment
		(start 180.071776 -71.306436)
		(end 179.04968 -71.306436)
		(width 0.17272)
		(layer "B.Cu")
		(net "SMB_BRICK2_SCL")
	)
	(segment
		(start 179.04968 -72.667876)
		(end 178.85029 -72.867266)
		(width 0.17272)
		(layer "B.Cu")
		(net "SMB_BRICK2_SCL")
	)
	(segment
		(start 180.271166 -70.825106)
		(end 180.271166 -71.107046)
		(width 0.17272)
		(layer "B.Cu")
		(net "SMB_BRICK2_SCL")
	)
	(segment
		(start 178.85029 -75.34529)
		(end 179.465224 -75.960224)
		(width 0.17272)
		(layer "B.Cu")
		(net "SMB_BRICK2_SCL")
	)
	(segment
		(start 180.271166 -72.186546)
		(end 180.271166 -72.468486)
		(width 0.17272)
		(layer "B.Cu")
		(net "SMB_BRICK2_SCL")
	)
	(segment
		(start 179.04968 -71.987156)
		(end 180.071776 -71.987156)
		(width 0.17272)
		(layer "B.Cu")
		(net "SMB_BRICK2_SCL")
	)
	(segment
		(start 180.271166 -73.829926)
		(end 180.071776 -74.029316)
		(width 0.17272)
		(layer "B.Cu")
		(net "SMB_BRICK2_SCL")
	)
	(segment
		(start 180.071776 -71.987156)
		(end 180.271166 -72.186546)
		(width 0.17272)
		(layer "B.Cu")
		(net "SMB_BRICK2_SCL")
	)
	(segment
		(start 180.271166 -71.107046)
		(end 180.071776 -71.306436)
		(width 0.17272)
		(layer "B.Cu")
		(net "SMB_BRICK2_SCL")
	)
	(segment
		(start 178.85029 -73.149206)
		(end 179.04968 -73.348596)
		(width 0.17272)
		(layer "B.Cu")
		(net "SMB_BRICK2_SCL")
	)
	(segment
		(start 180.071776 -70.625716)
		(end 180.271166 -70.825106)
		(width 0.17272)
		(layer "B.Cu")
		(net "SMB_BRICK2_SCL")
	)
	(segment
		(start 178.85029 -71.787766)
		(end 179.04968 -71.987156)
		(width 0.17272)
		(layer "B.Cu")
		(net "SMB_BRICK2_SCL")
	)
	(segment
		(start 178.85029 -72.867266)
		(end 178.85029 -73.149206)
		(width 0.17272)
		(layer "B.Cu")
		(net "SMB_BRICK2_SCL")
	)
	(segment
		(start 179.04968 -70.625716)
		(end 180.071776 -70.625716)
		(width 0.17272)
		(layer "B.Cu")
		(net "SMB_BRICK2_SCL")
	)
	(segment
		(start 179.465224 -75.960224)
		(end 179.465224 -76.327)
		(width 0.17272)
		(layer "B.Cu")
		(net "SMB_BRICK2_SCL")
	)
	(segment
		(start 180.271166 -72.468486)
		(end 180.071776 -72.667876)
		(width 0.17272)
		(layer "B.Cu")
		(net "SMB_BRICK2_SCL")
	)
	(segment
		(start 178.85029 -70.426326)
		(end 179.04968 -70.625716)
		(width 0.17272)
		(layer "B.Cu")
		(net "SMB_BRICK2_SCL")
	)
	(segment
		(start 178.85029 -71.505826)
		(end 178.85029 -71.787766)
		(width 0.17272)
		(layer "B.Cu")
		(net "SMB_BRICK2_SCL")
	)
	(segment
		(start 178.85029 -74.228706)
		(end 178.85029 -75.34529)
		(width 0.17272)
		(layer "B.Cu")
		(net "SMB_BRICK2_SCL")
	)
	(segment
		(start 180.850286 -76.30795)
		(end 180.850286 -67.869816)
		(width 0.17272)
		(layer "B.Cu")
		(net "BRICK2_PMBADD")
	)
	(segment
		(start 176.850294 -116.47805)
		(end 176.850294 -121.209816)
		(width 0.17272)
		(layer "B.Cu")
		(net "BRICK_P12V2_ON_OFF_R")
	)
	(segment
		(start 176.850294 -74.493374)
		(end 177.179224 -74.822304)
		(width 0.17272)
		(layer "B.Cu")
		(net "SMB_BRICK2_ALERT")
	)
	(segment
		(start 176.850294 -67.869816)
		(end 176.850294 -74.493374)
		(width 0.17272)
		(layer "B.Cu")
		(net "SMB_BRICK2_ALERT")
	)
	(segment
		(start 177.179224 -74.822304)
		(end 177.179224 -76.327)
		(width 0.17272)
		(layer "B.Cu")
		(net "SMB_BRICK2_ALERT")
	)
	(via
		(at 230.078026 -76.916026)
		(size 0.6604)
		(drill 0.3302)
		(layers "F.Cu" "B.Cu")
		(net "FM_U5_VCC")
	)
	(segment
		(start 230.078026 -76.916026)
		(end 229.743 -76.581)
		(width 0.17272)
		(layer "B.Cu")
		(net "FM_U5_VCC")
	)
	(segment
		(start 229.743 -76.581)
		(end 229.743 -75.58405)
		(width 0.17272)
		(layer "B.Cu")
		(net "FM_U5_VCC")
	)
	(segment
		(start 230.759 -78.55204)
		(end 230.759 -77.597)
		(width 0.17272)
		(layer "B.Cu")
		(net "FM_U5_VCC")
	)
	(segment
		(start 230.759 -77.597)
		(end 230.078026 -76.916026)
		(width 0.17272)
		(layer "B.Cu")
		(net "FM_U5_VCC")
	)
	(via
		(at 17.374362 -82.2198)
		(size 0.6604)
		(drill 0.3302)
		(layers "F.Cu" "B.Cu")
		(net "PWRGD_GPU_HSC")
	)
	(segment
		(start 211.94395 -83.312)
		(end 211.94395 -82.169)
		(width 0.17272)
		(layer "B.Cu")
		(net "PWRGD_GPU_HSC")
	)
	(segment
		(start 211.94395 -84.455)
		(end 211.94395 -83.312)
		(width 0.17272)
		(layer "B.Cu")
		(net "PWRGD_GPU_HSC")
	)
	(segment
		(start 20.275042 -85.12048)
		(end 17.374362 -82.2198)
		(width 0.17272)
		(layer "B.Cu")
		(net "PWRGD_GPU_HSC")
	)
	(segment
		(start 199.542146 -83.2358)
		(end 198.691246 -82.3849)
		(width 0.17272)
		(layer "B.Cu")
		(net "PWRGD_GPU_HSC")
	)
	(segment
		(start 198.691246 -82.3849)
		(end 193.194686 -82.3849)
		(width 0.17272)
		(layer "B.Cu")
		(net "PWRGD_GPU_HSC")
	)
	(segment
		(start 184.40019 -81.153)
		(end 182.86603 -82.68716)
		(width 0.17272)
		(layer "B.Cu")
		(net "PWRGD_GPU_HSC")
	)
	(segment
		(start 211.074 -84.455)
		(end 211.94395 -84.455)
		(width 0.17272)
		(layer "B.Cu")
		(net "PWRGD_GPU_HSC")
	)
	(segment
		(start 182.86603 -82.68716)
		(end 151.501602 -82.68716)
		(width 0.17272)
		(layer "B.Cu")
		(net "PWRGD_GPU_HSC")
	)
	(segment
		(start 205.994 -84.201)
		(end 205.0288 -83.2358)
		(width 0.17272)
		(layer "B.Cu")
		(net "PWRGD_GPU_HSC")
	)
	(segment
		(start 35.61588 -85.12048)
		(end 20.275042 -85.12048)
		(width 0.17272)
		(layer "B.Cu")
		(net "PWRGD_GPU_HSC")
	)
	(segment
		(start 46.167294 -85.37448)
		(end 43.596814 -82.804)
		(width 0.17272)
		(layer "B.Cu")
		(net "PWRGD_GPU_HSC")
	)
	(segment
		(start 193.194686 -82.3849)
		(end 191.962786 -81.153)
		(width 0.17272)
		(layer "B.Cu")
		(net "PWRGD_GPU_HSC")
	)
	(segment
		(start 17.374362 -82.2198)
		(end 12.1158 -82.2198)
		(width 0.17272)
		(layer "B.Cu")
		(net "PWRGD_GPU_HSC")
	)
	(segment
		(start 191.962786 -81.153)
		(end 184.40019 -81.153)
		(width 0.17272)
		(layer "B.Cu")
		(net "PWRGD_GPU_HSC")
	)
	(segment
		(start 11.43 -81.534)
		(end 10.795 -81.534)
		(width 0.17272)
		(layer "B.Cu")
		(net "PWRGD_GPU_HSC")
	)
	(segment
		(start 12.1158 -82.2198)
		(end 11.43 -81.534)
		(width 0.17272)
		(layer "B.Cu")
		(net "PWRGD_GPU_HSC")
	)
	(segment
		(start 151.501602 -82.68716)
		(end 148.814282 -85.37448)
		(width 0.17272)
		(layer "B.Cu")
		(net "PWRGD_GPU_HSC")
	)
	(segment
		(start 210.07705 -84.836)
		(end 209.44205 -84.201)
		(width 0.17272)
		(layer "B.Cu")
		(net "PWRGD_GPU_HSC")
	)
	(segment
		(start 205.0288 -83.2358)
		(end 199.542146 -83.2358)
		(width 0.17272)
		(layer "B.Cu")
		(net "PWRGD_GPU_HSC")
	)
	(segment
		(start 37.93236 -82.804)
		(end 35.61588 -85.12048)
		(width 0.17272)
		(layer "B.Cu")
		(net "PWRGD_GPU_HSC")
	)
	(segment
		(start 9.85012 -82.47888)
		(end 9.85012 -83.749896)
		(width 0.17272)
		(layer "B.Cu")
		(net "PWRGD_GPU_HSC")
	)
	(segment
		(start 210.693 -84.836)
		(end 211.074 -84.455)
		(width 0.17272)
		(layer "B.Cu")
		(net "PWRGD_GPU_HSC")
	)
	(segment
		(start 210.07705 -84.836)
		(end 210.693 -84.836)
		(width 0.17272)
		(layer "B.Cu")
		(net "PWRGD_GPU_HSC")
	)
	(segment
		(start 209.44205 -84.201)
		(end 205.994 -84.201)
		(width 0.17272)
		(layer "B.Cu")
		(net "PWRGD_GPU_HSC")
	)
	(segment
		(start 43.596814 -82.804)
		(end 37.93236 -82.804)
		(width 0.17272)
		(layer "B.Cu")
		(net "PWRGD_GPU_HSC")
	)
	(segment
		(start 148.814282 -85.37448)
		(end 46.167294 -85.37448)
		(width 0.17272)
		(layer "B.Cu")
		(net "PWRGD_GPU_HSC")
	)
	(segment
		(start 10.795 -81.534)
		(end 9.85012 -82.47888)
		(width 0.17272)
		(layer "B.Cu")
		(net "PWRGD_GPU_HSC")
	)
	(via
		(at 208.153 -85.471)
		(size 0.6604)
		(drill 0.3302)
		(layers "F.Cu" "B.Cu")
		(net "PWRGD_GPU_HSC_R")
	)
	(segment
		(start 208.407 -85.725)
		(end 210.26628 -85.725)
		(width 0.17272)
		(layer "B.Cu")
		(net "PWRGD_GPU_HSC_R")
	)
	(segment
		(start 208.153 -85.00872)
		(end 208.153 -85.471)
		(width 0.17272)
		(layer "B.Cu")
		(net "PWRGD_GPU_HSC_R")
	)
	(segment
		(start 210.439 -85.89772)
		(end 210.439 -86.93404)
		(width 0.17272)
		(layer "B.Cu")
		(net "PWRGD_GPU_HSC_R")
	)
	(segment
		(start 208.153 -85.471)
		(end 208.407 -85.725)
		(width 0.17272)
		(layer "B.Cu")
		(net "PWRGD_GPU_HSC_R")
	)
	(segment
		(start 208.32572 -84.836)
		(end 208.153 -85.00872)
		(width 0.17272)
		(layer "B.Cu")
		(net "PWRGD_GPU_HSC_R")
	)
	(segment
		(start 209.27695 -84.836)
		(end 208.32572 -84.836)
		(width 0.17272)
		(layer "B.Cu")
		(net "PWRGD_GPU_HSC_R")
	)
	(segment
		(start 210.26628 -85.725)
		(end 210.439 -85.89772)
		(width 0.17272)
		(layer "B.Cu")
		(net "PWRGD_GPU_HSC_R")
	)
	(via
		(at 221.246446 -67.804284)
		(size 0.6604)
		(drill 0.3302)
		(layers "F.Cu" "B.Cu")
		(net "PWRGD_GPU_HSC_BUF_R")
	)
	(segment
		(start 222.885 -70.59295)
		(end 222.52305 -70.59295)
		(width 0.17272)
		(layer "B.Cu")
		(net "PWRGD_GPU_HSC_BUF_R")
	)
	(segment
		(start 208.661 -91.948254)
		(end 209.422746 -92.71)
		(width 0.17272)
		(layer "B.Cu")
		(net "PWRGD_GPU_HSC_BUF_R")
	)
	(segment
		(start 213.614254 -45.974)
		(end 208.072482 -45.974)
		(width 0.17272)
		(layer "B.Cu")
		(net "PWRGD_GPU_HSC_BUF_R")
	)
	(segment
		(start 211.61248 -31.84652)
		(end 207.413098 -31.84652)
		(width 0.17272)
		(layer "B.Cu")
		(net "PWRGD_GPU_HSC_BUF_R")
	)
	(segment
		(start 209.422746 -92.71)
		(end 211.201 -92.71)
		(width 0.17272)
		(layer "B.Cu")
		(net "PWRGD_GPU_HSC_BUF_R")
	)
	(segment
		(start 203.30668 -41.208198)
		(end 203.30668 -30.37332)
		(width 0.17272)
		(layer "B.Cu")
		(net "PWRGD_GPU_HSC_BUF_R")
	)
	(segment
		(start 208.661 -90.95105)
		(end 208.661 -91.948254)
		(width 0.17272)
		(layer "B.Cu")
		(net "PWRGD_GPU_HSC_BUF_R")
	)
	(segment
		(start 211.582 -28.194)
		(end 212.598 -29.21)
		(width 0.17272)
		(layer "B.Cu")
		(net "PWRGD_GPU_HSC_BUF_R")
	)
	(segment
		(start 207.413098 -31.84652)
		(end 206.389986 -32.869632)
		(width 0.17272)
		(layer "B.Cu")
		(net "PWRGD_GPU_HSC_BUF_R")
	)
	(segment
		(start 221.246446 -67.804284)
		(end 216.3318 -62.889638)
		(width 0.17272)
		(layer "B.Cu")
		(net "PWRGD_GPU_HSC_BUF_R")
	)
	(segment
		(start 219.583 -78.5114)
		(end 213.6394 -84.455)
		(width 0.17272)
		(layer "B.Cu")
		(net "PWRGD_GPU_HSC_BUF_R")
	)
	(segment
		(start 203.30668 -30.37332)
		(end 205.486 -28.194)
		(width 0.17272)
		(layer "B.Cu")
		(net "PWRGD_GPU_HSC_BUF_R")
	)
	(segment
		(start 212.598 -29.21)
		(end 212.598 -30.861)
		(width 0.17272)
		(layer "B.Cu")
		(net "PWRGD_GPU_HSC_BUF_R")
	)
	(segment
		(start 212.90788 -85.400134)
		(end 212.74405 -85.236304)
		(width 0.17272)
		(layer "B.Cu")
		(net "PWRGD_GPU_HSC_BUF_R")
	)
	(segment
		(start 219.583 -73.533)
		(end 219.583 -78.5114)
		(width 0.17272)
		(layer "B.Cu")
		(net "PWRGD_GPU_HSC_BUF_R")
	)
	(segment
		(start 211.201 -92.71)
		(end 212.90788 -91.00312)
		(width 0.17272)
		(layer "B.Cu")
		(net "PWRGD_GPU_HSC_BUF_R")
	)
	(segment
		(start 208.072482 -45.974)
		(end 203.30668 -41.208198)
		(width 0.17272)
		(layer "B.Cu")
		(net "PWRGD_GPU_HSC_BUF_R")
	)
	(segment
		(start 205.486 -28.194)
		(end 211.582 -28.194)
		(width 0.17272)
		(layer "B.Cu")
		(net "PWRGD_GPU_HSC_BUF_R")
	)
	(segment
		(start 212.74405 -85.236304)
		(end 212.74405 -84.455)
		(width 0.17272)
		(layer "B.Cu")
		(net "PWRGD_GPU_HSC_BUF_R")
	)
	(segment
		(start 213.6394 -84.455)
		(end 212.74405 -84.455)
		(width 0.17272)
		(layer "B.Cu")
		(net "PWRGD_GPU_HSC_BUF_R")
	)
	(segment
		(start 216.3318 -48.691546)
		(end 213.614254 -45.974)
		(width 0.17272)
		(layer "B.Cu")
		(net "PWRGD_GPU_HSC_BUF_R")
	)
	(segment
		(start 216.3318 -62.889638)
		(end 216.3318 -48.691546)
		(width 0.17272)
		(layer "B.Cu")
		(net "PWRGD_GPU_HSC_BUF_R")
	)
	(segment
		(start 222.52305 -70.59295)
		(end 219.583 -73.533)
		(width 0.17272)
		(layer "B.Cu")
		(net "PWRGD_GPU_HSC_BUF_R")
	)
	(segment
		(start 212.598 -30.861)
		(end 211.61248 -31.84652)
		(width 0.17272)
		(layer "B.Cu")
		(net "PWRGD_GPU_HSC_BUF_R")
	)
	(segment
		(start 221.246446 -67.804284)
		(end 222.885 -69.442838)
		(width 0.17272)
		(layer "B.Cu")
		(net "PWRGD_GPU_HSC_BUF_R")
	)
	(segment
		(start 212.90788 -91.00312)
		(end 212.90788 -85.400134)
		(width 0.17272)
		(layer "B.Cu")
		(net "PWRGD_GPU_HSC_BUF_R")
	)
	(segment
		(start 222.885 -69.442838)
		(end 222.885 -70.59295)
		(width 0.17272)
		(layer "B.Cu")
		(net "PWRGD_GPU_HSC_BUF_R")
	)
	(via
		(at 191.26708 -85.979)
		(size 0.6604)
		(drill 0.3302)
		(layers "F.Cu" "B.Cu")
		(net "SMB_P52V_VPDB_SCL_R")
	)
	(segment
		(start 190.01105 -85.979)
		(end 191.26708 -85.979)
		(width 0.17272)
		(layer "B.Cu")
		(net "SMB_P52V_VPDB_SCL_R")
	)
	(segment
		(start 190.01105 -84.963)
		(end 190.01105 -85.979)
		(width 0.17272)
		(layer "B.Cu")
		(net "SMB_P52V_VPDB_SCL_R")
	)
	(segment
		(start 191.483234 -85.979)
		(end 192.271142 -86.766908)
		(width 0.17272)
		(layer "B.Cu")
		(net "SMB_P52V_VPDB_SCL_R")
	)
	(segment
		(start 192.271142 -86.766908)
		(end 193.11112 -86.766908)
		(width 0.17272)
		(layer "B.Cu")
		(net "SMB_P52V_VPDB_SCL_R")
	)
	(segment
		(start 191.26708 -85.979)
		(end 191.483234 -85.979)
		(width 0.17272)
		(layer "B.Cu")
		(net "SMB_P52V_VPDB_SCL_R")
	)
	(segment
		(start 300.1645 -37.65296)
		(end 300.624494 -38.112954)
		(width 0.254)
		(layer "F.Cu")
		(net "P52V_1_FUSE_1")
	)
	(segment
		(start 300.624494 -38.112954)
		(end 300.624494 -39.738554)
		(width 0.254)
		(layer "F.Cu")
		(net "P52V_1_FUSE_1")
	)
	(segment
		(start 296.164 -37.65296)
		(end 300.1645 -37.65296)
		(width 0.254)
		(layer "F.Cu")
		(net "P52V_1_FUSE_1")
	)
	(via
		(at 299.090334 -41.389808)
		(size 0.508)
		(drill 0.254)
		(layers "F.Cu" "B.Cu")
		(net "P52V_1_FUSE_1")
	)
	(via
		(at 301.122334 -41.389808)
		(size 0.508)
		(drill 0.254)
		(layers "F.Cu" "B.Cu")
		(net "P52V_1_FUSE_1")
	)
	(via
		(at 300.487334 -42.151808)
		(size 0.508)
		(drill 0.254)
		(layers "F.Cu" "B.Cu")
		(net "P52V_1_FUSE_1")
	)
	(via
		(at 301.122334 -42.151808)
		(size 0.508)
		(drill 0.254)
		(layers "F.Cu" "B.Cu")
		(net "P52V_1_FUSE_1")
	)
	(via
		(at 299.090334 -42.151808)
		(size 0.508)
		(drill 0.254)
		(layers "F.Cu" "B.Cu")
		(net "P52V_1_FUSE_1")
	)
	(via
		(at 301.908972 -41.346628)
		(size 0.508)
		(drill 0.254)
		(layers "F.Cu" "B.Cu")
		(net "P52V_1_FUSE_1")
	)
	(via
		(at 299.852334 -42.151808)
		(size 0.508)
		(drill 0.254)
		(layers "F.Cu" "B.Cu")
		(net "P52V_1_FUSE_1")
	)
	(via
		(at 299.852334 -41.389808)
		(size 0.508)
		(drill 0.254)
		(layers "F.Cu" "B.Cu")
		(net "P52V_1_FUSE_1")
	)
	(via
		(at 300.487334 -41.389808)
		(size 0.508)
		(drill 0.254)
		(layers "F.Cu" "B.Cu")
		(net "P52V_1_FUSE_1")
	)
	(via
		(at 301.9044 -42.164)
		(size 0.508)
		(drill 0.254)
		(layers "F.Cu" "B.Cu")
		(net "P52V_1_FUSE_1")
	)
	(via
		(at 234.62996 -87.757)
		(size 0.762)
		(drill 0.254)
		(layers "F.Cu" "B.Cu")
		(net "PWRGD_P3V3_AUX_MB_BUF_N")
	)
	(segment
		(start 216.46896 -85.91804)
		(end 218.2368 -84.1502)
		(width 0.17272)
		(layer "B.Cu")
		(net "PWRGD_P3V3_AUX_MB_BUF_N")
	)
	(segment
		(start 230.869998 -85.379052)
		(end 230.869998 -87.757)
		(width 0.17272)
		(layer "B.Cu")
		(net "PWRGD_P3V3_AUX_MB_BUF_N")
	)
	(segment
		(start 234.62996 -87.757)
		(end 234.62996 -86.658958)
		(width 0.17272)
		(layer "B.Cu")
		(net "PWRGD_P3V3_AUX_MB_BUF_N")
	)
	(segment
		(start 218.2368 -84.1502)
		(end 224.78492 -84.1502)
		(width 0.17272)
		(layer "B.Cu")
		(net "PWRGD_P3V3_AUX_MB_BUF_N")
	)
	(segment
		(start 216.46896 -86.404958)
		(end 216.46896 -85.91804)
		(width 0.17272)
		(layer "B.Cu")
		(net "PWRGD_P3V3_AUX_MB_BUF_N")
	)
	(segment
		(start 230.869998 -87.757)
		(end 234.62996 -87.757)
		(width 0.17272)
		(layer "B.Cu")
		(net "PWRGD_P3V3_AUX_MB_BUF_N")
	)
	(segment
		(start 224.78492 -84.1502)
		(end 228.39172 -87.757)
		(width 0.17272)
		(layer "B.Cu")
		(net "PWRGD_P3V3_AUX_MB_BUF_N")
	)
	(segment
		(start 228.39172 -87.757)
		(end 230.869998 -87.757)
		(width 0.17272)
		(layer "B.Cu")
		(net "PWRGD_P3V3_AUX_MB_BUF_N")
	)
	(segment
		(start 231.013 -85.23605)
		(end 230.869998 -85.379052)
		(width 0.17272)
		(layer "B.Cu")
		(net "PWRGD_P3V3_AUX_MB_BUF_N")
	)
	(via
		(at 229.489 -83.30565)
		(size 0.508)
		(drill 0.254)
		(layers "F.Cu" "B.Cu")
		(net "PWRGD_P3V3_AUX_MB_BUF")
	)
	(via
		(at 237.031784 -89.75344)
		(size 0.762)
		(drill 0.254)
		(layers "F.Cu" "B.Cu")
		(net "PWRGD_P3V3_AUX_MB_BUF")
	)
	(segment
		(start 148.972524 -90.80754)
		(end 152.815544 -86.96452)
		(width 0.17272)
		(layer "B.Cu")
		(net "PWRGD_P3V3_AUX_MB_BUF")
	)
	(segment
		(start 12.121896 -86.55812)
		(end 10.85088 -86.55812)
		(width 0.17272)
		(layer "B.Cu")
		(net "PWRGD_P3V3_AUX_MB_BUF")
	)
	(segment
		(start 7.974584 -86.711536)
		(end 7.43712 -87.249)
		(width 0.17272)
		(layer "B.Cu")
		(net "PWRGD_P3V3_AUX_MB_BUF")
	)
	(segment
		(start 7.43712 -87.249)
		(end 7.43712 -88.646)
		(width 0.17272)
		(layer "B.Cu")
		(net "PWRGD_P3V3_AUX_MB_BUF")
	)
	(segment
		(start 215.77935 -83.30565)
		(end 229.489 -83.30565)
		(width 0.17272)
		(layer "B.Cu")
		(net "PWRGD_P3V3_AUX_MB_BUF")
	)
	(segment
		(start 228.870002 -86.80704)
		(end 229.489 -86.188042)
		(width 0.17272)
		(layer "B.Cu")
		(net "PWRGD_P3V3_AUX_MB_BUF")
	)
	(segment
		(start 9.414256 -87.138256)
		(end 8.987536 -86.711536)
		(width 0.17272)
		(layer "B.Cu")
		(net "PWRGD_P3V3_AUX_MB_BUF")
	)
	(segment
		(start 187.495942 -95.503492)
		(end 195.526914 -95.503492)
		(width 0.17272)
		(layer "B.Cu")
		(net "PWRGD_P3V3_AUX_MB_BUF")
	)
	(segment
		(start 229.489 -86.188042)
		(end 229.489 -83.30565)
		(width 0.17272)
		(layer "B.Cu")
		(net "PWRGD_P3V3_AUX_MB_BUF")
	)
	(segment
		(start 152.815544 -86.96452)
		(end 178.95697 -86.96452)
		(width 0.17272)
		(layer "B.Cu")
		(net "PWRGD_P3V3_AUX_MB_BUF")
	)
	(segment
		(start 8.987536 -86.711536)
		(end 7.974584 -86.711536)
		(width 0.17272)
		(layer "B.Cu")
		(net "PWRGD_P3V3_AUX_MB_BUF")
	)
	(segment
		(start 213.487 -85.598)
		(end 215.77935 -83.30565)
		(width 0.17272)
		(layer "B.Cu")
		(net "PWRGD_P3V3_AUX_MB_BUF")
	)
	(segment
		(start 178.95697 -86.96452)
		(end 187.495942 -95.503492)
		(width 0.17272)
		(layer "B.Cu")
		(net "PWRGD_P3V3_AUX_MB_BUF")
	)
	(segment
		(start 229.489 -83.30565)
		(end 229.489 -82.69605)
		(width 0.17272)
		(layer "B.Cu")
		(net "PWRGD_P3V3_AUX_MB_BUF")
	)
	(segment
		(start 210.093052 -94.991428)
		(end 213.487 -91.59748)
		(width 0.17272)
		(layer "B.Cu")
		(net "PWRGD_P3V3_AUX_MB_BUF")
	)
	(segment
		(start 9.59866 -90.80754)
		(end 148.972524 -90.80754)
		(width 0.17272)
		(layer "B.Cu")
		(net "PWRGD_P3V3_AUX_MB_BUF")
	)
	(segment
		(start 196.038978 -94.991428)
		(end 210.093052 -94.991428)
		(width 0.17272)
		(layer "B.Cu")
		(net "PWRGD_P3V3_AUX_MB_BUF")
	)
	(segment
		(start 7.43712 -88.646)
		(end 9.59866 -90.80754)
		(width 0.17272)
		(layer "B.Cu")
		(net "PWRGD_P3V3_AUX_MB_BUF")
	)
	(segment
		(start 12.39012 -86.289896)
		(end 12.121896 -86.55812)
		(width 0.17272)
		(layer "B.Cu")
		(net "PWRGD_P3V3_AUX_MB_BUF")
	)
	(segment
		(start 10.270744 -87.138256)
		(end 9.414256 -87.138256)
		(width 0.17272)
		(layer "B.Cu")
		(net "PWRGD_P3V3_AUX_MB_BUF")
	)
	(segment
		(start 195.526914 -95.503492)
		(end 196.038978 -94.991428)
		(width 0.17272)
		(layer "B.Cu")
		(net "PWRGD_P3V3_AUX_MB_BUF")
	)
	(segment
		(start 10.85088 -86.55812)
		(end 10.270744 -87.138256)
		(width 0.17272)
		(layer "B.Cu")
		(net "PWRGD_P3V3_AUX_MB_BUF")
	)
	(segment
		(start 213.487 -91.59748)
		(end 213.487 -85.598)
		(width 0.17272)
		(layer "B.Cu")
		(net "PWRGD_P3V3_AUX_MB_BUF")
	)
	(segment
		(start 237.031784 -89.75344)
		(end 237.031784 -89.14384)
		(width 0.17272)
		(layer "B.Cu")
		(net "PWRGD_P3V3_AUX_MB_BUF")
	)
	(segment
		(start 235.797344 -88.519)
		(end 237.031784 -89.75344)
		(width 0.12954)
		(layer "In7.Cu")
		(net "PWRGD_P3V3_AUX_MB_BUF")
	)
	(segment
		(start 229.489 -83.9978)
		(end 234.0102 -88.519)
		(width 0.12954)
		(layer "In7.Cu")
		(net "PWRGD_P3V3_AUX_MB_BUF")
	)
	(segment
		(start 229.489 -83.30565)
		(end 229.489 -83.9978)
		(width 0.12954)
		(layer "In7.Cu")
		(net "PWRGD_P3V3_AUX_MB_BUF")
	)
	(segment
		(start 234.0102 -88.519)
		(end 235.797344 -88.519)
		(width 0.12954)
		(layer "In7.Cu")
		(net "PWRGD_P3V3_AUX_MB_BUF")
	)
	(via
		(at 230.109014 -81.372964)
		(size 0.762)
		(drill 0.254)
		(layers "F.Cu" "B.Cu")
		(net "PWRGD_P3V3_AUX_MB_BUF_R")
	)
	(segment
		(start 230.632 -81.89595)
		(end 229.489 -81.89595)
		(width 0.17272)
		(layer "B.Cu")
		(net "PWRGD_P3V3_AUX_MB_BUF_R")
	)
	(segment
		(start 230.109014 -80.45196)
		(end 230.109014 -81.372964)
		(width 0.17272)
		(layer "B.Cu")
		(net "PWRGD_P3V3_AUX_MB_BUF_R")
	)
	(segment
		(start 230.109014 -81.372964)
		(end 230.632 -81.89595)
		(width 0.17272)
		(layer "B.Cu")
		(net "PWRGD_P3V3_AUX_MB_BUF_R")
	)
	(via
		(at 232.283 -77.193394)
		(size 0.6604)
		(drill 0.3302)
		(layers "F.Cu" "B.Cu")
		(net "PWRGD_P3V3_AUX_MB_R1")
	)
	(segment
		(start 231.408986 -78.067408)
		(end 232.283 -77.193394)
		(width 0.17272)
		(layer "B.Cu")
		(net "PWRGD_P3V3_AUX_MB_R1")
	)
	(segment
		(start 231.408986 -78.55204)
		(end 231.408986 -78.067408)
		(width 0.17272)
		(layer "B.Cu")
		(net "PWRGD_P3V3_AUX_MB_R1")
	)
	(segment
		(start 232.283 -77.193394)
		(end 232.283 -75.58405)
		(width 0.17272)
		(layer "B.Cu")
		(net "PWRGD_P3V3_AUX_MB_R1")
	)
	(segment
		(start 232.283 -75.58405)
		(end 231.013 -75.58405)
		(width 0.17272)
		(layer "B.Cu")
		(net "PWRGD_P3V3_AUX_MB_R1")
	)
	(via
		(at 231.921812 -68.961762)
		(size 0.6604)
		(drill 0.3302)
		(layers "F.Cu" "B.Cu")
		(net "PWRGD_P3V3_AUX_MB_R")
	)
	(segment
		(start 225.011234 -68.072)
		(end 231.03205 -68.072)
		(width 0.17272)
		(layer "B.Cu")
		(net "PWRGD_P3V3_AUX_MB_R")
	)
	(segment
		(start 205.612746 -34.163)
		(end 205.2828 -34.492946)
		(width 0.17272)
		(layer "B.Cu")
		(net "PWRGD_P3V3_AUX_MB_R")
	)
	(segment
		(start 233.553 -70.59295)
		(end 232.537 -70.59295)
		(width 0.17272)
		(layer "B.Cu")
		(net "PWRGD_P3V3_AUX_MB_R")
	)
	(segment
		(start 218.24188 -47.648622)
		(end 218.24188 -61.302646)
		(width 0.17272)
		(layer "B.Cu")
		(net "PWRGD_P3V3_AUX_MB_R")
	)
	(segment
		(start 218.24188 -61.302646)
		(end 225.011234 -68.072)
		(width 0.17272)
		(layer "B.Cu")
		(net "PWRGD_P3V3_AUX_MB_R")
	)
	(segment
		(start 209.159348 -44.059348)
		(end 214.652606 -44.059348)
		(width 0.17272)
		(layer "B.Cu")
		(net "PWRGD_P3V3_AUX_MB_R")
	)
	(segment
		(start 214.652606 -44.059348)
		(end 218.24188 -47.648622)
		(width 0.17272)
		(layer "B.Cu")
		(net "PWRGD_P3V3_AUX_MB_R")
	)
	(segment
		(start 205.2828 -34.492946)
		(end 205.2828 -40.1828)
		(width 0.17272)
		(layer "B.Cu")
		(net "PWRGD_P3V3_AUX_MB_R")
	)
	(segment
		(start 231.921812 -68.961762)
		(end 233.553 -70.59295)
		(width 0.17272)
		(layer "B.Cu")
		(net "PWRGD_P3V3_AUX_MB_R")
	)
	(segment
		(start 207.683354 -34.163)
		(end 205.612746 -34.163)
		(width 0.17272)
		(layer "B.Cu")
		(net "PWRGD_P3V3_AUX_MB_R")
	)
	(segment
		(start 205.2828 -40.1828)
		(end 209.159348 -44.059348)
		(width 0.17272)
		(layer "B.Cu")
		(net "PWRGD_P3V3_AUX_MB_R")
	)
	(segment
		(start 231.03205 -68.072)
		(end 231.921812 -68.961762)
		(width 0.17272)
		(layer "B.Cu")
		(net "PWRGD_P3V3_AUX_MB_R")
	)
	(segment
		(start 208.929986 -35.409632)
		(end 207.683354 -34.163)
		(width 0.17272)
		(layer "B.Cu")
		(net "PWRGD_P3V3_AUX_MB_R")
	)
	(via
		(at 232.446322 -73.307448)
		(size 0.6604)
		(drill 0.3302)
		(layers "F.Cu" "B.Cu")
		(net "PWRGD_P3V3_AUX_MB")
	)
	(segment
		(start 231.013 -74.74077)
		(end 232.446322 -73.307448)
		(width 0.17272)
		(layer "B.Cu")
		(net "PWRGD_P3V3_AUX_MB")
	)
	(segment
		(start 233.553 -72.20077)
		(end 233.553 -71.39305)
		(width 0.17272)
		(layer "B.Cu")
		(net "PWRGD_P3V3_AUX_MB")
	)
	(segment
		(start 232.446322 -73.307448)
		(end 233.553 -72.20077)
		(width 0.17272)
		(layer "B.Cu")
		(net "PWRGD_P3V3_AUX_MB")
	)
	(segment
		(start 231.013 -74.78395)
		(end 231.013 -74.74077)
		(width 0.17272)
		(layer "B.Cu")
		(net "PWRGD_P3V3_AUX_MB")
	)
	(segment
		(start 279.757886 -41.091866)
		(end 280.797 -41.091866)
		(width 0.17272)
		(layer "F.Cu")
		(net "SMB_P52V_VPDB_SCL_R2")
	)
	(segment
		(start 279.410922 -40.744902)
		(end 279.757886 -41.091866)
		(width 0.17272)
		(layer "F.Cu")
		(net "SMB_P52V_VPDB_SCL_R2")
	)
	(segment
		(start 279.410922 -39.649146)
		(end 279.410922 -40.744902)
		(width 0.17272)
		(layer "F.Cu")
		(net "SMB_P52V_VPDB_SCL_R2")
	)
	(segment
		(start 280.797 -41.091866)
		(end 283.595572 -41.091866)
		(width 0.17272)
		(layer "F.Cu")
		(net "SMB_P52V_VPDB_SCL_R2")
	)
	(via
		(at 280.797 -41.091866)
		(size 0.762)
		(drill 0.381)
		(layers "F.Cu" "B.Cu")
		(net "SMB_P52V_VPDB_SCL_R2")
	)
	(via
		(at 213.717886 -71.263764)
		(size 0.6604)
		(drill 0.3302)
		(layers "F.Cu" "B.Cu")
		(net "BOARD_ID_2")
	)
	(segment
		(start 212.811106 -73.152)
		(end 212.811106 -72.170544)
		(width 0.17272)
		(layer "B.Cu")
		(net "BOARD_ID_2")
	)
	(segment
		(start 214.8586 -70.12305)
		(end 214.884 -70.12305)
		(width 0.17272)
		(layer "B.Cu")
		(net "BOARD_ID_2")
	)
	(segment
		(start 214.884 -67.58305)
		(end 215.50376 -68.20281)
		(width 0.17272)
		(layer "B.Cu")
		(net "BOARD_ID_2")
	)
	(segment
		(start 212.811106 -72.170544)
		(end 213.717886 -71.263764)
		(width 0.17272)
		(layer "B.Cu")
		(net "BOARD_ID_2")
	)
	(segment
		(start 215.06434 -69.94271)
		(end 214.884 -70.12305)
		(width 0.17272)
		(layer "B.Cu")
		(net "BOARD_ID_2")
	)
	(segment
		(start 213.717886 -71.263764)
		(end 214.8586 -70.12305)
		(width 0.17272)
		(layer "B.Cu")
		(net "BOARD_ID_2")
	)
	(segment
		(start 215.50376 -68.20281)
		(end 215.50376 -69.579744)
		(width 0.17272)
		(layer "B.Cu")
		(net "BOARD_ID_2")
	)
	(segment
		(start 215.50376 -69.579744)
		(end 215.140794 -69.94271)
		(width 0.17272)
		(layer "B.Cu")
		(net "BOARD_ID_2")
	)
	(segment
		(start 215.140794 -69.94271)
		(end 215.06434 -69.94271)
		(width 0.17272)
		(layer "B.Cu")
		(net "BOARD_ID_2")
	)
	(via
		(at 216.789 -68.21805)
		(size 0.762)
		(drill 0.254)
		(layers "F.Cu" "B.Cu")
		(net "BOARD_ID_1")
	)
	(segment
		(start 213.461092 -73.152)
		(end 213.461092 -72.329294)
		(width 0.17272)
		(layer "B.Cu")
		(net "BOARD_ID_1")
	)
	(segment
		(start 216.154 -70.12305)
		(end 216.388696 -70.12305)
		(width 0.17272)
		(layer "B.Cu")
		(net "BOARD_ID_1")
	)
	(segment
		(start 216.789 -68.21805)
		(end 216.154 -67.58305)
		(width 0.17272)
		(layer "B.Cu")
		(net "BOARD_ID_1")
	)
	(segment
		(start 215.051386 -70.739)
		(end 215.53805 -70.739)
		(width 0.17272)
		(layer "B.Cu")
		(net "BOARD_ID_1")
	)
	(segment
		(start 216.789 -69.722746)
		(end 216.789 -68.21805)
		(width 0.17272)
		(layer "B.Cu")
		(net "BOARD_ID_1")
	)
	(segment
		(start 216.388696 -70.12305)
		(end 216.789 -69.722746)
		(width 0.17272)
		(layer "B.Cu")
		(net "BOARD_ID_1")
	)
	(segment
		(start 213.461092 -72.329294)
		(end 215.051386 -70.739)
		(width 0.17272)
		(layer "B.Cu")
		(net "BOARD_ID_1")
	)
	(segment
		(start 215.53805 -70.739)
		(end 216.154 -70.12305)
		(width 0.17272)
		(layer "B.Cu")
		(net "BOARD_ID_1")
	)
	(via
		(at 215.773 -71.501)
		(size 0.6604)
		(drill 0.3302)
		(layers "F.Cu" "B.Cu")
		(net "BOARD_ID_0")
	)
	(segment
		(start 214.111078 -73.152)
		(end 214.111078 -72.354694)
		(width 0.17272)
		(layer "B.Cu")
		(net "BOARD_ID_0")
	)
	(segment
		(start 217.500454 -70.12305)
		(end 218.04376 -69.579744)
		(width 0.17272)
		(layer "B.Cu")
		(net "BOARD_ID_0")
	)
	(segment
		(start 214.964772 -71.501)
		(end 215.773 -71.501)
		(width 0.17272)
		(layer "B.Cu")
		(net "BOARD_ID_0")
	)
	(segment
		(start 217.424 -70.12305)
		(end 217.500454 -70.12305)
		(width 0.17272)
		(layer "B.Cu")
		(net "BOARD_ID_0")
	)
	(segment
		(start 218.04376 -68.20281)
		(end 217.424 -67.58305)
		(width 0.17272)
		(layer "B.Cu")
		(net "BOARD_ID_0")
	)
	(segment
		(start 217.424 -70.231)
		(end 217.424 -70.12305)
		(width 0.17272)
		(layer "B.Cu")
		(net "BOARD_ID_0")
	)
	(segment
		(start 215.773 -71.501)
		(end 216.154 -71.501)
		(width 0.17272)
		(layer "B.Cu")
		(net "BOARD_ID_0")
	)
	(segment
		(start 218.04376 -69.579744)
		(end 218.04376 -68.20281)
		(width 0.17272)
		(layer "B.Cu")
		(net "BOARD_ID_0")
	)
	(segment
		(start 216.154 -71.501)
		(end 217.424 -70.231)
		(width 0.17272)
		(layer "B.Cu")
		(net "BOARD_ID_0")
	)
	(segment
		(start 214.111078 -72.354694)
		(end 214.964772 -71.501)
		(width 0.17272)
		(layer "B.Cu")
		(net "BOARD_ID_0")
	)
	(via
		(at 209.094324 -71.426578)
		(size 0.6604)
		(drill 0.3302)
		(layers "F.Cu" "B.Cu")
		(net "SMB_VPDB_IOEXP_SCL")
	)
	(segment
		(start 209.094324 -71.426578)
		(end 208.534 -70.866254)
		(width 0.17272)
		(layer "B.Cu")
		(net "SMB_VPDB_IOEXP_SCL")
	)
	(segment
		(start 208.534 -70.866254)
		(end 208.534 -70.12305)
		(width 0.17272)
		(layer "B.Cu")
		(net "SMB_VPDB_IOEXP_SCL")
	)
	(segment
		(start 209.560922 -73.152)
		(end 209.560922 -71.893176)
		(width 0.17272)
		(layer "B.Cu")
		(net "SMB_VPDB_IOEXP_SCL")
	)
	(segment
		(start 209.560922 -71.893176)
		(end 209.094324 -71.426578)
		(width 0.17272)
		(layer "B.Cu")
		(net "SMB_VPDB_IOEXP_SCL")
	)
	(via
		(at 207.137 -71.501)
		(size 0.6604)
		(drill 0.3302)
		(layers "F.Cu" "B.Cu")
		(net "SMB_VPDB_IOEXP_SDA")
	)
	(segment
		(start 207.137 -71.501)
		(end 207.137 -71.246746)
		(width 0.17272)
		(layer "B.Cu")
		(net "SMB_VPDB_IOEXP_SDA")
	)
	(segment
		(start 208.910936 -73.152)
		(end 208.910936 -72.385936)
		(width 0.17272)
		(layer "B.Cu")
		(net "SMB_VPDB_IOEXP_SDA")
	)
	(segment
		(start 208.910936 -72.385936)
		(end 208.026 -71.501)
		(width 0.17272)
		(layer "B.Cu")
		(net "SMB_VPDB_IOEXP_SDA")
	)
	(segment
		(start 207.264 -71.119746)
		(end 207.264 -70.12305)
		(width 0.17272)
		(layer "B.Cu")
		(net "SMB_VPDB_IOEXP_SDA")
	)
	(segment
		(start 208.026 -71.501)
		(end 207.137 -71.501)
		(width 0.17272)
		(layer "B.Cu")
		(net "SMB_VPDB_IOEXP_SDA")
	)
	(segment
		(start 207.137 -71.246746)
		(end 207.264 -71.119746)
		(width 0.17272)
		(layer "B.Cu")
		(net "SMB_VPDB_IOEXP_SDA")
	)
	(via
		(at 186.70905 -85.344)
		(size 0.508)
		(drill 0.254)
		(layers "F.Cu" "B.Cu")
		(net "SMB_P52V_VPDB_SCL")
	)
	(via
		(at 137.063226 -79.6036)
		(size 0.508)
		(drill 0.254)
		(layers "F.Cu" "B.Cu")
		(net "SMB_P52V_VPDB_SCL")
	)
	(via
		(at 177.0634 -79.6036)
		(size 0.508)
		(drill 0.254)
		(layers "F.Cu" "B.Cu")
		(net "SMB_P52V_VPDB_SCL")
	)
	(via
		(at 96.133666 -79.784194)
		(size 0.6604)
		(drill 0.3302)
		(layers "F.Cu" "B.Cu")
		(net "SMB_P52V_VPDB_SCL")
	)
	(via
		(at 58.52795 -79.65567)
		(size 0.508)
		(drill 0.254)
		(layers "F.Cu" "B.Cu")
		(net "SMB_P52V_VPDB_SCL")
	)
	(via
		(at 97.272602 -79.6925)
		(size 0.508)
		(drill 0.254)
		(layers "F.Cu" "B.Cu")
		(net "SMB_P52V_VPDB_SCL")
	)
	(segment
		(start 96.133666 -79.784194)
		(end 96.717612 -79.784194)
		(width 0.17272)
		(layer "B.Cu")
		(net "SMB_P52V_VPDB_SCL")
	)
	(segment
		(start 138.942826 -79.4258)
		(end 138.66495 -79.147924)
		(width 0.17272)
		(layer "B.Cu")
		(net "SMB_P52V_VPDB_SCL")
	)
	(segment
		(start 178.665124 -78.867)
		(end 178.665124 -77.597)
		(width 0.17272)
		(layer "B.Cu")
		(net "SMB_P52V_VPDB_SCL")
	)
	(segment
		(start 138.66495 -78.867)
		(end 138.66495 -77.597)
		(width 0.17272)
		(layer "B.Cu")
		(net "SMB_P52V_VPDB_SCL")
	)
	(segment
		(start 96.717612 -79.784194)
		(end 96.809306 -79.6925)
		(width 0.17272)
		(layer "B.Cu")
		(net "SMB_P52V_VPDB_SCL")
	)
	(segment
		(start 138.66495 -77.597)
		(end 138.66495 -76.327)
		(width 0.17272)
		(layer "B.Cu")
		(net "SMB_P52V_VPDB_SCL")
	)
	(segment
		(start 96.11995 -76.327)
		(end 96.11995 -77.47)
		(width 0.17272)
		(layer "B.Cu")
		(net "SMB_P52V_VPDB_SCL")
	)
	(segment
		(start 58.52795 -79.65567)
		(end 58.52795 -78.613)
		(width 0.17272)
		(layer "B.Cu")
		(net "SMB_P52V_VPDB_SCL")
	)
	(segment
		(start 58.52795 -78.613)
		(end 58.52795 -77.47)
		(width 0.17272)
		(layer "B.Cu")
		(net "SMB_P52V_VPDB_SCL")
	)
	(segment
		(start 58.52795 -77.47)
		(end 58.52795 -76.327)
		(width 0.17272)
		(layer "B.Cu")
		(net "SMB_P52V_VPDB_SCL")
	)
	(segment
		(start 137.418826 -79.6036)
		(end 138.180826 -80.3656)
		(width 0.17272)
		(layer "B.Cu")
		(net "SMB_P52V_VPDB_SCL")
	)
	(segment
		(start 96.11995 -78.613)
		(end 96.11995 -79.770478)
		(width 0.17272)
		(layer "B.Cu")
		(net "SMB_P52V_VPDB_SCL")
	)
	(segment
		(start 138.66495 -79.147924)
		(end 138.66495 -78.867)
		(width 0.17272)
		(layer "B.Cu")
		(net "SMB_P52V_VPDB_SCL")
	)
	(segment
		(start 96.809306 -79.6925)
		(end 97.272602 -79.6925)
		(width 0.17272)
		(layer "B.Cu")
		(net "SMB_P52V_VPDB_SCL")
	)
	(segment
		(start 138.942826 -79.9846)
		(end 138.942826 -79.4258)
		(width 0.17272)
		(layer "B.Cu")
		(net "SMB_P52V_VPDB_SCL")
	)
	(segment
		(start 177.928524 -79.6036)
		(end 178.665124 -78.867)
		(width 0.17272)
		(layer "B.Cu")
		(net "SMB_P52V_VPDB_SCL")
	)
	(segment
		(start 96.11995 -77.47)
		(end 96.11995 -78.613)
		(width 0.17272)
		(layer "B.Cu")
		(net "SMB_P52V_VPDB_SCL")
	)
	(segment
		(start 96.11995 -79.770478)
		(end 96.133666 -79.784194)
		(width 0.17272)
		(layer "B.Cu")
		(net "SMB_P52V_VPDB_SCL")
	)
	(segment
		(start 138.180826 -80.3656)
		(end 138.561826 -80.3656)
		(width 0.17272)
		(layer "B.Cu")
		(net "SMB_P52V_VPDB_SCL")
	)
	(segment
		(start 137.063226 -79.6036)
		(end 137.418826 -79.6036)
		(width 0.17272)
		(layer "B.Cu")
		(net "SMB_P52V_VPDB_SCL")
	)
	(segment
		(start 177.0634 -79.6036)
		(end 177.928524 -79.6036)
		(width 0.17272)
		(layer "B.Cu")
		(net "SMB_P52V_VPDB_SCL")
	)
	(segment
		(start 138.561826 -80.3656)
		(end 138.942826 -79.9846)
		(width 0.17272)
		(layer "B.Cu")
		(net "SMB_P52V_VPDB_SCL")
	)
	(segment
		(start 178.665124 -77.597)
		(end 178.665124 -76.327)
		(width 0.17272)
		(layer "B.Cu")
		(net "SMB_P52V_VPDB_SCL")
	)
	(segment
		(start 189.21095 -85.979)
		(end 186.70905 -85.979)
		(width 0.17272)
		(layer "B.Cu")
		(net "SMB_P52V_VPDB_SCL")
	)
	(segment
		(start 186.70905 -85.979)
		(end 186.70905 -85.344)
		(width 0.17272)
		(layer "B.Cu")
		(net "SMB_P52V_VPDB_SCL")
	)
	(segment
		(start 97.272602 -79.6925)
		(end 136.974326 -79.6925)
		(width 0.12954)
		(layer "In7.Cu")
		(net "SMB_P52V_VPDB_SCL")
	)
	(segment
		(start 186.02579 -86.02726)
		(end 183.554878 -86.02726)
		(width 0.12954)
		(layer "In7.Cu")
		(net "SMB_P52V_VPDB_SCL")
	)
	(segment
		(start 136.974326 -79.6925)
		(end 137.063226 -79.6036)
		(width 0.12954)
		(layer "In7.Cu")
		(net "SMB_P52V_VPDB_SCL")
	)
	(segment
		(start 171.0944 -79.6036)
		(end 172.3644 -78.3336)
		(width 0.12954)
		(layer "In7.Cu")
		(net "SMB_P52V_VPDB_SCL")
	)
	(segment
		(start 174.6504 -79.6036)
		(end 177.0634 -79.6036)
		(width 0.12954)
		(layer "In7.Cu")
		(net "SMB_P52V_VPDB_SCL")
	)
	(segment
		(start 172.3644 -78.3336)
		(end 173.3804 -78.3336)
		(width 0.12954)
		(layer "In7.Cu")
		(net "SMB_P52V_VPDB_SCL")
	)
	(segment
		(start 58.52795 -79.65567)
		(end 58.56478 -79.6925)
		(width 0.12954)
		(layer "In7.Cu")
		(net "SMB_P52V_VPDB_SCL")
	)
	(segment
		(start 186.70905 -85.344)
		(end 186.02579 -86.02726)
		(width 0.12954)
		(layer "In7.Cu")
		(net "SMB_P52V_VPDB_SCL")
	)
	(segment
		(start 173.3804 -78.3336)
		(end 174.6504 -79.6036)
		(width 0.12954)
		(layer "In7.Cu")
		(net "SMB_P52V_VPDB_SCL")
	)
	(segment
		(start 183.554878 -86.02726)
		(end 177.131218 -79.6036)
		(width 0.12954)
		(layer "In7.Cu")
		(net "SMB_P52V_VPDB_SCL")
	)
	(segment
		(start 137.063226 -79.6036)
		(end 171.0944 -79.6036)
		(width 0.12954)
		(layer "In7.Cu")
		(net "SMB_P52V_VPDB_SCL")
	)
	(segment
		(start 177.131218 -79.6036)
		(end 177.0634 -79.6036)
		(width 0.12954)
		(layer "In7.Cu")
		(net "SMB_P52V_VPDB_SCL")
	)
	(segment
		(start 58.56478 -79.6925)
		(end 97.272602 -79.6925)
		(width 0.12954)
		(layer "In7.Cu")
		(net "SMB_P52V_VPDB_SCL")
	)
	(via
		(at 194.62496 -93.077284)
		(size 0.6604)
		(drill 0.3302)
		(layers "F.Cu" "B.Cu")
		(net "SMB_HPDB_MISC_SDA")
	)
	(segment
		(start 39.38905 -89.027)
		(end 149.11451 -89.027)
		(width 0.17272)
		(layer "B.Cu")
		(net "SMB_HPDB_MISC_SDA")
	)
	(segment
		(start 195.987924 -87.476076)
		(end 196.697092 -86.766908)
		(width 0.17272)
		(layer "B.Cu")
		(net "SMB_HPDB_MISC_SDA")
	)
	(segment
		(start 198.81088 -86.766908)
		(end 200.380092 -86.766908)
		(width 0.17272)
		(layer "B.Cu")
		(net "SMB_HPDB_MISC_SDA")
	)
	(segment
		(start 149.11451 -89.027)
		(end 152.39111 -85.7504)
		(width 0.17272)
		(layer "B.Cu")
		(net "SMB_HPDB_MISC_SDA")
	)
	(segment
		(start 179.81168 -85.7504)
		(end 188.285882 -94.224602)
		(width 0.17272)
		(layer "B.Cu")
		(net "SMB_HPDB_MISC_SDA")
	)
	(segment
		(start 152.39111 -85.7504)
		(end 179.81168 -85.7504)
		(width 0.17272)
		(layer "B.Cu")
		(net "SMB_HPDB_MISC_SDA")
	)
	(segment
		(start 188.285882 -94.224602)
		(end 193.477642 -94.224602)
		(width 0.17272)
		(layer "B.Cu")
		(net "SMB_HPDB_MISC_SDA")
	)
	(segment
		(start 196.697092 -86.766908)
		(end 198.81088 -86.766908)
		(width 0.17272)
		(layer "B.Cu")
		(net "SMB_HPDB_MISC_SDA")
	)
	(segment
		(start 195.987924 -91.71432)
		(end 195.987924 -87.476076)
		(width 0.17272)
		(layer "B.Cu")
		(net "SMB_HPDB_MISC_SDA")
	)
	(segment
		(start 194.62496 -93.077284)
		(end 195.987924 -91.71432)
		(width 0.17272)
		(layer "B.Cu")
		(net "SMB_HPDB_MISC_SDA")
	)
	(segment
		(start 200.380092 -86.766908)
		(end 202.057 -85.09)
		(width 0.17272)
		(layer "B.Cu")
		(net "SMB_HPDB_MISC_SDA")
	)
	(segment
		(start 202.057 -85.09)
		(end 202.54595 -85.09)
		(width 0.17272)
		(layer "B.Cu")
		(net "SMB_HPDB_MISC_SDA")
	)
	(segment
		(start 193.477642 -94.224602)
		(end 194.62496 -93.077284)
		(width 0.17272)
		(layer "B.Cu")
		(net "SMB_HPDB_MISC_SDA")
	)
	(segment
		(start 207.264 -68.71335)
		(end 207.899 -69.34835)
		(width 0.17272)
		(layer "F.Cu")
		(net "SMB_VPDB_MISC_SDA")
	)
	(segment
		(start 204.724 -80.899)
		(end 204.724 -86.76005)
		(width 0.17272)
		(layer "F.Cu")
		(net "SMB_VPDB_MISC_SDA")
	)
	(segment
		(start 207.899 -69.34835)
		(end 207.899 -77.724)
		(width 0.17272)
		(layer "F.Cu")
		(net "SMB_VPDB_MISC_SDA")
	)
	(segment
		(start 207.899 -77.724)
		(end 204.724 -80.899)
		(width 0.17272)
		(layer "F.Cu")
		(net "SMB_VPDB_MISC_SDA")
	)
	(segment
		(start 204.724 -86.76005)
		(end 205.33995 -87.376)
		(width 0.17272)
		(layer "F.Cu")
		(net "SMB_VPDB_MISC_SDA")
	)
	(via
		(at 219.583 -91.059)
		(size 0.508)
		(drill 0.254)
		(layers "F.Cu" "B.Cu")
		(net "SMB_VPDB_MISC_SDA")
	)
	(via
		(at 207.264 -68.71335)
		(size 0.762)
		(drill 0.254)
		(layers "F.Cu" "B.Cu")
		(net "SMB_VPDB_MISC_SDA")
	)
	(via
		(at 205.33995 -87.376)
		(size 0.508)
		(drill 0.254)
		(layers "F.Cu" "B.Cu")
		(net "SMB_VPDB_MISC_SDA")
	)
	(segment
		(start 198.81088 -88.71712)
		(end 201.1934 -88.71712)
		(width 0.17272)
		(layer "B.Cu")
		(net "SMB_VPDB_MISC_SDA")
	)
	(segment
		(start 203.22921 -88.69426)
		(end 202.54595 -88.011)
		(width 0.17272)
		(layer "B.Cu")
		(net "SMB_VPDB_MISC_SDA")
	)
	(segment
		(start 204.65669 -88.69426)
		(end 203.22921 -88.69426)
		(width 0.17272)
		(layer "B.Cu")
		(net "SMB_VPDB_MISC_SDA")
	)
	(segment
		(start 201.89952 -88.011)
		(end 202.54595 -88.011)
		(width 0.17272)
		(layer "B.Cu")
		(net "SMB_VPDB_MISC_SDA")
	)
	(segment
		(start 205.33995 -88.011)
		(end 204.65669 -88.69426)
		(width 0.17272)
		(layer "B.Cu")
		(net "SMB_VPDB_MISC_SDA")
	)
	(segment
		(start 219.583 -91.059)
		(end 219.583 -90.44305)
		(width 0.17272)
		(layer "B.Cu")
		(net "SMB_VPDB_MISC_SDA")
	)
	(segment
		(start 205.33995 -87.376)
		(end 205.33995 -88.011)
		(width 0.17272)
		(layer "B.Cu")
		(net "SMB_VPDB_MISC_SDA")
	)
	(segment
		(start 201.1934 -88.71712)
		(end 201.89952 -88.011)
		(width 0.17272)
		(layer "B.Cu")
		(net "SMB_VPDB_MISC_SDA")
	)
	(segment
		(start 207.264 -68.71335)
		(end 207.264 -69.32295)
		(width 0.17272)
		(layer "B.Cu")
		(net "SMB_VPDB_MISC_SDA")
	)
	(segment
		(start 205.81112 -86.90483)
		(end 212.63483 -86.90483)
		(width 0.12954)
		(layer "In7.Cu")
		(net "SMB_VPDB_MISC_SDA")
	)
	(segment
		(start 205.33995 -87.376)
		(end 205.81112 -86.90483)
		(width 0.12954)
		(layer "In7.Cu")
		(net "SMB_VPDB_MISC_SDA")
	)
	(segment
		(start 212.63483 -86.90483)
		(end 213.85149 -88.12149)
		(width 0.12954)
		(layer "In7.Cu")
		(net "SMB_VPDB_MISC_SDA")
	)
	(segment
		(start 216.64549 -88.12149)
		(end 219.583 -91.059)
		(width 0.12954)
		(layer "In7.Cu")
		(net "SMB_VPDB_MISC_SDA")
	)
	(segment
		(start 213.85149 -88.12149)
		(end 216.64549 -88.12149)
		(width 0.12954)
		(layer "In7.Cu")
		(net "SMB_VPDB_MISC_SDA")
	)
	(via
		(at 191.262 -93.091)
		(size 0.6604)
		(drill 0.3302)
		(layers "F.Cu" "B.Cu")
		(net "SMB_HPDB_MISC_SCL")
	)
	(segment
		(start 148.90496 -88.4174)
		(end 39.79545 -88.4174)
		(width 0.17272)
		(layer "B.Cu")
		(net "SMB_HPDB_MISC_SCL")
	)
	(segment
		(start 195.326 -91.44)
		(end 195.326 -87.122)
		(width 0.17272)
		(layer "B.Cu")
		(net "SMB_HPDB_MISC_SCL")
	)
	(segment
		(start 188.596524 -93.599)
		(end 180.086 -85.088476)
		(width 0.17272)
		(layer "B.Cu")
		(net "SMB_HPDB_MISC_SCL")
	)
	(segment
		(start 195.326 -87.122)
		(end 196.331078 -86.116922)
		(width 0.17272)
		(layer "B.Cu")
		(net "SMB_HPDB_MISC_SCL")
	)
	(segment
		(start 202.54595 -83.82)
		(end 202.463654 -83.82)
		(width 0.17272)
		(layer "B.Cu")
		(net "SMB_HPDB_MISC_SCL")
	)
	(segment
		(start 191.77 -93.599)
		(end 193.167 -93.599)
		(width 0.17272)
		(layer "B.Cu")
		(net "SMB_HPDB_MISC_SCL")
	)
	(segment
		(start 190.754 -93.599)
		(end 188.596524 -93.599)
		(width 0.17272)
		(layer "B.Cu")
		(net "SMB_HPDB_MISC_SCL")
	)
	(segment
		(start 191.262 -93.091)
		(end 190.754 -93.599)
		(width 0.17272)
		(layer "B.Cu")
		(net "SMB_HPDB_MISC_SCL")
	)
	(segment
		(start 202.463654 -83.82)
		(end 200.166732 -86.116922)
		(width 0.17272)
		(layer "B.Cu")
		(net "SMB_HPDB_MISC_SCL")
	)
	(segment
		(start 39.79545 -88.4174)
		(end 39.38905 -88.011)
		(width 0.17272)
		(layer "B.Cu")
		(net "SMB_HPDB_MISC_SCL")
	)
	(segment
		(start 200.166732 -86.116922)
		(end 198.81088 -86.116922)
		(width 0.17272)
		(layer "B.Cu")
		(net "SMB_HPDB_MISC_SCL")
	)
	(segment
		(start 152.233884 -85.088476)
		(end 148.90496 -88.4174)
		(width 0.17272)
		(layer "B.Cu")
		(net "SMB_HPDB_MISC_SCL")
	)
	(segment
		(start 196.331078 -86.116922)
		(end 198.81088 -86.116922)
		(width 0.17272)
		(layer "B.Cu")
		(net "SMB_HPDB_MISC_SCL")
	)
	(segment
		(start 193.167 -93.599)
		(end 195.326 -91.44)
		(width 0.17272)
		(layer "B.Cu")
		(net "SMB_HPDB_MISC_SCL")
	)
	(segment
		(start 180.086 -85.088476)
		(end 152.233884 -85.088476)
		(width 0.17272)
		(layer "B.Cu")
		(net "SMB_HPDB_MISC_SCL")
	)
	(segment
		(start 191.262 -93.091)
		(end 191.77 -93.599)
		(width 0.17272)
		(layer "B.Cu")
		(net "SMB_HPDB_MISC_SCL")
	)
	(segment
		(start 205.33995 -84.836)
		(end 205.33995 -82.18805)
		(width 0.17272)
		(layer "F.Cu")
		(net "SMB_VPDB_MISC_SCL")
	)
	(segment
		(start 208.534 -78.994)
		(end 208.534 -68.71335)
		(width 0.17272)
		(layer "F.Cu")
		(net "SMB_VPDB_MISC_SCL")
	)
	(segment
		(start 205.33995 -82.18805)
		(end 208.534 -78.994)
		(width 0.17272)
		(layer "F.Cu")
		(net "SMB_VPDB_MISC_SCL")
	)
	(via
		(at 220.726 -91.567)
		(size 0.508)
		(drill 0.254)
		(layers "F.Cu" "B.Cu")
		(net "SMB_VPDB_MISC_SCL")
	)
	(via
		(at 208.534 -68.71335)
		(size 0.508)
		(drill 0.254)
		(layers "F.Cu" "B.Cu")
		(net "SMB_VPDB_MISC_SCL")
	)
	(via
		(at 205.33995 -84.836)
		(size 0.508)
		(drill 0.254)
		(layers "F.Cu" "B.Cu")
		(net "SMB_VPDB_MISC_SCL")
	)
	(segment
		(start 201.803 -87.249)
		(end 200.98512 -88.06688)
		(width 0.17272)
		(layer "B.Cu")
		(net "SMB_VPDB_MISC_SCL")
	)
	(segment
		(start 220.726 -91.567)
		(end 220.726 -90.44305)
		(width 0.17272)
		(layer "B.Cu")
		(net "SMB_VPDB_MISC_SCL")
	)
	(segment
		(start 200.98512 -88.06688)
		(end 198.81088 -88.06688)
		(width 0.17272)
		(layer "B.Cu")
		(net "SMB_VPDB_MISC_SCL")
	)
	(segment
		(start 203.708254 -87.249)
		(end 201.803 -87.249)
		(width 0.17272)
		(layer "B.Cu")
		(net "SMB_VPDB_MISC_SCL")
	)
	(segment
		(start 205.33995 -86.614)
		(end 204.343254 -86.614)
		(width 0.17272)
		(layer "B.Cu")
		(net "SMB_VPDB_MISC_SCL")
	)
	(segment
		(start 205.33995 -86.614)
		(end 205.33995 -84.836)
		(width 0.17272)
		(layer "B.Cu")
		(net "SMB_VPDB_MISC_SCL")
	)
	(segment
		(start 204.343254 -86.614)
		(end 203.708254 -87.249)
		(width 0.17272)
		(layer "B.Cu")
		(net "SMB_VPDB_MISC_SCL")
	)
	(segment
		(start 208.534 -68.71335)
		(end 208.534 -69.32295)
		(width 0.17272)
		(layer "B.Cu")
		(net "SMB_VPDB_MISC_SCL")
	)
	(segment
		(start 211.514436 -84.836)
		(end 213.800436 -87.122)
		(width 0.12954)
		(layer "In7.Cu")
		(net "SMB_VPDB_MISC_SCL")
	)
	(segment
		(start 213.800436 -87.122)
		(end 216.662 -87.122)
		(width 0.12954)
		(layer "In7.Cu")
		(net "SMB_VPDB_MISC_SCL")
	)
	(segment
		(start 220.726 -91.186)
		(end 220.726 -91.567)
		(width 0.12954)
		(layer "In7.Cu")
		(net "SMB_VPDB_MISC_SCL")
	)
	(segment
		(start 205.33995 -84.836)
		(end 211.514436 -84.836)
		(width 0.12954)
		(layer "In7.Cu")
		(net "SMB_VPDB_MISC_SCL")
	)
	(segment
		(start 216.662 -87.122)
		(end 220.726 -91.186)
		(width 0.12954)
		(layer "In7.Cu")
		(net "SMB_VPDB_MISC_SCL")
	)
	(via
		(at 41.464738 -85.217)
		(size 0.6604)
		(drill 0.3302)
		(layers "F.Cu" "B.Cu")
		(net "SMB_P52V_HPDB_SCL")
	)
	(segment
		(start 191.00673 -88.71712)
		(end 190.01105 -89.7128)
		(width 0.17272)
		(layer "B.Cu")
		(net "SMB_P52V_HPDB_SCL")
	)
	(segment
		(start 44.030138 -87.7824)
		(end 41.464738 -85.217)
		(width 0.17272)
		(layer "B.Cu")
		(net "SMB_P52V_HPDB_SCL")
	)
	(segment
		(start 193.11112 -88.71712)
		(end 191.00673 -88.71712)
		(width 0.17272)
		(layer "B.Cu")
		(net "SMB_P52V_HPDB_SCL")
	)
	(segment
		(start 189.32779 -89.02954)
		(end 185.879994 -89.02954)
		(width 0.17272)
		(layer "B.Cu")
		(net "SMB_P52V_HPDB_SCL")
	)
	(segment
		(start 41.464738 -85.217)
		(end 39.38905 -85.217)
		(width 0.17272)
		(layer "B.Cu")
		(net "SMB_P52V_HPDB_SCL")
	)
	(segment
		(start 190.01105 -89.7128)
		(end 189.32779 -89.02954)
		(width 0.17272)
		(layer "B.Cu")
		(net "SMB_P52V_HPDB_SCL")
	)
	(segment
		(start 185.879994 -89.02954)
		(end 181.330854 -84.4804)
		(width 0.17272)
		(layer "B.Cu")
		(net "SMB_P52V_HPDB_SCL")
	)
	(segment
		(start 181.330854 -84.4804)
		(end 152.022556 -84.4804)
		(width 0.17272)
		(layer "B.Cu")
		(net "SMB_P52V_HPDB_SCL")
	)
	(segment
		(start 148.720556 -87.7824)
		(end 44.030138 -87.7824)
		(width 0.17272)
		(layer "B.Cu")
		(net "SMB_P52V_HPDB_SCL")
	)
	(segment
		(start 152.022556 -84.4804)
		(end 148.720556 -87.7824)
		(width 0.17272)
		(layer "B.Cu")
		(net "SMB_P52V_HPDB_SCL")
	)
	(via
		(at 43.510708 -84.701634)
		(size 0.6604)
		(drill 0.3302)
		(layers "F.Cu" "B.Cu")
		(net "SMB_P52V_HPDB_SDA")
	)
	(segment
		(start 181.864 -83.82)
		(end 151.863552 -83.82)
		(width 0.17272)
		(layer "B.Cu")
		(net "SMB_P52V_HPDB_SDA")
	)
	(segment
		(start 189.31001 -87.61476)
		(end 185.65876 -87.61476)
		(width 0.17272)
		(layer "B.Cu")
		(net "SMB_P52V_HPDB_SDA")
	)
	(segment
		(start 42.883074 -84.074)
		(end 43.510708 -84.701634)
		(width 0.17272)
		(layer "B.Cu")
		(net "SMB_P52V_HPDB_SDA")
	)
	(segment
		(start 190.01105 -88.3158)
		(end 189.31001 -87.61476)
		(width 0.17272)
		(layer "B.Cu")
		(net "SMB_P52V_HPDB_SDA")
	)
	(segment
		(start 190.25997 -88.06688)
		(end 190.01105 -88.3158)
		(width 0.17272)
		(layer "B.Cu")
		(net "SMB_P52V_HPDB_SDA")
	)
	(segment
		(start 45.956474 -87.1474)
		(end 43.510708 -84.701634)
		(width 0.17272)
		(layer "B.Cu")
		(net "SMB_P52V_HPDB_SDA")
	)
	(segment
		(start 151.863552 -83.82)
		(end 148.536152 -87.1474)
		(width 0.17272)
		(layer "B.Cu")
		(net "SMB_P52V_HPDB_SDA")
	)
	(segment
		(start 185.65876 -87.61476)
		(end 181.864 -83.82)
		(width 0.17272)
		(layer "B.Cu")
		(net "SMB_P52V_HPDB_SDA")
	)
	(segment
		(start 39.38905 -84.074)
		(end 42.883074 -84.074)
		(width 0.17272)
		(layer "B.Cu")
		(net "SMB_P52V_HPDB_SDA")
	)
	(segment
		(start 148.536152 -87.1474)
		(end 45.956474 -87.1474)
		(width 0.17272)
		(layer "B.Cu")
		(net "SMB_P52V_HPDB_SDA")
	)
	(segment
		(start 193.11112 -88.06688)
		(end 190.25997 -88.06688)
		(width 0.17272)
		(layer "B.Cu")
		(net "SMB_P52V_HPDB_SDA")
	)
	(segment
		(start 204.84211 -67.32905)
		(end 205.04404 -67.53098)
		(width 0.17272)
		(layer "F.Cu")
		(net "LED_D3_R")
	)
	(segment
		(start 204.724 -67.32905)
		(end 204.84211 -67.32905)
		(width 0.17272)
		(layer "F.Cu")
		(net "LED_D3_R")
	)
	(segment
		(start 204.089 -67.32905)
		(end 204.724 -67.32905)
		(width 0.17272)
		(layer "F.Cu")
		(net "LED_D3_R")
	)
	(segment
		(start 205.04404 -67.53098)
		(end 205.613 -67.53098)
		(width 0.17272)
		(layer "F.Cu")
		(net "LED_D3_R")
	)
	(via
		(at 204.724 -67.32905)
		(size 0.508)
		(drill 0.254)
		(layers "F.Cu" "B.Cu")
		(net "LED_D3_R")
	)
	(via
		(at 201.057002 -87.100918)
		(size 0.6604)
		(drill 0.3302)
		(layers "F.Cu" "B.Cu")
		(net "PU_9543_0_INT1")
	)
	(segment
		(start 198.81088 -87.416894)
		(end 200.741026 -87.416894)
		(width 0.17272)
		(layer "B.Cu")
		(net "PU_9543_0_INT1")
	)
	(segment
		(start 201.057002 -87.100918)
		(end 201.54392 -86.614)
		(width 0.17272)
		(layer "B.Cu")
		(net "PU_9543_0_INT1")
	)
	(segment
		(start 201.54392 -86.614)
		(end 202.54595 -86.614)
		(width 0.17272)
		(layer "B.Cu")
		(net "PU_9543_0_INT1")
	)
	(segment
		(start 200.741026 -87.416894)
		(end 201.057002 -87.100918)
		(width 0.17272)
		(layer "B.Cu")
		(net "PU_9543_0_INT1")
	)
	(via
		(at 54.08295 -80.137)
		(size 0.508)
		(drill 0.254)
		(layers "F.Cu" "B.Cu")
		(net "SMB_P52V_VPDB_SDA")
	)
	(via
		(at 97.272602 -80.3656)
		(size 0.508)
		(drill 0.254)
		(layers "F.Cu" "B.Cu")
		(net "SMB_P52V_VPDB_SDA")
	)
	(via
		(at 137.063226 -80.3656)
		(size 0.508)
		(drill 0.254)
		(layers "F.Cu" "B.Cu")
		(net "SMB_P52V_VPDB_SDA")
	)
	(via
		(at 186.70905 -82.804)
		(size 0.508)
		(drill 0.254)
		(layers "F.Cu" "B.Cu")
		(net "SMB_P52V_VPDB_SDA")
	)
	(via
		(at 172.8216 -78.867)
		(size 0.508)
		(drill 0.254)
		(layers "F.Cu" "B.Cu")
		(net "SMB_P52V_VPDB_SDA")
	)
	(segment
		(start 54.08295 -80.137)
		(end 54.08295 -78.613)
		(width 0.17272)
		(layer "B.Cu")
		(net "SMB_P52V_VPDB_SDA")
	)
	(segment
		(start 193.11112 -86.116922)
		(end 192.517776 -86.116922)
		(width 0.17272)
		(layer "B.Cu")
		(net "SMB_P52V_VPDB_SDA")
	)
	(segment
		(start 174.093124 -76.327)
		(end 174.093124 -77.597)
		(width 0.17272)
		(layer "B.Cu")
		(net "SMB_P52V_VPDB_SDA")
	)
	(segment
		(start 174.093124 -77.597)
		(end 174.093124 -78.867)
		(width 0.17272)
		(layer "B.Cu")
		(net "SMB_P52V_VPDB_SDA")
	)
	(segment
		(start 187.39231 -84.12226)
		(end 189.349126 -84.12226)
		(width 0.17272)
		(layer "B.Cu")
		(net "SMB_P52V_VPDB_SDA")
	)
	(segment
		(start 54.08295 -77.47)
		(end 54.08295 -76.327)
		(width 0.17272)
		(layer "B.Cu")
		(net "SMB_P52V_VPDB_SDA")
	)
	(segment
		(start 97.688146 -80.3656)
		(end 98.40595 -79.647796)
		(width 0.17272)
		(layer "B.Cu")
		(net "SMB_P52V_VPDB_SDA")
	)
	(segment
		(start 186.70905 -83.439)
		(end 187.39231 -84.12226)
		(width 0.17272)
		(layer "B.Cu")
		(net "SMB_P52V_VPDB_SDA")
	)
	(segment
		(start 98.40595 -79.647796)
		(end 98.40595 -78.613)
		(width 0.17272)
		(layer "B.Cu")
		(net "SMB_P52V_VPDB_SDA")
	)
	(segment
		(start 190.01105 -83.460336)
		(end 190.01105 -83.439)
		(width 0.17272)
		(layer "B.Cu")
		(net "SMB_P52V_VPDB_SDA")
	)
	(segment
		(start 134.09295 -76.327)
		(end 134.09295 -77.597)
		(width 0.17272)
		(layer "B.Cu")
		(net "SMB_P52V_VPDB_SDA")
	)
	(segment
		(start 98.40595 -77.47)
		(end 98.40595 -76.327)
		(width 0.17272)
		(layer "B.Cu")
		(net "SMB_P52V_VPDB_SDA")
	)
	(segment
		(start 98.40595 -78.613)
		(end 98.40595 -77.47)
		(width 0.17272)
		(layer "B.Cu")
		(net "SMB_P52V_VPDB_SDA")
	)
	(segment
		(start 186.70905 -83.439)
		(end 186.70905 -82.804)
		(width 0.17272)
		(layer "B.Cu")
		(net "SMB_P52V_VPDB_SDA")
	)
	(segment
		(start 191.5795 -85.178646)
		(end 191.5795 -85.028786)
		(width 0.17272)
		(layer "B.Cu")
		(net "SMB_P52V_VPDB_SDA")
	)
	(segment
		(start 189.349126 -84.12226)
		(end 190.01105 -83.460336)
		(width 0.17272)
		(layer "B.Cu")
		(net "SMB_P52V_VPDB_SDA")
	)
	(segment
		(start 137.063226 -80.3656)
		(end 135.46455 -80.3656)
		(width 0.17272)
		(layer "B.Cu")
		(net "SMB_P52V_VPDB_SDA")
	)
	(segment
		(start 134.09295 -78.994)
		(end 134.09295 -78.867)
		(width 0.17272)
		(layer "B.Cu")
		(net "SMB_P52V_VPDB_SDA")
	)
	(segment
		(start 135.46455 -80.3656)
		(end 134.09295 -78.994)
		(width 0.17272)
		(layer "B.Cu")
		(net "SMB_P52V_VPDB_SDA")
	)
	(segment
		(start 172.8216 -78.867)
		(end 174.093124 -78.867)
		(width 0.17272)
		(layer "B.Cu")
		(net "SMB_P52V_VPDB_SDA")
	)
	(segment
		(start 134.09295 -77.597)
		(end 134.09295 -78.867)
		(width 0.17272)
		(layer "B.Cu")
		(net "SMB_P52V_VPDB_SDA")
	)
	(segment
		(start 97.272602 -80.3656)
		(end 97.688146 -80.3656)
		(width 0.17272)
		(layer "B.Cu")
		(net "SMB_P52V_VPDB_SDA")
	)
	(segment
		(start 54.08295 -78.613)
		(end 54.08295 -77.47)
		(width 0.17272)
		(layer "B.Cu")
		(net "SMB_P52V_VPDB_SDA")
	)
	(segment
		(start 191.5795 -85.028786)
		(end 190.01105 -83.460336)
		(width 0.17272)
		(layer "B.Cu")
		(net "SMB_P52V_VPDB_SDA")
	)
	(segment
		(start 192.517776 -86.116922)
		(end 191.5795 -85.178646)
		(width 0.17272)
		(layer "B.Cu")
		(net "SMB_P52V_VPDB_SDA")
	)
	(segment
		(start 186.436 -86.614)
		(end 183.3118 -86.614)
		(width 0.12954)
		(layer "In7.Cu")
		(net "SMB_P52V_VPDB_SDA")
	)
	(segment
		(start 171.323 -80.3656)
		(end 137.063226 -80.3656)
		(width 0.12954)
		(layer "In7.Cu")
		(net "SMB_P52V_VPDB_SDA")
	)
	(segment
		(start 186.70905 -82.804)
		(end 187.198 -83.29295)
		(width 0.12954)
		(layer "In7.Cu")
		(net "SMB_P52V_VPDB_SDA")
	)
	(segment
		(start 187.198 -85.852)
		(end 186.436 -86.614)
		(width 0.12954)
		(layer "In7.Cu")
		(net "SMB_P52V_VPDB_SDA")
	)
	(segment
		(start 97.272602 -80.3656)
		(end 54.31155 -80.3656)
		(width 0.12954)
		(layer "In7.Cu")
		(net "SMB_P52V_VPDB_SDA")
	)
	(segment
		(start 137.063226 -80.3656)
		(end 97.272602 -80.3656)
		(width 0.12954)
		(layer "In7.Cu")
		(net "SMB_P52V_VPDB_SDA")
	)
	(segment
		(start 187.198 -83.29295)
		(end 187.198 -85.852)
		(width 0.12954)
		(layer "In7.Cu")
		(net "SMB_P52V_VPDB_SDA")
	)
	(segment
		(start 183.3118 -86.614)
		(end 177.0888 -80.391)
		(width 0.12954)
		(layer "In7.Cu")
		(net "SMB_P52V_VPDB_SDA")
	)
	(segment
		(start 174.3456 -80.391)
		(end 172.8216 -78.867)
		(width 0.12954)
		(layer "In7.Cu")
		(net "SMB_P52V_VPDB_SDA")
	)
	(segment
		(start 54.31155 -80.3656)
		(end 54.08295 -80.137)
		(width 0.12954)
		(layer "In7.Cu")
		(net "SMB_P52V_VPDB_SDA")
	)
	(segment
		(start 177.0888 -80.391)
		(end 174.3456 -80.391)
		(width 0.12954)
		(layer "In7.Cu")
		(net "SMB_P52V_VPDB_SDA")
	)
	(segment
		(start 172.8216 -78.867)
		(end 171.323 -80.3656)
		(width 0.12954)
		(layer "In7.Cu")
		(net "SMB_P52V_VPDB_SDA")
	)
	(segment
		(start 303.126394 -83.5025)
		(end 302.338994 -83.5025)
		(width 0.4572)
		(layer "F.Cu")
		(net "P52V_HS1_SENSE_P_R2")
	)
	(segment
		(start 302.338994 -86.8045)
		(end 302.338994 -85.2805)
		(width 0.4572)
		(layer "F.Cu")
		(net "P52V_HS1_SENSE_P_R2")
	)
	(segment
		(start 300.408086 -78.217268)
		(end 300.139354 -78.217268)
		(width 0.254)
		(layer "F.Cu")
		(net "P52V_HS1_SENSE_P_R2")
	)
	(segment
		(start 302.338994 -85.2805)
		(end 302.338994 -83.5025)
		(width 0.4572)
		(layer "F.Cu")
		(net "P52V_HS1_SENSE_P_R2")
	)
	(segment
		(start 300.139354 -78.217268)
		(end 299.631354 -77.709268)
		(width 0.254)
		(layer "F.Cu")
		(net "P52V_HS1_SENSE_P_R2")
	)
	(via
		(at 303.126394 -83.5025)
		(size 0.508)
		(drill 0.254)
		(layers "F.Cu" "B.Cu")
		(net "P52V_HS1_SENSE_P_R2")
	)
	(via
		(at 299.631354 -77.709268)
		(size 0.508)
		(drill 0.254)
		(layers "F.Cu" "B.Cu")
		(net "P52V_HS1_SENSE_P_R2")
	)
	(segment
		(start 303.126394 -83.5025)
		(end 301.87138 -83.5025)
		(width 0.4572)
		(layer "B.Cu")
		(net "P52V_HS1_SENSE_P_R2")
	)
	(segment
		(start 300.34992 -78.427834)
		(end 299.631354 -77.709268)
		(width 0.4572)
		(layer "B.Cu")
		(net "P52V_HS1_SENSE_P_R2")
	)
	(segment
		(start 300.34992 -81.98104)
		(end 300.34992 -78.427834)
		(width 0.4572)
		(layer "B.Cu")
		(net "P52V_HS1_SENSE_P_R2")
	)
	(segment
		(start 301.87138 -83.5025)
		(end 300.34992 -81.98104)
		(width 0.4572)
		(layer "B.Cu")
		(net "P52V_HS1_SENSE_P_R2")
	)
	(segment
		(start 295.92778 -83.5025)
		(end 296.801794 -83.5025)
		(width 0.4572)
		(layer "F.Cu")
		(net "P52V_HS1_SENSE_N_R2")
	)
	(segment
		(start 296.801794 -85.2805)
		(end 296.801794 -83.5025)
		(width 0.4572)
		(layer "F.Cu")
		(net "P52V_HS1_SENSE_N_R2")
	)
	(segment
		(start 299.123354 -78.217268)
		(end 299.631354 -78.725268)
		(width 0.254)
		(layer "F.Cu")
		(net "P52V_HS1_SENSE_N_R2")
	)
	(segment
		(start 298.854622 -78.217268)
		(end 299.123354 -78.217268)
		(width 0.254)
		(layer "F.Cu")
		(net "P52V_HS1_SENSE_N_R2")
	)
	(segment
		(start 296.801794 -86.8045)
		(end 296.801794 -85.2805)
		(width 0.4572)
		(layer "F.Cu")
		(net "P52V_HS1_SENSE_N_R2")
	)
	(via
		(at 299.631354 -78.725268)
		(size 0.508)
		(drill 0.254)
		(layers "F.Cu" "B.Cu")
		(net "P52V_HS1_SENSE_N_R2")
	)
	(via
		(at 295.92778 -83.5025)
		(size 0.508)
		(drill 0.254)
		(layers "F.Cu" "B.Cu")
		(net "P52V_HS1_SENSE_N_R2")
	)
	(segment
		(start 299.631354 -78.725268)
		(end 299.76572 -78.859634)
		(width 0.4572)
		(layer "B.Cu")
		(net "P52V_HS1_SENSE_N_R2")
	)
	(segment
		(start 298.236386 -83.5025)
		(end 295.92778 -83.5025)
		(width 0.4572)
		(layer "B.Cu")
		(net "P52V_HS1_SENSE_N_R2")
	)
	(segment
		(start 299.76572 -78.859634)
		(end 299.76572 -81.973166)
		(width 0.4572)
		(layer "B.Cu")
		(net "P52V_HS1_SENSE_N_R2")
	)
	(segment
		(start 299.76572 -81.973166)
		(end 298.236386 -83.5025)
		(width 0.4572)
		(layer "B.Cu")
		(net "P52V_HS1_SENSE_N_R2")
	)
	(via
		(at 196.95795 -92.583)
		(size 0.6604)
		(drill 0.3302)
		(layers "F.Cu" "B.Cu")
		(net "RST_SMB_PDB_BUF_R1_N")
	)
	(segment
		(start 196.95795 -92.583)
		(end 196.95795 -91.07805)
		(width 0.17272)
		(layer "B.Cu")
		(net "RST_SMB_PDB_BUF_R1_N")
	)
	(segment
		(start 196.95795 -91.07805)
		(end 198.018908 -90.017092)
		(width 0.17272)
		(layer "B.Cu")
		(net "RST_SMB_PDB_BUF_R1_N")
	)
	(segment
		(start 196.95795 -93.853)
		(end 196.95795 -92.583)
		(width 0.17272)
		(layer "B.Cu")
		(net "RST_SMB_PDB_BUF_R1_N")
	)
	(segment
		(start 198.018908 -90.017092)
		(end 198.81088 -90.017092)
		(width 0.17272)
		(layer "B.Cu")
		(net "RST_SMB_PDB_BUF_R1_N")
	)
	(via
		(at 322.961 -71.628)
		(size 0.6604)
		(drill 0.3302)
		(layers "F.Cu" "B.Cu")
		(net "TP_J5_D1")
	)
	(segment
		(start 321.709034 -72.879966)
		(end 319.030096 -72.879966)
		(width 0.17272)
		(layer "B.Cu")
		(net "TP_J5_D1")
	)
	(segment
		(start 322.961 -71.628)
		(end 321.709034 -72.879966)
		(width 0.17272)
		(layer "B.Cu")
		(net "TP_J5_D1")
	)
	(via
		(at 322.58 -73.66)
		(size 0.6604)
		(drill 0.3302)
		(layers "F.Cu" "B.Cu")
		(net "TP_J5_C1")
	)
	(segment
		(start 322.0974 -74.1426)
		(end 317.75273 -74.1426)
		(width 0.17272)
		(layer "B.Cu")
		(net "TP_J5_C1")
	)
	(segment
		(start 322.58 -73.66)
		(end 322.0974 -74.1426)
		(width 0.17272)
		(layer "B.Cu")
		(net "TP_J5_C1")
	)
	(segment
		(start 317.75273 -74.1426)
		(end 316.490096 -72.879966)
		(width 0.17272)
		(layer "B.Cu")
		(net "TP_J5_C1")
	)
	(via
		(at 240.157 -81.026)
		(size 0.6604)
		(drill 0.3302)
		(layers "F.Cu" "B.Cu")
		(net "NC_U1_READY")
	)
	(segment
		(start 239.268 -81.026)
		(end 240.157 -81.026)
		(width 0.17272)
		(layer "B.Cu")
		(net "NC_U1_READY")
	)
	(segment
		(start 239.02289 -81.27111)
		(end 239.268 -81.026)
		(width 0.17272)
		(layer "B.Cu")
		(net "NC_U1_READY")
	)
	(segment
		(start 239.02289 -81.939384)
		(end 239.02289 -81.27111)
		(width 0.17272)
		(layer "B.Cu")
		(net "NC_U1_READY")
	)
	(via
		(at 211.709 -85.598)
		(size 0.6604)
		(drill 0.3302)
		(layers "F.Cu" "B.Cu")
		(net "NC_U6")
	)
	(segment
		(start 211.088986 -86.93404)
		(end 211.088986 -86.218014)
		(width 0.17272)
		(layer "B.Cu")
		(net "NC_U6")
	)
	(segment
		(start 211.088986 -86.218014)
		(end 211.709 -85.598)
		(width 0.17272)
		(layer "B.Cu")
		(net "NC_U6")
	)
	(via
		(at 200.914 -91.948)
		(size 0.6604)
		(drill 0.3302)
		(layers "F.Cu" "B.Cu")
		(net "PCA9543_MISC_A0")
	)
	(segment
		(start 199.521064 -91.317064)
		(end 198.81088 -91.317064)
		(width 0.17272)
		(layer "B.Cu")
		(net "PCA9543_MISC_A0")
	)
	(segment
		(start 200.152 -91.948)
		(end 199.521064 -91.317064)
		(width 0.17272)
		(layer "B.Cu")
		(net "PCA9543_MISC_A0")
	)
	(segment
		(start 200.914 -91.948)
		(end 200.152 -91.948)
		(width 0.17272)
		(layer "B.Cu")
		(net "PCA9543_MISC_A0")
	)
	(segment
		(start 203.089256 -92.56776)
		(end 202.54595 -92.024454)
		(width 0.17272)
		(layer "B.Cu")
		(net "PCA9543_MISC_A0")
	)
	(segment
		(start 202.54595 -92.024454)
		(end 202.54595 -91.948)
		(width 0.17272)
		(layer "B.Cu")
		(net "PCA9543_MISC_A0")
	)
	(segment
		(start 204.72019 -92.56776)
		(end 203.089256 -92.56776)
		(width 0.17272)
		(layer "B.Cu")
		(net "PCA9543_MISC_A0")
	)
	(segment
		(start 205.33995 -91.948)
		(end 204.72019 -92.56776)
		(width 0.17272)
		(layer "B.Cu")
		(net "PCA9543_MISC_A0")
	)
	(segment
		(start 202.54595 -91.948)
		(end 200.914 -91.948)
		(width 0.17272)
		(layer "B.Cu")
		(net "PCA9543_MISC_A0")
	)
	(via
		(at 201.168 -90.932)
		(size 0.762)
		(drill 0.254)
		(layers "F.Cu" "B.Cu")
		(net "PCA9543_MISC_A1")
	)
	(segment
		(start 202.54595 -90.754454)
		(end 202.54595 -90.678)
		(width 0.17272)
		(layer "B.Cu")
		(net "PCA9543_MISC_A1")
	)
	(segment
		(start 204.72019 -91.29776)
		(end 203.089256 -91.29776)
		(width 0.17272)
		(layer "B.Cu")
		(net "PCA9543_MISC_A1")
	)
	(segment
		(start 200.278746 -90.932)
		(end 200.013824 -90.667078)
		(width 0.17272)
		(layer "B.Cu")
		(net "PCA9543_MISC_A1")
	)
	(segment
		(start 201.930254 -90.678)
		(end 201.676254 -90.932)
		(width 0.17272)
		(layer "B.Cu")
		(net "PCA9543_MISC_A1")
	)
	(segment
		(start 201.676254 -90.932)
		(end 201.168 -90.932)
		(width 0.17272)
		(layer "B.Cu")
		(net "PCA9543_MISC_A1")
	)
	(segment
		(start 203.089256 -91.29776)
		(end 202.54595 -90.754454)
		(width 0.17272)
		(layer "B.Cu")
		(net "PCA9543_MISC_A1")
	)
	(segment
		(start 201.168 -90.932)
		(end 200.278746 -90.932)
		(width 0.17272)
		(layer "B.Cu")
		(net "PCA9543_MISC_A1")
	)
	(segment
		(start 200.013824 -90.667078)
		(end 198.81088 -90.667078)
		(width 0.17272)
		(layer "B.Cu")
		(net "PCA9543_MISC_A1")
	)
	(segment
		(start 205.33995 -90.678)
		(end 204.72019 -91.29776)
		(width 0.17272)
		(layer "B.Cu")
		(net "PCA9543_MISC_A1")
	)
	(segment
		(start 202.54595 -90.678)
		(end 201.930254 -90.678)
		(width 0.17272)
		(layer "B.Cu")
		(net "PCA9543_MISC_A1")
	)
	(via
		(at 192.786 -92.837)
		(size 0.6604)
		(drill 0.3302)
		(layers "F.Cu" "B.Cu")
		(net "TP_9543_MISC_INT_N")
	)
	(segment
		(start 194.056 -91.567)
		(end 192.786 -92.837)
		(width 0.17272)
		(layer "B.Cu")
		(net "TP_9543_MISC_INT_N")
	)
	(segment
		(start 193.88328 -89.367106)
		(end 194.056 -89.539826)
		(width 0.17272)
		(layer "B.Cu")
		(net "TP_9543_MISC_INT_N")
	)
	(segment
		(start 194.056 -89.539826)
		(end 194.056 -91.567)
		(width 0.17272)
		(layer "B.Cu")
		(net "TP_9543_MISC_INT_N")
	)
	(segment
		(start 193.11112 -89.367106)
		(end 193.88328 -89.367106)
		(width 0.17272)
		(layer "B.Cu")
		(net "TP_9543_MISC_INT_N")
	)
	(via
		(at 191.4017 -87.416894)
		(size 0.6604)
		(drill 0.3302)
		(layers "F.Cu" "B.Cu")
		(net "PU_9543_1_INT1")
	)
	(segment
		(start 190.01105 -86.995)
		(end 190.711074 -86.995)
		(width 0.17272)
		(layer "B.Cu")
		(net "PU_9543_1_INT1")
	)
	(segment
		(start 191.132968 -87.416894)
		(end 191.4017 -87.416894)
		(width 0.17272)
		(layer "B.Cu")
		(net "PU_9543_1_INT1")
	)
	(segment
		(start 191.4017 -87.416894)
		(end 193.11112 -87.416894)
		(width 0.17272)
		(layer "B.Cu")
		(net "PU_9543_1_INT1")
	)
	(segment
		(start 190.711074 -86.995)
		(end 191.132968 -87.416894)
		(width 0.17272)
		(layer "B.Cu")
		(net "PU_9543_1_INT1")
	)
	(via
		(at 191.389 -82.804)
		(size 0.6604)
		(drill 0.3302)
		(layers "F.Cu" "B.Cu")
		(net "PU_9543_1_INT0")
	)
	(segment
		(start 191.008 -82.423)
		(end 190.01105 -82.423)
		(width 0.17272)
		(layer "B.Cu")
		(net "PU_9543_1_INT0")
	)
	(segment
		(start 191.389 -82.804)
		(end 192.151 -83.566)
		(width 0.17272)
		(layer "B.Cu")
		(net "PU_9543_1_INT0")
	)
	(segment
		(start 192.151 -83.566)
		(end 192.151 -84.922868)
		(width 0.17272)
		(layer "B.Cu")
		(net "PU_9543_1_INT0")
	)
	(segment
		(start 192.695068 -85.466936)
		(end 193.11112 -85.466936)
		(width 0.17272)
		(layer "B.Cu")
		(net "PU_9543_1_INT0")
	)
	(segment
		(start 191.389 -82.804)
		(end 191.008 -82.423)
		(width 0.17272)
		(layer "B.Cu")
		(net "PU_9543_1_INT0")
	)
	(segment
		(start 192.151 -84.922868)
		(end 192.695068 -85.466936)
		(width 0.17272)
		(layer "B.Cu")
		(net "PU_9543_1_INT0")
	)
	(via
		(at 200.84542 -89.367106)
		(size 0.6604)
		(drill 0.3302)
		(layers "F.Cu" "B.Cu")
		(net "PU_9543_0_INT0")
	)
	(segment
		(start 200.84542 -89.367106)
		(end 202.505056 -89.367106)
		(width 0.17272)
		(layer "B.Cu")
		(net "PU_9543_0_INT0")
	)
	(segment
		(start 198.81088 -89.367106)
		(end 200.84542 -89.367106)
		(width 0.17272)
		(layer "B.Cu")
		(net "PU_9543_0_INT0")
	)
	(segment
		(start 202.505056 -89.367106)
		(end 202.54595 -89.408)
		(width 0.17272)
		(layer "B.Cu")
		(net "PU_9543_0_INT0")
	)
	(via
		(at 226.231704 -69.24548)
		(size 0.6604)
		(drill 0.3302)
		(layers "F.Cu" "B.Cu")
		(net "P12V_BRICK_PWRGD_R_N")
	)
	(segment
		(start 228.219 -70.59295)
		(end 227.203 -70.59295)
		(width 0.17272)
		(layer "B.Cu")
		(net "P12V_BRICK_PWRGD_R_N")
	)
	(segment
		(start 204.26172 -32.298894)
		(end 204.26172 -40.812466)
		(width 0.17272)
		(layer "B.Cu")
		(net "P12V_BRICK_PWRGD_R_N")
	)
	(segment
		(start 204.26172 -40.812466)
		(end 208.463642 -45.014388)
		(width 0.17272)
		(layer "B.Cu")
		(net "P12V_BRICK_PWRGD_R_N")
	)
	(segment
		(start 228.219 -70.59295)
		(end 226.87153 -69.24548)
		(width 0.17272)
		(layer "B.Cu")
		(net "P12V_BRICK_PWRGD_R_N")
	)
	(segment
		(start 226.87153 -69.24548)
		(end 226.231704 -69.24548)
		(width 0.17272)
		(layer "B.Cu")
		(net "P12V_BRICK_PWRGD_R_N")
	)
	(segment
		(start 224.392998 -69.24548)
		(end 226.231704 -69.24548)
		(width 0.17272)
		(layer "B.Cu")
		(net "P12V_BRICK_PWRGD_R_N")
	)
	(segment
		(start 208.463642 -45.014388)
		(end 214.152734 -45.014388)
		(width 0.17272)
		(layer "B.Cu")
		(net "P12V_BRICK_PWRGD_R_N")
	)
	(segment
		(start 206.389986 -30.329632)
		(end 206.230982 -30.329632)
		(width 0.17272)
		(layer "B.Cu")
		(net "P12V_BRICK_PWRGD_R_N")
	)
	(segment
		(start 217.28684 -62.139322)
		(end 224.392998 -69.24548)
		(width 0.17272)
		(layer "B.Cu")
		(net "P12V_BRICK_PWRGD_R_N")
	)
	(segment
		(start 214.152734 -45.014388)
		(end 217.28684 -48.148494)
		(width 0.17272)
		(layer "B.Cu")
		(net "P12V_BRICK_PWRGD_R_N")
	)
	(segment
		(start 217.28684 -48.148494)
		(end 217.28684 -62.139322)
		(width 0.17272)
		(layer "B.Cu")
		(net "P12V_BRICK_PWRGD_R_N")
	)
	(segment
		(start 206.230982 -30.329632)
		(end 204.26172 -32.298894)
		(width 0.17272)
		(layer "B.Cu")
		(net "P12V_BRICK_PWRGD_R_N")
	)
	(segment
		(start 64.470026 -121.209816)
		(end 65.829434 -122.569224)
		(width 0.889)
		(layer "F.Cu")
		(net "P52V_HS_FILTER")
	)
	(segment
		(start 54.238906 -136.906)
		(end 55.204614 -135.940292)
		(width 0.635)
		(layer "F.Cu")
		(net "P52V_HS_FILTER")
	)
	(segment
		(start 161.081466 -137.871708)
		(end 162.047174 -136.906)
		(width 0.635)
		(layer "F.Cu")
		(net "P52V_HS_FILTER")
	)
	(segment
		(start 63.110618 -122.569224)
		(end 64.470026 -121.209816)
		(width 0.889)
		(layer "F.Cu")
		(net "P52V_HS_FILTER")
	)
	(segment
		(start 81.081118 -137.871708)
		(end 82.046826 -136.906)
		(width 0.635)
		(layer "F.Cu")
		(net "P52V_HS_FILTER")
	)
	(segment
		(start 183.110886 -119.850408)
		(end 184.470294 -121.209816)
		(width 0.889)
		(layer "F.Cu")
		(net "P52V_HS_FILTER")
	)
	(segment
		(start 122.047 -136.906)
		(end 123.012708 -135.940292)
		(width 0.635)
		(layer "F.Cu")
		(net "P52V_HS_FILTER")
	)
	(segment
		(start 121.081292 -137.871708)
		(end 122.047 -136.906)
		(width 0.635)
		(layer "F.Cu")
		(net "P52V_HS_FILTER")
	)
	(segment
		(start 104.469946 -121.209816)
		(end 105.829354 -122.569224)
		(width 0.889)
		(layer "F.Cu")
		(net "P52V_HS_FILTER")
	)
	(segment
		(start 133.273292 -135.940292)
		(end 134.239 -136.906)
		(width 0.635)
		(layer "F.Cu")
		(net "P52V_HS_FILTER")
	)
	(segment
		(start 81.081118 -135.940292)
		(end 82.046826 -136.906)
		(width 0.635)
		(layer "F.Cu")
		(net "P52V_HS_FILTER")
	)
	(segment
		(start 104.469946 -121.209816)
		(end 105.829354 -119.850408)
		(width 0.889)
		(layer "F.Cu")
		(net "P52V_HS_FILTER")
	)
	(segment
		(start 103.110538 -122.569224)
		(end 104.469946 -121.209816)
		(width 0.889)
		(layer "F.Cu")
		(net "P52V_HS_FILTER")
	)
	(segment
		(start 65.465198 -137.871708)
		(end 66.430906 -136.906)
		(width 0.635)
		(layer "F.Cu")
		(net "P52V_HS_FILTER")
	)
	(segment
		(start 186.431174 -136.906)
		(end 187.396882 -135.940292)
		(width 0.635)
		(layer "F.Cu")
		(net "P52V_HS_FILTER")
	)
	(segment
		(start 161.081466 -135.940292)
		(end 162.047174 -136.906)
		(width 0.635)
		(layer "F.Cu")
		(net "P52V_HS_FILTER")
	)
	(segment
		(start 53.273198 -135.940292)
		(end 54.238906 -136.906)
		(width 0.635)
		(layer "F.Cu")
		(net "P52V_HS_FILTER")
	)
	(segment
		(start 103.110538 -119.850408)
		(end 104.469946 -121.209816)
		(width 0.889)
		(layer "F.Cu")
		(net "P52V_HS_FILTER")
	)
	(segment
		(start 42.046906 -136.906)
		(end 43.012614 -137.871708)
		(width 0.635)
		(layer "F.Cu")
		(net "P52V_HS_FILTER")
	)
	(segment
		(start 105.465118 -135.940292)
		(end 106.430826 -136.906)
		(width 0.635)
		(layer "F.Cu")
		(net "P52V_HS_FILTER")
	)
	(segment
		(start 63.110618 -119.850408)
		(end 64.470026 -121.209816)
		(width 0.889)
		(layer "F.Cu")
		(net "P52V_HS_FILTER")
	)
	(segment
		(start 41.081198 -137.871708)
		(end 42.046906 -136.906)
		(width 0.635)
		(layer "F.Cu")
		(net "P52V_HS_FILTER")
	)
	(segment
		(start 66.430906 -136.906)
		(end 67.396614 -137.871708)
		(width 0.635)
		(layer "F.Cu")
		(net "P52V_HS_FILTER")
	)
	(segment
		(start 82.046826 -136.906)
		(end 83.012534 -135.940292)
		(width 0.635)
		(layer "F.Cu")
		(net "P52V_HS_FILTER")
	)
	(segment
		(start 42.046906 -136.906)
		(end 43.012614 -135.940292)
		(width 0.635)
		(layer "F.Cu")
		(net "P52V_HS_FILTER")
	)
	(segment
		(start 134.239 -136.906)
		(end 135.204708 -137.871708)
		(width 0.635)
		(layer "F.Cu")
		(net "P52V_HS_FILTER")
	)
	(segment
		(start 173.273466 -135.940292)
		(end 174.239174 -136.906)
		(width 0.635)
		(layer "F.Cu")
		(net "P52V_HS_FILTER")
	)
	(segment
		(start 146.431 -136.906)
		(end 147.396708 -137.871708)
		(width 0.635)
		(layer "F.Cu")
		(net "P52V_HS_FILTER")
	)
	(segment
		(start 162.047174 -136.906)
		(end 163.012882 -135.940292)
		(width 0.635)
		(layer "F.Cu")
		(net "P52V_HS_FILTER")
	)
	(segment
		(start 64.470026 -121.209816)
		(end 65.829434 -119.850408)
		(width 0.889)
		(layer "F.Cu")
		(net "P52V_HS_FILTER")
	)
	(segment
		(start 174.239174 -136.906)
		(end 175.204882 -135.940292)
		(width 0.635)
		(layer "F.Cu")
		(net "P52V_HS_FILTER")
	)
	(segment
		(start 133.273292 -137.871708)
		(end 134.239 -136.906)
		(width 0.635)
		(layer "F.Cu")
		(net "P52V_HS_FILTER")
	)
	(segment
		(start 184.470294 -121.209816)
		(end 185.829702 -122.569224)
		(width 0.889)
		(layer "F.Cu")
		(net "P52V_HS_FILTER")
	)
	(segment
		(start 185.465466 -137.871708)
		(end 186.431174 -136.906)
		(width 0.635)
		(layer "F.Cu")
		(net "P52V_HS_FILTER")
	)
	(segment
		(start 146.431 -136.906)
		(end 147.396708 -135.940292)
		(width 0.635)
		(layer "F.Cu")
		(net "P52V_HS_FILTER")
	)
	(segment
		(start 185.465466 -135.940292)
		(end 186.431174 -136.906)
		(width 0.635)
		(layer "F.Cu")
		(net "P52V_HS_FILTER")
	)
	(segment
		(start 106.430826 -136.906)
		(end 107.396534 -135.940292)
		(width 0.635)
		(layer "F.Cu")
		(net "P52V_HS_FILTER")
	)
	(segment
		(start 94.238826 -136.906)
		(end 95.204534 -135.940292)
		(width 0.635)
		(layer "F.Cu")
		(net "P52V_HS_FILTER")
	)
	(segment
		(start 94.238826 -136.906)
		(end 95.204534 -137.871708)
		(width 0.635)
		(layer "F.Cu")
		(net "P52V_HS_FILTER")
	)
	(segment
		(start 93.273118 -137.871708)
		(end 94.238826 -136.906)
		(width 0.635)
		(layer "F.Cu")
		(net "P52V_HS_FILTER")
	)
	(segment
		(start 134.239 -136.906)
		(end 135.204708 -135.940292)
		(width 0.635)
		(layer "F.Cu")
		(net "P52V_HS_FILTER")
	)
	(segment
		(start 93.273118 -135.940292)
		(end 94.238826 -136.906)
		(width 0.635)
		(layer "F.Cu")
		(net "P52V_HS_FILTER")
	)
	(segment
		(start 143.110712 -122.569224)
		(end 144.47012 -121.209816)
		(width 0.889)
		(layer "F.Cu")
		(net "P52V_HS_FILTER")
	)
	(segment
		(start 122.047 -136.906)
		(end 123.012708 -137.871708)
		(width 0.635)
		(layer "F.Cu")
		(net "P52V_HS_FILTER")
	)
	(segment
		(start 105.465118 -137.871708)
		(end 106.430826 -136.906)
		(width 0.635)
		(layer "F.Cu")
		(net "P52V_HS_FILTER")
	)
	(segment
		(start 184.470294 -121.209816)
		(end 185.829702 -119.850408)
		(width 0.889)
		(layer "F.Cu")
		(net "P52V_HS_FILTER")
	)
	(segment
		(start 53.273198 -137.871708)
		(end 54.238906 -136.906)
		(width 0.635)
		(layer "F.Cu")
		(net "P52V_HS_FILTER")
	)
	(segment
		(start 145.465292 -135.940292)
		(end 146.431 -136.906)
		(width 0.635)
		(layer "F.Cu")
		(net "P52V_HS_FILTER")
	)
	(segment
		(start 174.239174 -136.906)
		(end 175.204882 -137.871708)
		(width 0.635)
		(layer "F.Cu")
		(net "P52V_HS_FILTER")
	)
	(segment
		(start 183.110886 -122.569224)
		(end 184.470294 -121.209816)
		(width 0.889)
		(layer "F.Cu")
		(net "P52V_HS_FILTER")
	)
	(segment
		(start 144.47012 -121.209816)
		(end 145.829528 -119.850408)
		(width 0.889)
		(layer "F.Cu")
		(net "P52V_HS_FILTER")
	)
	(segment
		(start 66.430906 -136.906)
		(end 67.396614 -135.940292)
		(width 0.635)
		(layer "F.Cu")
		(net "P52V_HS_FILTER")
	)
	(segment
		(start 186.431174 -136.906)
		(end 187.396882 -137.871708)
		(width 0.635)
		(layer "F.Cu")
		(net "P52V_HS_FILTER")
	)
	(segment
		(start 82.046826 -136.906)
		(end 83.012534 -137.871708)
		(width 0.635)
		(layer "F.Cu")
		(net "P52V_HS_FILTER")
	)
	(segment
		(start 143.110712 -119.850408)
		(end 144.47012 -121.209816)
		(width 0.889)
		(layer "F.Cu")
		(net "P52V_HS_FILTER")
	)
	(segment
		(start 144.47012 -121.209816)
		(end 145.829528 -122.569224)
		(width 0.889)
		(layer "F.Cu")
		(net "P52V_HS_FILTER")
	)
	(segment
		(start 54.238906 -136.906)
		(end 55.204614 -137.871708)
		(width 0.635)
		(layer "F.Cu")
		(net "P52V_HS_FILTER")
	)
	(segment
		(start 145.465292 -137.871708)
		(end 146.431 -136.906)
		(width 0.635)
		(layer "F.Cu")
		(net "P52V_HS_FILTER")
	)
	(segment
		(start 173.273466 -137.871708)
		(end 174.239174 -136.906)
		(width 0.635)
		(layer "F.Cu")
		(net "P52V_HS_FILTER")
	)
	(segment
		(start 41.081198 -135.940292)
		(end 42.046906 -136.906)
		(width 0.635)
		(layer "F.Cu")
		(net "P52V_HS_FILTER")
	)
	(segment
		(start 65.465198 -135.940292)
		(end 66.430906 -136.906)
		(width 0.635)
		(layer "F.Cu")
		(net "P52V_HS_FILTER")
	)
	(segment
		(start 162.047174 -136.906)
		(end 163.012882 -137.871708)
		(width 0.635)
		(layer "F.Cu")
		(net "P52V_HS_FILTER")
	)
	(segment
		(start 106.430826 -136.906)
		(end 107.396534 -137.871708)
		(width 0.635)
		(layer "F.Cu")
		(net "P52V_HS_FILTER")
	)
	(segment
		(start 121.081292 -135.940292)
		(end 122.047 -136.906)
		(width 0.635)
		(layer "F.Cu")
		(net "P52V_HS_FILTER")
	)
	(via
		(at 216.936828 -130.66014)
		(size 0.508)
		(drill 0.254)
		(layers "F.Cu" "B.Cu")
		(net "P52V_HS_FILTER")
	)
	(via
		(at 215.458802 -130.66014)
		(size 0.508)
		(drill 0.254)
		(layers "F.Cu" "B.Cu")
		(net "P52V_HS_FILTER")
	)
	(via
		(at 216.936828 -132.94614)
		(size 0.508)
		(drill 0.254)
		(layers "F.Cu" "B.Cu")
		(net "P52V_HS_FILTER")
	)
	(via
		(at 216.936828 -129.13614)
		(size 0.508)
		(drill 0.254)
		(layers "F.Cu" "B.Cu")
		(net "P52V_HS_FILTER")
	)
	(via
		(at 123.6726 -126.492)
		(size 0.508)
		(drill 0.254)
		(layers "F.Cu" "B.Cu")
		(net "P52V_HS_FILTER")
	)
	(via
		(at 68.056506 -126.492)
		(size 0.508)
		(drill 0.254)
		(layers "F.Cu" "B.Cu")
		(net "P52V_HS_FILTER")
	)
	(via
		(at 216.936828 -131.42214)
		(size 0.508)
		(drill 0.254)
		(layers "F.Cu" "B.Cu")
		(net "P52V_HS_FILTER")
	)
	(via
		(at 218.251278 -122.047762)
		(size 0.508)
		(drill 0.254)
		(layers "F.Cu" "B.Cu")
		(net "P52V_HS_FILTER")
	)
	(via
		(at 221.299278 -122.809762)
		(size 0.508)
		(drill 0.254)
		(layers "F.Cu" "B.Cu")
		(net "P52V_HS_FILTER")
	)
	(via
		(at 216.727278 -120.569736)
		(size 0.508)
		(drill 0.254)
		(layers "F.Cu" "B.Cu")
		(net "P52V_HS_FILTER")
	)
	(via
		(at 217.489278 -121.331736)
		(size 0.508)
		(drill 0.254)
		(layers "F.Cu" "B.Cu")
		(net "P52V_HS_FILTER")
	)
	(via
		(at 206.16037 -122.809762)
		(size 0.508)
		(drill 0.254)
		(layers "F.Cu" "B.Cu")
		(net "P52V_HS_FILTER")
	)
	(via
		(at 83.672426 -131.572)
		(size 0.508)
		(drill 0.254)
		(layers "F.Cu" "B.Cu")
		(net "P52V_HS_FILTER")
	)
	(via
		(at 122.9106 -126.492)
		(size 0.508)
		(drill 0.254)
		(layers "F.Cu" "B.Cu")
		(net "P52V_HS_FILTER")
	)
	(via
		(at 175.864774 -126.492)
		(size 0.508)
		(drill 0.254)
		(layers "F.Cu" "B.Cu")
		(net "P52V_HS_FILTER")
	)
	(via
		(at 216.174828 -132.94614)
		(size 0.508)
		(drill 0.254)
		(layers "F.Cu" "B.Cu")
		(net "P52V_HS_FILTER")
	)
	(via
		(at 206.174086 -123.528328)
		(size 0.508)
		(drill 0.254)
		(layers "F.Cu" "B.Cu")
		(net "P52V_HS_FILTER")
	)
	(via
		(at 214.696802 -130.66014)
		(size 0.508)
		(drill 0.254)
		(layers "F.Cu" "B.Cu")
		(net "P52V_HS_FILTER")
	)
	(via
		(at 202.35037 -120.569736)
		(size 0.508)
		(drill 0.254)
		(layers "F.Cu" "B.Cu")
		(net "P52V_HS_FILTER")
	)
	(via
		(at 82.910426 -131.572)
		(size 0.508)
		(drill 0.254)
		(layers "F.Cu" "B.Cu")
		(net "P52V_HS_FILTER")
	)
	(via
		(at 147.2946 -131.572)
		(size 0.508)
		(drill 0.254)
		(layers "F.Cu" "B.Cu")
		(net "P52V_HS_FILTER")
	)
	(via
		(at 220.537278 -122.047762)
		(size 0.508)
		(drill 0.254)
		(layers "F.Cu" "B.Cu")
		(net "P52V_HS_FILTER")
	)
	(via
		(at 163.672774 -126.492)
		(size 0.508)
		(drill 0.254)
		(layers "F.Cu" "B.Cu")
		(net "P52V_HS_FILTER")
	)
	(via
		(at 219.026994 -123.528328)
		(size 0.508)
		(drill 0.254)
		(layers "F.Cu" "B.Cu")
		(net "P52V_HS_FILTER")
	)
	(via
		(at 206.16037 -121.331736)
		(size 0.508)
		(drill 0.254)
		(layers "F.Cu" "B.Cu")
		(net "P52V_HS_FILTER")
	)
	(via
		(at 206.16037 -120.569736)
		(size 0.508)
		(drill 0.254)
		(layers "F.Cu" "B.Cu")
		(net "P52V_HS_FILTER")
	)
	(via
		(at 205.412086 -123.528328)
		(size 0.508)
		(drill 0.254)
		(layers "F.Cu" "B.Cu")
		(net "P52V_HS_FILTER")
	)
	(via
		(at 216.174828 -130.66014)
		(size 0.508)
		(drill 0.254)
		(layers "F.Cu" "B.Cu")
		(net "P52V_HS_FILTER")
	)
	(via
		(at 219.788994 -123.528328)
		(size 0.508)
		(drill 0.254)
		(layers "F.Cu" "B.Cu")
		(net "P52V_HS_FILTER")
	)
	(via
		(at 162.910774 -126.492)
		(size 0.508)
		(drill 0.254)
		(layers "F.Cu" "B.Cu")
		(net "P52V_HS_FILTER")
	)
	(via
		(at 147.2946 -126.492)
		(size 0.508)
		(drill 0.254)
		(layers "F.Cu" "B.Cu")
		(net "P52V_HS_FILTER")
	)
	(via
		(at 214.696802 -127.61214)
		(size 0.508)
		(drill 0.254)
		(layers "F.Cu" "B.Cu")
		(net "P52V_HS_FILTER")
	)
	(via
		(at 222.061278 -121.331736)
		(size 0.508)
		(drill 0.254)
		(layers "F.Cu" "B.Cu")
		(net "P52V_HS_FILTER")
	)
	(via
		(at 214.696802 -128.37414)
		(size 0.508)
		(drill 0.254)
		(layers "F.Cu" "B.Cu")
		(net "P52V_HS_FILTER")
	)
	(via
		(at 219.775278 -122.809762)
		(size 0.508)
		(drill 0.254)
		(layers "F.Cu" "B.Cu")
		(net "P52V_HS_FILTER")
	)
	(via
		(at 95.102426 -126.492)
		(size 0.508)
		(drill 0.254)
		(layers "F.Cu" "B.Cu")
		(net "P52V_HS_FILTER")
	)
	(via
		(at 213.978236 -131.435856)
		(size 0.508)
		(drill 0.254)
		(layers "F.Cu" "B.Cu")
		(net "P52V_HS_FILTER")
	)
	(via
		(at 203.11237 -122.047762)
		(size 0.508)
		(drill 0.254)
		(layers "F.Cu" "B.Cu")
		(net "P52V_HS_FILTER")
	)
	(via
		(at 43.672506 -126.492)
		(size 0.508)
		(drill 0.254)
		(layers "F.Cu" "B.Cu")
		(net "P52V_HS_FILTER")
	)
	(via
		(at 55.102506 -126.492)
		(size 0.508)
		(drill 0.254)
		(layers "F.Cu" "B.Cu")
		(net "P52V_HS_FILTER")
	)
	(via
		(at 148.0566 -126.492)
		(size 0.508)
		(drill 0.254)
		(layers "F.Cu" "B.Cu")
		(net "P52V_HS_FILTER")
	)
	(via
		(at 213.978236 -128.387856)
		(size 0.508)
		(drill 0.254)
		(layers "F.Cu" "B.Cu")
		(net "P52V_HS_FILTER")
	)
	(via
		(at 135.8646 -131.572)
		(size 0.508)
		(drill 0.254)
		(layers "F.Cu" "B.Cu")
		(net "P52V_HS_FILTER")
	)
	(via
		(at 202.364086 -123.528328)
		(size 0.508)
		(drill 0.254)
		(layers "F.Cu" "B.Cu")
		(net "P52V_HS_FILTER")
	)
	(via
		(at 203.87437 -121.331736)
		(size 0.508)
		(drill 0.254)
		(layers "F.Cu" "B.Cu")
		(net "P52V_HS_FILTER")
	)
	(via
		(at 219.775278 -120.569736)
		(size 0.508)
		(drill 0.254)
		(layers "F.Cu" "B.Cu")
		(net "P52V_HS_FILTER")
	)
	(via
		(at 214.696802 -129.89814)
		(size 0.508)
		(drill 0.254)
		(layers "F.Cu" "B.Cu")
		(net "P52V_HS_FILTER")
	)
	(via
		(at 206.92237 -122.809762)
		(size 0.508)
		(drill 0.254)
		(layers "F.Cu" "B.Cu")
		(net "P52V_HS_FILTER")
	)
	(via
		(at 206.92237 -122.047762)
		(size 0.508)
		(drill 0.254)
		(layers "F.Cu" "B.Cu")
		(net "P52V_HS_FILTER")
	)
	(via
		(at 95.102426 -131.572)
		(size 0.508)
		(drill 0.254)
		(layers "F.Cu" "B.Cu")
		(net "P52V_HS_FILTER")
	)
	(via
		(at 42.910506 -131.572)
		(size 0.508)
		(drill 0.254)
		(layers "F.Cu" "B.Cu")
		(net "P52V_HS_FILTER")
	)
	(via
		(at 221.312994 -123.528328)
		(size 0.508)
		(drill 0.254)
		(layers "F.Cu" "B.Cu")
		(net "P52V_HS_FILTER")
	)
	(via
		(at 219.775278 -122.047762)
		(size 0.508)
		(drill 0.254)
		(layers "F.Cu" "B.Cu")
		(net "P52V_HS_FILTER")
	)
	(via
		(at 222.061278 -122.809762)
		(size 0.508)
		(drill 0.254)
		(layers "F.Cu" "B.Cu")
		(net "P52V_HS_FILTER")
	)
	(via
		(at 213.978236 -129.911856)
		(size 0.508)
		(drill 0.254)
		(layers "F.Cu" "B.Cu")
		(net "P52V_HS_FILTER")
	)
	(via
		(at 216.174828 -131.42214)
		(size 0.508)
		(drill 0.254)
		(layers "F.Cu" "B.Cu")
		(net "P52V_HS_FILTER")
	)
	(via
		(at 204.650086 -123.528328)
		(size 0.508)
		(drill 0.254)
		(layers "F.Cu" "B.Cu")
		(net "P52V_HS_FILTER")
	)
	(via
		(at 203.126086 -123.528328)
		(size 0.508)
		(drill 0.254)
		(layers "F.Cu" "B.Cu")
		(net "P52V_HS_FILTER")
	)
	(via
		(at 107.294426 -126.492)
		(size 0.508)
		(drill 0.254)
		(layers "F.Cu" "B.Cu")
		(net "P52V_HS_FILTER")
	)
	(via
		(at 68.056506 -131.572)
		(size 0.508)
		(drill 0.254)
		(layers "F.Cu" "B.Cu")
		(net "P52V_HS_FILTER")
	)
	(via
		(at 202.35037 -122.809762)
		(size 0.508)
		(drill 0.254)
		(layers "F.Cu" "B.Cu")
		(net "P52V_HS_FILTER")
	)
	(via
		(at 216.727278 -121.331736)
		(size 0.508)
		(drill 0.254)
		(layers "F.Cu" "B.Cu")
		(net "P52V_HS_FILTER")
	)
	(via
		(at 122.9106 -131.572)
		(size 0.508)
		(drill 0.254)
		(layers "F.Cu" "B.Cu")
		(net "P52V_HS_FILTER")
	)
	(via
		(at 216.174828 -128.37414)
		(size 0.508)
		(drill 0.254)
		(layers "F.Cu" "B.Cu")
		(net "P52V_HS_FILTER")
	)
	(via
		(at 216.936828 -127.61214)
		(size 0.508)
		(drill 0.254)
		(layers "F.Cu" "B.Cu")
		(net "P52V_HS_FILTER")
	)
	(via
		(at 214.696802 -129.13614)
		(size 0.508)
		(drill 0.254)
		(layers "F.Cu" "B.Cu")
		(net "P52V_HS_FILTER")
	)
	(via
		(at 221.299278 -122.047762)
		(size 0.508)
		(drill 0.254)
		(layers "F.Cu" "B.Cu")
		(net "P52V_HS_FILTER")
	)
	(via
		(at 216.174828 -132.18414)
		(size 0.508)
		(drill 0.254)
		(layers "F.Cu" "B.Cu")
		(net "P52V_HS_FILTER")
	)
	(via
		(at 207.698086 -123.528328)
		(size 0.508)
		(drill 0.254)
		(layers "F.Cu" "B.Cu")
		(net "P52V_HS_FILTER")
	)
	(via
		(at 203.888086 -123.528328)
		(size 0.508)
		(drill 0.254)
		(layers "F.Cu" "B.Cu")
		(net "P52V_HS_FILTER")
	)
	(via
		(at 216.936828 -132.18414)
		(size 0.508)
		(drill 0.254)
		(layers "F.Cu" "B.Cu")
		(net "P52V_HS_FILTER")
	)
	(via
		(at 216.174828 -129.13614)
		(size 0.508)
		(drill 0.254)
		(layers "F.Cu" "B.Cu")
		(net "P52V_HS_FILTER")
	)
	(via
		(at 207.68437 -122.809762)
		(size 0.508)
		(drill 0.254)
		(layers "F.Cu" "B.Cu")
		(net "P52V_HS_FILTER")
	)
	(via
		(at 207.68437 -120.569736)
		(size 0.508)
		(drill 0.254)
		(layers "F.Cu" "B.Cu")
		(net "P52V_HS_FILTER")
	)
	(via
		(at 213.978236 -129.149856)
		(size 0.508)
		(drill 0.254)
		(layers "F.Cu" "B.Cu")
		(net "P52V_HS_FILTER")
	)
	(via
		(at 216.727278 -122.047762)
		(size 0.508)
		(drill 0.254)
		(layers "F.Cu" "B.Cu")
		(net "P52V_HS_FILTER")
	)
	(via
		(at 215.458802 -127.61214)
		(size 0.508)
		(drill 0.254)
		(layers "F.Cu" "B.Cu")
		(net "P52V_HS_FILTER")
	)
	(via
		(at 203.87437 -120.569736)
		(size 0.508)
		(drill 0.254)
		(layers "F.Cu" "B.Cu")
		(net "P52V_HS_FILTER")
	)
	(via
		(at 206.16037 -122.047762)
		(size 0.508)
		(drill 0.254)
		(layers "F.Cu" "B.Cu")
		(net "P52V_HS_FILTER")
	)
	(via
		(at 123.6726 -131.572)
		(size 0.508)
		(drill 0.254)
		(layers "F.Cu" "B.Cu")
		(net "P52V_HS_FILTER")
	)
	(via
		(at 163.672774 -131.572)
		(size 0.508)
		(drill 0.254)
		(layers "F.Cu" "B.Cu")
		(net "P52V_HS_FILTER")
	)
	(via
		(at 206.936086 -123.528328)
		(size 0.508)
		(drill 0.254)
		(layers "F.Cu" "B.Cu")
		(net "P52V_HS_FILTER")
	)
	(via
		(at 187.294774 -126.492)
		(size 0.508)
		(drill 0.254)
		(layers "F.Cu" "B.Cu")
		(net "P52V_HS_FILTER")
	)
	(via
		(at 216.174828 -127.61214)
		(size 0.508)
		(drill 0.254)
		(layers "F.Cu" "B.Cu")
		(net "P52V_HS_FILTER")
	)
	(via
		(at 207.68437 -122.047762)
		(size 0.508)
		(drill 0.254)
		(layers "F.Cu" "B.Cu")
		(net "P52V_HS_FILTER")
	)
	(via
		(at 218.251278 -121.331736)
		(size 0.508)
		(drill 0.254)
		(layers "F.Cu" "B.Cu")
		(net "P52V_HS_FILTER")
	)
	(via
		(at 205.39837 -121.331736)
		(size 0.508)
		(drill 0.254)
		(layers "F.Cu" "B.Cu")
		(net "P52V_HS_FILTER")
	)
	(via
		(at 55.102506 -131.572)
		(size 0.508)
		(drill 0.254)
		(layers "F.Cu" "B.Cu")
		(net "P52V_HS_FILTER")
	)
	(via
		(at 207.68437 -121.331736)
		(size 0.508)
		(drill 0.254)
		(layers "F.Cu" "B.Cu")
		(net "P52V_HS_FILTER")
	)
	(via
		(at 215.458802 -129.89814)
		(size 0.508)
		(drill 0.254)
		(layers "F.Cu" "B.Cu")
		(net "P52V_HS_FILTER")
	)
	(via
		(at 213.978236 -132.197856)
		(size 0.508)
		(drill 0.254)
		(layers "F.Cu" "B.Cu")
		(net "P52V_HS_FILTER")
	)
	(via
		(at 162.910774 -131.572)
		(size 0.508)
		(drill 0.254)
		(layers "F.Cu" "B.Cu")
		(net "P52V_HS_FILTER")
	)
	(via
		(at 220.537278 -122.809762)
		(size 0.508)
		(drill 0.254)
		(layers "F.Cu" "B.Cu")
		(net "P52V_HS_FILTER")
	)
	(via
		(at 206.92237 -120.569736)
		(size 0.508)
		(drill 0.254)
		(layers "F.Cu" "B.Cu")
		(net "P52V_HS_FILTER")
	)
	(via
		(at 213.978236 -132.959856)
		(size 0.508)
		(drill 0.254)
		(layers "F.Cu" "B.Cu")
		(net "P52V_HS_FILTER")
	)
	(via
		(at 219.013278 -120.569736)
		(size 0.508)
		(drill 0.254)
		(layers "F.Cu" "B.Cu")
		(net "P52V_HS_FILTER")
	)
	(via
		(at 216.727278 -122.809762)
		(size 0.508)
		(drill 0.254)
		(layers "F.Cu" "B.Cu")
		(net "P52V_HS_FILTER")
	)
	(via
		(at 204.63637 -122.047762)
		(size 0.508)
		(drill 0.254)
		(layers "F.Cu" "B.Cu")
		(net "P52V_HS_FILTER")
	)
	(via
		(at 215.458802 -131.42214)
		(size 0.508)
		(drill 0.254)
		(layers "F.Cu" "B.Cu")
		(net "P52V_HS_FILTER")
	)
	(via
		(at 217.489278 -122.047762)
		(size 0.508)
		(drill 0.254)
		(layers "F.Cu" "B.Cu")
		(net "P52V_HS_FILTER")
	)
	(via
		(at 219.013278 -122.047762)
		(size 0.508)
		(drill 0.254)
		(layers "F.Cu" "B.Cu")
		(net "P52V_HS_FILTER")
	)
	(via
		(at 107.294426 -131.572)
		(size 0.508)
		(drill 0.254)
		(layers "F.Cu" "B.Cu")
		(net "P52V_HS_FILTER")
	)
	(via
		(at 214.696802 -132.94614)
		(size 0.508)
		(drill 0.254)
		(layers "F.Cu" "B.Cu")
		(net "P52V_HS_FILTER")
	)
	(via
		(at 221.299278 -121.331736)
		(size 0.508)
		(drill 0.254)
		(layers "F.Cu" "B.Cu")
		(net "P52V_HS_FILTER")
	)
	(via
		(at 202.35037 -121.331736)
		(size 0.508)
		(drill 0.254)
		(layers "F.Cu" "B.Cu")
		(net "P52V_HS_FILTER")
	)
	(via
		(at 218.251278 -120.569736)
		(size 0.508)
		(drill 0.254)
		(layers "F.Cu" "B.Cu")
		(net "P52V_HS_FILTER")
	)
	(via
		(at 55.864506 -131.572)
		(size 0.508)
		(drill 0.254)
		(layers "F.Cu" "B.Cu")
		(net "P52V_HS_FILTER")
	)
	(via
		(at 175.864774 -131.572)
		(size 0.508)
		(drill 0.254)
		(layers "F.Cu" "B.Cu")
		(net "P52V_HS_FILTER")
	)
	(via
		(at 204.63637 -122.809762)
		(size 0.508)
		(drill 0.254)
		(layers "F.Cu" "B.Cu")
		(net "P52V_HS_FILTER")
	)
	(via
		(at 215.458802 -132.94614)
		(size 0.508)
		(drill 0.254)
		(layers "F.Cu" "B.Cu")
		(net "P52V_HS_FILTER")
	)
	(via
		(at 203.11237 -122.809762)
		(size 0.508)
		(drill 0.254)
		(layers "F.Cu" "B.Cu")
		(net "P52V_HS_FILTER")
	)
	(via
		(at 203.11237 -121.331736)
		(size 0.508)
		(drill 0.254)
		(layers "F.Cu" "B.Cu")
		(net "P52V_HS_FILTER")
	)
	(via
		(at 203.11237 -120.569736)
		(size 0.508)
		(drill 0.254)
		(layers "F.Cu" "B.Cu")
		(net "P52V_HS_FILTER")
	)
	(via
		(at 135.1026 -126.492)
		(size 0.508)
		(drill 0.254)
		(layers "F.Cu" "B.Cu")
		(net "P52V_HS_FILTER")
	)
	(via
		(at 215.458802 -128.37414)
		(size 0.508)
		(drill 0.254)
		(layers "F.Cu" "B.Cu")
		(net "P52V_HS_FILTER")
	)
	(via
		(at 187.294774 -131.572)
		(size 0.508)
		(drill 0.254)
		(layers "F.Cu" "B.Cu")
		(net "P52V_HS_FILTER")
	)
	(via
		(at 203.87437 -122.809762)
		(size 0.508)
		(drill 0.254)
		(layers "F.Cu" "B.Cu")
		(net "P52V_HS_FILTER")
	)
	(via
		(at 219.775278 -121.331736)
		(size 0.508)
		(drill 0.254)
		(layers "F.Cu" "B.Cu")
		(net "P52V_HS_FILTER")
	)
	(via
		(at 216.936828 -128.37414)
		(size 0.508)
		(drill 0.254)
		(layers "F.Cu" "B.Cu")
		(net "P52V_HS_FILTER")
	)
	(via
		(at 43.672506 -131.572)
		(size 0.508)
		(drill 0.254)
		(layers "F.Cu" "B.Cu")
		(net "P52V_HS_FILTER")
	)
	(via
		(at 188.056774 -126.492)
		(size 0.508)
		(drill 0.254)
		(layers "F.Cu" "B.Cu")
		(net "P52V_HS_FILTER")
	)
	(via
		(at 82.910426 -126.492)
		(size 0.508)
		(drill 0.254)
		(layers "F.Cu" "B.Cu")
		(net "P52V_HS_FILTER")
	)
	(via
		(at 216.936828 -129.89814)
		(size 0.508)
		(drill 0.254)
		(layers "F.Cu" "B.Cu")
		(net "P52V_HS_FILTER")
	)
	(via
		(at 55.864506 -126.492)
		(size 0.508)
		(drill 0.254)
		(layers "F.Cu" "B.Cu")
		(net "P52V_HS_FILTER")
	)
	(via
		(at 215.458802 -132.18414)
		(size 0.508)
		(drill 0.254)
		(layers "F.Cu" "B.Cu")
		(net "P52V_HS_FILTER")
	)
	(via
		(at 67.294506 -126.492)
		(size 0.508)
		(drill 0.254)
		(layers "F.Cu" "B.Cu")
		(net "P52V_HS_FILTER")
	)
	(via
		(at 148.0566 -131.572)
		(size 0.508)
		(drill 0.254)
		(layers "F.Cu" "B.Cu")
		(net "P52V_HS_FILTER")
	)
	(via
		(at 220.537278 -120.569736)
		(size 0.508)
		(drill 0.254)
		(layers "F.Cu" "B.Cu")
		(net "P52V_HS_FILTER")
	)
	(via
		(at 218.251278 -122.809762)
		(size 0.508)
		(drill 0.254)
		(layers "F.Cu" "B.Cu")
		(net "P52V_HS_FILTER")
	)
	(via
		(at 222.061278 -122.047762)
		(size 0.508)
		(drill 0.254)
		(layers "F.Cu" "B.Cu")
		(net "P52V_HS_FILTER")
	)
	(via
		(at 217.489278 -122.809762)
		(size 0.508)
		(drill 0.254)
		(layers "F.Cu" "B.Cu")
		(net "P52V_HS_FILTER")
	)
	(via
		(at 135.1026 -131.572)
		(size 0.508)
		(drill 0.254)
		(layers "F.Cu" "B.Cu")
		(net "P52V_HS_FILTER")
	)
	(via
		(at 175.102774 -126.492)
		(size 0.508)
		(drill 0.254)
		(layers "F.Cu" "B.Cu")
		(net "P52V_HS_FILTER")
	)
	(via
		(at 135.8646 -126.492)
		(size 0.508)
		(drill 0.254)
		(layers "F.Cu" "B.Cu")
		(net "P52V_HS_FILTER")
	)
	(via
		(at 218.264994 -123.528328)
		(size 0.508)
		(drill 0.254)
		(layers "F.Cu" "B.Cu")
		(net "P52V_HS_FILTER")
	)
	(via
		(at 213.978236 -127.625856)
		(size 0.508)
		(drill 0.254)
		(layers "F.Cu" "B.Cu")
		(net "P52V_HS_FILTER")
	)
	(via
		(at 108.056426 -131.572)
		(size 0.508)
		(drill 0.254)
		(layers "F.Cu" "B.Cu")
		(net "P52V_HS_FILTER")
	)
	(via
		(at 204.63637 -121.331736)
		(size 0.508)
		(drill 0.254)
		(layers "F.Cu" "B.Cu")
		(net "P52V_HS_FILTER")
	)
	(via
		(at 219.013278 -122.809762)
		(size 0.508)
		(drill 0.254)
		(layers "F.Cu" "B.Cu")
		(net "P52V_HS_FILTER")
	)
	(via
		(at 108.056426 -126.492)
		(size 0.508)
		(drill 0.254)
		(layers "F.Cu" "B.Cu")
		(net "P52V_HS_FILTER")
	)
	(via
		(at 214.696802 -131.42214)
		(size 0.508)
		(drill 0.254)
		(layers "F.Cu" "B.Cu")
		(net "P52V_HS_FILTER")
	)
	(via
		(at 216.740994 -123.528328)
		(size 0.508)
		(drill 0.254)
		(layers "F.Cu" "B.Cu")
		(net "P52V_HS_FILTER")
	)
	(via
		(at 83.672426 -126.492)
		(size 0.508)
		(drill 0.254)
		(layers "F.Cu" "B.Cu")
		(net "P52V_HS_FILTER")
	)
	(via
		(at 220.537278 -121.331736)
		(size 0.508)
		(drill 0.254)
		(layers "F.Cu" "B.Cu")
		(net "P52V_HS_FILTER")
	)
	(via
		(at 217.489278 -120.569736)
		(size 0.508)
		(drill 0.254)
		(layers "F.Cu" "B.Cu")
		(net "P52V_HS_FILTER")
	)
	(via
		(at 213.978236 -130.673856)
		(size 0.508)
		(drill 0.254)
		(layers "F.Cu" "B.Cu")
		(net "P52V_HS_FILTER")
	)
	(via
		(at 95.864426 -131.572)
		(size 0.508)
		(drill 0.254)
		(layers "F.Cu" "B.Cu")
		(net "P52V_HS_FILTER")
	)
	(via
		(at 204.63637 -120.569736)
		(size 0.508)
		(drill 0.254)
		(layers "F.Cu" "B.Cu")
		(net "P52V_HS_FILTER")
	)
	(via
		(at 220.550994 -123.528328)
		(size 0.508)
		(drill 0.254)
		(layers "F.Cu" "B.Cu")
		(net "P52V_HS_FILTER")
	)
	(via
		(at 202.35037 -122.047762)
		(size 0.508)
		(drill 0.254)
		(layers "F.Cu" "B.Cu")
		(net "P52V_HS_FILTER")
	)
	(via
		(at 95.864426 -126.492)
		(size 0.508)
		(drill 0.254)
		(layers "F.Cu" "B.Cu")
		(net "P52V_HS_FILTER")
	)
	(via
		(at 222.061278 -120.569736)
		(size 0.508)
		(drill 0.254)
		(layers "F.Cu" "B.Cu")
		(net "P52V_HS_FILTER")
	)
	(via
		(at 219.013278 -121.331736)
		(size 0.508)
		(drill 0.254)
		(layers "F.Cu" "B.Cu")
		(net "P52V_HS_FILTER")
	)
	(via
		(at 203.87437 -122.047762)
		(size 0.508)
		(drill 0.254)
		(layers "F.Cu" "B.Cu")
		(net "P52V_HS_FILTER")
	)
	(via
		(at 175.102774 -131.572)
		(size 0.508)
		(drill 0.254)
		(layers "F.Cu" "B.Cu")
		(net "P52V_HS_FILTER")
	)
	(via
		(at 214.696802 -132.18414)
		(size 0.508)
		(drill 0.254)
		(layers "F.Cu" "B.Cu")
		(net "P52V_HS_FILTER")
	)
	(via
		(at 205.39837 -120.569736)
		(size 0.508)
		(drill 0.254)
		(layers "F.Cu" "B.Cu")
		(net "P52V_HS_FILTER")
	)
	(via
		(at 67.294506 -131.572)
		(size 0.508)
		(drill 0.254)
		(layers "F.Cu" "B.Cu")
		(net "P52V_HS_FILTER")
	)
	(via
		(at 188.056774 -131.572)
		(size 0.508)
		(drill 0.254)
		(layers "F.Cu" "B.Cu")
		(net "P52V_HS_FILTER")
	)
	(via
		(at 206.92237 -121.331736)
		(size 0.508)
		(drill 0.254)
		(layers "F.Cu" "B.Cu")
		(net "P52V_HS_FILTER")
	)
	(via
		(at 217.502994 -123.528328)
		(size 0.508)
		(drill 0.254)
		(layers "F.Cu" "B.Cu")
		(net "P52V_HS_FILTER")
	)
	(via
		(at 42.910506 -126.492)
		(size 0.508)
		(drill 0.254)
		(layers "F.Cu" "B.Cu")
		(net "P52V_HS_FILTER")
	)
	(via
		(at 221.299278 -120.569736)
		(size 0.508)
		(drill 0.254)
		(layers "F.Cu" "B.Cu")
		(net "P52V_HS_FILTER")
	)
	(via
		(at 205.39837 -122.047762)
		(size 0.508)
		(drill 0.254)
		(layers "F.Cu" "B.Cu")
		(net "P52V_HS_FILTER")
	)
	(via
		(at 222.074994 -123.528328)
		(size 0.508)
		(drill 0.254)
		(layers "F.Cu" "B.Cu")
		(net "P52V_HS_FILTER")
	)
	(via
		(at 216.174828 -129.89814)
		(size 0.508)
		(drill 0.254)
		(layers "F.Cu" "B.Cu")
		(net "P52V_HS_FILTER")
	)
	(via
		(at 215.458802 -129.13614)
		(size 0.508)
		(drill 0.254)
		(layers "F.Cu" "B.Cu")
		(net "P52V_HS_FILTER")
	)
	(via
		(at 205.39837 -122.809762)
		(size 0.508)
		(drill 0.254)
		(layers "F.Cu" "B.Cu")
		(net "P52V_HS_FILTER")
	)
	(segment
		(start 82.046826 -136.906)
		(end 83.012534 -137.871708)
		(width 0.635)
		(layer "B.Cu")
		(net "P52V_HS_FILTER")
	)
	(segment
		(start 133.273292 -135.940292)
		(end 134.239 -136.906)
		(width 0.635)
		(layer "B.Cu")
		(net "P52V_HS_FILTER")
	)
	(segment
		(start 94.238826 -136.906)
		(end 95.204534 -137.871708)
		(width 0.635)
		(layer "B.Cu")
		(net "P52V_HS_FILTER")
	)
	(segment
		(start 94.238826 -136.906)
		(end 95.204534 -135.940292)
		(width 0.635)
		(layer "B.Cu")
		(net "P52V_HS_FILTER")
	)
	(segment
		(start 134.239 -136.906)
		(end 135.204708 -135.940292)
		(width 0.635)
		(layer "B.Cu")
		(net "P52V_HS_FILTER")
	)
	(segment
		(start 146.431 -136.906)
		(end 147.396708 -137.871708)
		(width 0.635)
		(layer "B.Cu")
		(net "P52V_HS_FILTER")
	)
	(segment
		(start 183.110886 -119.850408)
		(end 184.470294 -121.209816)
		(width 0.889)
		(layer "B.Cu")
		(net "P52V_HS_FILTER")
	)
	(segment
		(start 186.431174 -136.906)
		(end 187.396882 -137.871708)
		(width 0.635)
		(layer "B.Cu")
		(net "P52V_HS_FILTER")
	)
	(segment
		(start 66.430906 -136.906)
		(end 67.396614 -135.940292)
		(width 0.635)
		(layer "B.Cu")
		(net "P52V_HS_FILTER")
	)
	(segment
		(start 184.470294 -121.209816)
		(end 185.829702 -119.850408)
		(width 0.889)
		(layer "B.Cu")
		(net "P52V_HS_FILTER")
	)
	(segment
		(start 64.470026 -121.209816)
		(end 65.829434 -122.569224)
		(width 0.889)
		(layer "B.Cu")
		(net "P52V_HS_FILTER")
	)
	(segment
		(start 143.110712 -119.850408)
		(end 144.47012 -121.209816)
		(width 0.889)
		(layer "B.Cu")
		(net "P52V_HS_FILTER")
	)
	(segment
		(start 82.046826 -136.906)
		(end 83.012534 -135.940292)
		(width 0.635)
		(layer "B.Cu")
		(net "P52V_HS_FILTER")
	)
	(segment
		(start 65.465198 -137.871708)
		(end 66.430906 -136.906)
		(width 0.635)
		(layer "B.Cu")
		(net "P52V_HS_FILTER")
	)
	(segment
		(start 183.110886 -122.569224)
		(end 184.470294 -121.209816)
		(width 0.889)
		(layer "B.Cu")
		(net "P52V_HS_FILTER")
	)
	(segment
		(start 173.273466 -137.871708)
		(end 174.239174 -136.906)
		(width 0.635)
		(layer "B.Cu")
		(net "P52V_HS_FILTER")
	)
	(segment
		(start 54.238906 -136.906)
		(end 55.204614 -135.940292)
		(width 0.635)
		(layer "B.Cu")
		(net "P52V_HS_FILTER")
	)
	(segment
		(start 104.469946 -121.209816)
		(end 105.829354 -122.569224)
		(width 0.889)
		(layer "B.Cu")
		(net "P52V_HS_FILTER")
	)
	(segment
		(start 105.465118 -137.871708)
		(end 106.430826 -136.906)
		(width 0.635)
		(layer "B.Cu")
		(net "P52V_HS_FILTER")
	)
	(segment
		(start 145.465292 -137.871708)
		(end 146.431 -136.906)
		(width 0.635)
		(layer "B.Cu")
		(net "P52V_HS_FILTER")
	)
	(segment
		(start 145.465292 -135.940292)
		(end 146.431 -136.906)
		(width 0.635)
		(layer "B.Cu")
		(net "P52V_HS_FILTER")
	)
	(segment
		(start 81.081118 -135.940292)
		(end 82.046826 -136.906)
		(width 0.635)
		(layer "B.Cu")
		(net "P52V_HS_FILTER")
	)
	(segment
		(start 174.239174 -136.906)
		(end 175.204882 -137.871708)
		(width 0.635)
		(layer "B.Cu")
		(net "P52V_HS_FILTER")
	)
	(segment
		(start 122.047 -136.906)
		(end 123.012708 -137.871708)
		(width 0.635)
		(layer "B.Cu")
		(net "P52V_HS_FILTER")
	)
	(segment
		(start 53.273198 -135.940292)
		(end 54.238906 -136.906)
		(width 0.635)
		(layer "B.Cu")
		(net "P52V_HS_FILTER")
	)
	(segment
		(start 144.47012 -121.209816)
		(end 145.829528 -122.569224)
		(width 0.889)
		(layer "B.Cu")
		(net "P52V_HS_FILTER")
	)
	(segment
		(start 42.046906 -136.906)
		(end 43.012614 -137.871708)
		(width 0.635)
		(layer "B.Cu")
		(net "P52V_HS_FILTER")
	)
	(segment
		(start 106.430826 -136.906)
		(end 107.396534 -137.871708)
		(width 0.635)
		(layer "B.Cu")
		(net "P52V_HS_FILTER")
	)
	(segment
		(start 173.273466 -135.940292)
		(end 174.239174 -136.906)
		(width 0.635)
		(layer "B.Cu")
		(net "P52V_HS_FILTER")
	)
	(segment
		(start 93.273118 -137.871708)
		(end 94.238826 -136.906)
		(width 0.635)
		(layer "B.Cu")
		(net "P52V_HS_FILTER")
	)
	(segment
		(start 66.430906 -136.906)
		(end 67.396614 -137.871708)
		(width 0.635)
		(layer "B.Cu")
		(net "P52V_HS_FILTER")
	)
	(segment
		(start 162.047174 -136.906)
		(end 163.012882 -135.940292)
		(width 0.635)
		(layer "B.Cu")
		(net "P52V_HS_FILTER")
	)
	(segment
		(start 122.047 -136.906)
		(end 123.012708 -135.940292)
		(width 0.635)
		(layer "B.Cu")
		(net "P52V_HS_FILTER")
	)
	(segment
		(start 103.110538 -122.569224)
		(end 104.469946 -121.209816)
		(width 0.889)
		(layer "B.Cu")
		(net "P52V_HS_FILTER")
	)
	(segment
		(start 41.081198 -137.871708)
		(end 42.046906 -136.906)
		(width 0.635)
		(layer "B.Cu")
		(net "P52V_HS_FILTER")
	)
	(segment
		(start 186.431174 -136.906)
		(end 187.396882 -135.940292)
		(width 0.635)
		(layer "B.Cu")
		(net "P52V_HS_FILTER")
	)
	(segment
		(start 81.081118 -137.871708)
		(end 82.046826 -136.906)
		(width 0.635)
		(layer "B.Cu")
		(net "P52V_HS_FILTER")
	)
	(segment
		(start 162.047174 -136.906)
		(end 163.012882 -137.871708)
		(width 0.635)
		(layer "B.Cu")
		(net "P52V_HS_FILTER")
	)
	(segment
		(start 65.465198 -135.940292)
		(end 66.430906 -136.906)
		(width 0.635)
		(layer "B.Cu")
		(net "P52V_HS_FILTER")
	)
	(segment
		(start 63.110618 -119.850408)
		(end 64.470026 -121.209816)
		(width 0.889)
		(layer "B.Cu")
		(net "P52V_HS_FILTER")
	)
	(segment
		(start 185.465466 -135.940292)
		(end 186.431174 -136.906)
		(width 0.635)
		(layer "B.Cu")
		(net "P52V_HS_FILTER")
	)
	(segment
		(start 64.470026 -121.209816)
		(end 65.829434 -119.850408)
		(width 0.889)
		(layer "B.Cu")
		(net "P52V_HS_FILTER")
	)
	(segment
		(start 41.081198 -135.940292)
		(end 42.046906 -136.906)
		(width 0.635)
		(layer "B.Cu")
		(net "P52V_HS_FILTER")
	)
	(segment
		(start 161.081466 -135.940292)
		(end 162.047174 -136.906)
		(width 0.635)
		(layer "B.Cu")
		(net "P52V_HS_FILTER")
	)
	(segment
		(start 53.273198 -137.871708)
		(end 54.238906 -136.906)
		(width 0.635)
		(layer "B.Cu")
		(net "P52V_HS_FILTER")
	)
	(segment
		(start 93.273118 -135.940292)
		(end 94.238826 -136.906)
		(width 0.635)
		(layer "B.Cu")
		(net "P52V_HS_FILTER")
	)
	(segment
		(start 105.465118 -135.940292)
		(end 106.430826 -136.906)
		(width 0.635)
		(layer "B.Cu")
		(net "P52V_HS_FILTER")
	)
	(segment
		(start 184.470294 -121.209816)
		(end 185.829702 -122.569224)
		(width 0.889)
		(layer "B.Cu")
		(net "P52V_HS_FILTER")
	)
	(segment
		(start 161.081466 -137.871708)
		(end 162.047174 -136.906)
		(width 0.635)
		(layer "B.Cu")
		(net "P52V_HS_FILTER")
	)
	(segment
		(start 104.469946 -121.209816)
		(end 105.829354 -119.850408)
		(width 0.889)
		(layer "B.Cu")
		(net "P52V_HS_FILTER")
	)
	(segment
		(start 174.239174 -136.906)
		(end 175.204882 -135.940292)
		(width 0.635)
		(layer "B.Cu")
		(net "P52V_HS_FILTER")
	)
	(segment
		(start 121.081292 -135.940292)
		(end 122.047 -136.906)
		(width 0.635)
		(layer "B.Cu")
		(net "P52V_HS_FILTER")
	)
	(segment
		(start 42.046906 -136.906)
		(end 43.012614 -135.940292)
		(width 0.635)
		(layer "B.Cu")
		(net "P52V_HS_FILTER")
	)
	(segment
		(start 146.431 -136.906)
		(end 147.396708 -135.940292)
		(width 0.635)
		(layer "B.Cu")
		(net "P52V_HS_FILTER")
	)
	(segment
		(start 106.430826 -136.906)
		(end 107.396534 -135.940292)
		(width 0.635)
		(layer "B.Cu")
		(net "P52V_HS_FILTER")
	)
	(segment
		(start 134.239 -136.906)
		(end 135.204708 -137.871708)
		(width 0.635)
		(layer "B.Cu")
		(net "P52V_HS_FILTER")
	)
	(segment
		(start 103.110538 -119.850408)
		(end 104.469946 -121.209816)
		(width 0.889)
		(layer "B.Cu")
		(net "P52V_HS_FILTER")
	)
	(segment
		(start 63.110618 -122.569224)
		(end 64.470026 -121.209816)
		(width 0.889)
		(layer "B.Cu")
		(net "P52V_HS_FILTER")
	)
	(segment
		(start 185.465466 -137.871708)
		(end 186.431174 -136.906)
		(width 0.635)
		(layer "B.Cu")
		(net "P52V_HS_FILTER")
	)
	(segment
		(start 54.238906 -136.906)
		(end 55.204614 -137.871708)
		(width 0.635)
		(layer "B.Cu")
		(net "P52V_HS_FILTER")
	)
	(segment
		(start 144.47012 -121.209816)
		(end 145.829528 -119.850408)
		(width 0.889)
		(layer "B.Cu")
		(net "P52V_HS_FILTER")
	)
	(segment
		(start 143.110712 -122.569224)
		(end 144.47012 -121.209816)
		(width 0.889)
		(layer "B.Cu")
		(net "P52V_HS_FILTER")
	)
	(segment
		(start 121.081292 -137.871708)
		(end 122.047 -136.906)
		(width 0.635)
		(layer "B.Cu")
		(net "P52V_HS_FILTER")
	)
	(segment
		(start 133.273292 -137.871708)
		(end 134.239 -136.906)
		(width 0.635)
		(layer "B.Cu")
		(net "P52V_HS_FILTER")
	)
	(segment
		(start 143.458184 -122.221752)
		(end 144.47012 -121.209816)
		(width 0.889)
		(layer "In2.Cu")
		(net "P52V_HS_FILTER")
	)
	(segment
		(start 146.431 -136.906)
		(end 147.164552 -137.639552)
		(width 0.635)
		(layer "In2.Cu")
		(net "P52V_HS_FILTER")
	)
	(segment
		(start 185.697622 -137.639552)
		(end 186.431174 -136.906)
		(width 0.635)
		(layer "In2.Cu")
		(net "P52V_HS_FILTER")
	)
	(segment
		(start 106.430826 -136.906)
		(end 107.164378 -136.172448)
		(width 0.635)
		(layer "In2.Cu")
		(net "P52V_HS_FILTER")
	)
	(segment
		(start 185.697622 -136.172448)
		(end 186.431174 -136.906)
		(width 0.635)
		(layer "In2.Cu")
		(net "P52V_HS_FILTER")
	)
	(segment
		(start 42.046906 -136.906)
		(end 42.780458 -136.172448)
		(width 0.635)
		(layer "In2.Cu")
		(net "P52V_HS_FILTER")
	)
	(segment
		(start 183.458358 -120.19788)
		(end 184.470294 -121.209816)
		(width 0.889)
		(layer "In2.Cu")
		(net "P52V_HS_FILTER")
	)
	(segment
		(start 183.458358 -122.221752)
		(end 184.470294 -121.209816)
		(width 0.889)
		(layer "In2.Cu")
		(net "P52V_HS_FILTER")
	)
	(segment
		(start 66.430906 -136.906)
		(end 67.164458 -137.639552)
		(width 0.635)
		(layer "In2.Cu")
		(net "P52V_HS_FILTER")
	)
	(segment
		(start 173.505622 -137.639552)
		(end 174.239174 -136.906)
		(width 0.635)
		(layer "In2.Cu")
		(net "P52V_HS_FILTER")
	)
	(segment
		(start 81.313274 -136.172448)
		(end 82.046826 -136.906)
		(width 0.635)
		(layer "In2.Cu")
		(net "P52V_HS_FILTER")
	)
	(segment
		(start 143.458184 -120.19788)
		(end 144.47012 -121.209816)
		(width 0.889)
		(layer "In2.Cu")
		(net "P52V_HS_FILTER")
	)
	(segment
		(start 105.697274 -136.172448)
		(end 106.430826 -136.906)
		(width 0.635)
		(layer "In2.Cu")
		(net "P52V_HS_FILTER")
	)
	(segment
		(start 65.697354 -136.172448)
		(end 66.430906 -136.906)
		(width 0.635)
		(layer "In2.Cu")
		(net "P52V_HS_FILTER")
	)
	(segment
		(start 121.313448 -137.639552)
		(end 122.047 -136.906)
		(width 0.635)
		(layer "In2.Cu")
		(net "P52V_HS_FILTER")
	)
	(segment
		(start 144.47012 -121.209816)
		(end 145.482056 -120.19788)
		(width 0.889)
		(layer "In2.Cu")
		(net "P52V_HS_FILTER")
	)
	(segment
		(start 161.313622 -136.172448)
		(end 162.047174 -136.906)
		(width 0.635)
		(layer "In2.Cu")
		(net "P52V_HS_FILTER")
	)
	(segment
		(start 134.239 -136.906)
		(end 134.972552 -137.639552)
		(width 0.635)
		(layer "In2.Cu")
		(net "P52V_HS_FILTER")
	)
	(segment
		(start 65.697354 -137.639552)
		(end 66.430906 -136.906)
		(width 0.635)
		(layer "In2.Cu")
		(net "P52V_HS_FILTER")
	)
	(segment
		(start 42.046906 -136.906)
		(end 42.780458 -137.639552)
		(width 0.635)
		(layer "In2.Cu")
		(net "P52V_HS_FILTER")
	)
	(segment
		(start 133.505448 -137.639552)
		(end 134.239 -136.906)
		(width 0.635)
		(layer "In2.Cu")
		(net "P52V_HS_FILTER")
	)
	(segment
		(start 134.239 -136.906)
		(end 134.972552 -136.172448)
		(width 0.635)
		(layer "In2.Cu")
		(net "P52V_HS_FILTER")
	)
	(segment
		(start 122.047 -136.906)
		(end 122.780552 -136.172448)
		(width 0.635)
		(layer "In2.Cu")
		(net "P52V_HS_FILTER")
	)
	(segment
		(start 93.505274 -137.639552)
		(end 94.238826 -136.906)
		(width 0.635)
		(layer "In2.Cu")
		(net "P52V_HS_FILTER")
	)
	(segment
		(start 144.47012 -121.209816)
		(end 145.482056 -122.221752)
		(width 0.889)
		(layer "In2.Cu")
		(net "P52V_HS_FILTER")
	)
	(segment
		(start 145.697448 -137.639552)
		(end 146.431 -136.906)
		(width 0.635)
		(layer "In2.Cu")
		(net "P52V_HS_FILTER")
	)
	(segment
		(start 186.431174 -136.906)
		(end 187.164726 -136.172448)
		(width 0.635)
		(layer "In2.Cu")
		(net "P52V_HS_FILTER")
	)
	(segment
		(start 161.313622 -137.639552)
		(end 162.047174 -136.906)
		(width 0.635)
		(layer "In2.Cu")
		(net "P52V_HS_FILTER")
	)
	(segment
		(start 53.505354 -136.172448)
		(end 54.238906 -136.906)
		(width 0.635)
		(layer "In2.Cu")
		(net "P52V_HS_FILTER")
	)
	(segment
		(start 93.505274 -136.172448)
		(end 94.238826 -136.906)
		(width 0.635)
		(layer "In2.Cu")
		(net "P52V_HS_FILTER")
	)
	(segment
		(start 174.239174 -136.906)
		(end 174.972726 -137.639552)
		(width 0.635)
		(layer "In2.Cu")
		(net "P52V_HS_FILTER")
	)
	(segment
		(start 82.046826 -136.906)
		(end 82.780378 -136.172448)
		(width 0.635)
		(layer "In2.Cu")
		(net "P52V_HS_FILTER")
	)
	(segment
		(start 174.239174 -136.906)
		(end 174.972726 -136.172448)
		(width 0.635)
		(layer "In2.Cu")
		(net "P52V_HS_FILTER")
	)
	(segment
		(start 103.45801 -120.19788)
		(end 104.469946 -121.209816)
		(width 0.889)
		(layer "In2.Cu")
		(net "P52V_HS_FILTER")
	)
	(segment
		(start 184.470294 -121.209816)
		(end 185.48223 -122.221752)
		(width 0.889)
		(layer "In2.Cu")
		(net "P52V_HS_FILTER")
	)
	(segment
		(start 162.047174 -136.906)
		(end 162.780726 -137.639552)
		(width 0.635)
		(layer "In2.Cu")
		(net "P52V_HS_FILTER")
	)
	(segment
		(start 64.470026 -121.209816)
		(end 65.481962 -122.221752)
		(width 0.889)
		(layer "In2.Cu")
		(net "P52V_HS_FILTER")
	)
	(segment
		(start 104.469946 -121.209816)
		(end 105.481882 -120.19788)
		(width 0.889)
		(layer "In2.Cu")
		(net "P52V_HS_FILTER")
	)
	(segment
		(start 145.697448 -136.172448)
		(end 146.431 -136.906)
		(width 0.635)
		(layer "In2.Cu")
		(net "P52V_HS_FILTER")
	)
	(segment
		(start 63.45809 -120.19788)
		(end 64.470026 -121.209816)
		(width 0.889)
		(layer "In2.Cu")
		(net "P52V_HS_FILTER")
	)
	(segment
		(start 82.046826 -136.906)
		(end 82.780378 -137.639552)
		(width 0.635)
		(layer "In2.Cu")
		(net "P52V_HS_FILTER")
	)
	(segment
		(start 121.313448 -136.172448)
		(end 122.047 -136.906)
		(width 0.635)
		(layer "In2.Cu")
		(net "P52V_HS_FILTER")
	)
	(segment
		(start 66.430906 -136.906)
		(end 67.164458 -136.172448)
		(width 0.635)
		(layer "In2.Cu")
		(net "P52V_HS_FILTER")
	)
	(segment
		(start 53.505354 -137.639552)
		(end 54.238906 -136.906)
		(width 0.635)
		(layer "In2.Cu")
		(net "P52V_HS_FILTER")
	)
	(segment
		(start 105.697274 -137.639552)
		(end 106.430826 -136.906)
		(width 0.635)
		(layer "In2.Cu")
		(net "P52V_HS_FILTER")
	)
	(segment
		(start 106.430826 -136.906)
		(end 107.164378 -137.639552)
		(width 0.635)
		(layer "In2.Cu")
		(net "P52V_HS_FILTER")
	)
	(segment
		(start 63.45809 -122.221752)
		(end 64.470026 -121.209816)
		(width 0.889)
		(layer "In2.Cu")
		(net "P52V_HS_FILTER")
	)
	(segment
		(start 133.505448 -136.172448)
		(end 134.239 -136.906)
		(width 0.635)
		(layer "In2.Cu")
		(net "P52V_HS_FILTER")
	)
	(segment
		(start 41.313354 -137.639552)
		(end 42.046906 -136.906)
		(width 0.635)
		(layer "In2.Cu")
		(net "P52V_HS_FILTER")
	)
	(segment
		(start 54.238906 -136.906)
		(end 54.972458 -137.639552)
		(width 0.635)
		(layer "In2.Cu")
		(net "P52V_HS_FILTER")
	)
	(segment
		(start 94.238826 -136.906)
		(end 94.972378 -136.172448)
		(width 0.635)
		(layer "In2.Cu")
		(net "P52V_HS_FILTER")
	)
	(segment
		(start 41.313354 -136.172448)
		(end 42.046906 -136.906)
		(width 0.635)
		(layer "In2.Cu")
		(net "P52V_HS_FILTER")
	)
	(segment
		(start 54.238906 -136.906)
		(end 54.972458 -136.172448)
		(width 0.635)
		(layer "In2.Cu")
		(net "P52V_HS_FILTER")
	)
	(segment
		(start 94.238826 -136.906)
		(end 94.972378 -137.639552)
		(width 0.635)
		(layer "In2.Cu")
		(net "P52V_HS_FILTER")
	)
	(segment
		(start 104.469946 -121.209816)
		(end 105.481882 -122.221752)
		(width 0.889)
		(layer "In2.Cu")
		(net "P52V_HS_FILTER")
	)
	(segment
		(start 162.047174 -136.906)
		(end 162.780726 -136.172448)
		(width 0.635)
		(layer "In2.Cu")
		(net "P52V_HS_FILTER")
	)
	(segment
		(start 173.505622 -136.172448)
		(end 174.239174 -136.906)
		(width 0.635)
		(layer "In2.Cu")
		(net "P52V_HS_FILTER")
	)
	(segment
		(start 103.45801 -122.221752)
		(end 104.469946 -121.209816)
		(width 0.889)
		(layer "In2.Cu")
		(net "P52V_HS_FILTER")
	)
	(segment
		(start 81.313274 -137.639552)
		(end 82.046826 -136.906)
		(width 0.635)
		(layer "In2.Cu")
		(net "P52V_HS_FILTER")
	)
	(segment
		(start 122.047 -136.906)
		(end 122.780552 -137.639552)
		(width 0.635)
		(layer "In2.Cu")
		(net "P52V_HS_FILTER")
	)
	(segment
		(start 64.470026 -121.209816)
		(end 65.481962 -120.19788)
		(width 0.889)
		(layer "In2.Cu")
		(net "P52V_HS_FILTER")
	)
	(segment
		(start 186.431174 -136.906)
		(end 187.164726 -137.639552)
		(width 0.635)
		(layer "In2.Cu")
		(net "P52V_HS_FILTER")
	)
	(segment
		(start 146.431 -136.906)
		(end 147.164552 -136.172448)
		(width 0.635)
		(layer "In2.Cu")
		(net "P52V_HS_FILTER")
	)
	(segment
		(start 184.470294 -121.209816)
		(end 185.48223 -120.19788)
		(width 0.889)
		(layer "In2.Cu")
		(net "P52V_HS_FILTER")
	)
	(segment
		(start 162.047174 -136.906)
		(end 162.780726 -136.172448)
		(width 0.635)
		(layer "In7.Cu")
		(net "P52V_HS_FILTER")
	)
	(segment
		(start 143.458184 -120.19788)
		(end 144.47012 -121.209816)
		(width 0.889)
		(layer "In7.Cu")
		(net "P52V_HS_FILTER")
	)
	(segment
		(start 186.431174 -136.906)
		(end 187.164726 -137.639552)
		(width 0.635)
		(layer "In7.Cu")
		(net "P52V_HS_FILTER")
	)
	(segment
		(start 54.238906 -136.906)
		(end 54.972458 -136.172448)
		(width 0.635)
		(layer "In7.Cu")
		(net "P52V_HS_FILTER")
	)
	(segment
		(start 173.505622 -137.639552)
		(end 174.239174 -136.906)
		(width 0.635)
		(layer "In7.Cu")
		(net "P52V_HS_FILTER")
	)
	(segment
		(start 146.431 -136.906)
		(end 147.164552 -137.639552)
		(width 0.635)
		(layer "In7.Cu")
		(net "P52V_HS_FILTER")
	)
	(segment
		(start 63.45809 -122.221752)
		(end 64.470026 -121.209816)
		(width 0.889)
		(layer "In7.Cu")
		(net "P52V_HS_FILTER")
	)
	(segment
		(start 103.45801 -122.221752)
		(end 104.469946 -121.209816)
		(width 0.889)
		(layer "In7.Cu")
		(net "P52V_HS_FILTER")
	)
	(segment
		(start 161.313622 -137.639552)
		(end 162.047174 -136.906)
		(width 0.635)
		(layer "In7.Cu")
		(net "P52V_HS_FILTER")
	)
	(segment
		(start 185.697622 -137.639552)
		(end 186.431174 -136.906)
		(width 0.635)
		(layer "In7.Cu")
		(net "P52V_HS_FILTER")
	)
	(segment
		(start 174.239174 -136.906)
		(end 174.972726 -137.639552)
		(width 0.635)
		(layer "In7.Cu")
		(net "P52V_HS_FILTER")
	)
	(segment
		(start 65.697354 -137.639552)
		(end 66.430906 -136.906)
		(width 0.635)
		(layer "In7.Cu")
		(net "P52V_HS_FILTER")
	)
	(segment
		(start 174.239174 -136.906)
		(end 174.972726 -136.172448)
		(width 0.635)
		(layer "In7.Cu")
		(net "P52V_HS_FILTER")
	)
	(segment
		(start 145.697448 -137.639552)
		(end 146.431 -136.906)
		(width 0.635)
		(layer "In7.Cu")
		(net "P52V_HS_FILTER")
	)
	(segment
		(start 42.046906 -136.906)
		(end 42.780458 -136.172448)
		(width 0.635)
		(layer "In7.Cu")
		(net "P52V_HS_FILTER")
	)
	(segment
		(start 146.431 -136.906)
		(end 147.164552 -136.172448)
		(width 0.635)
		(layer "In7.Cu")
		(net "P52V_HS_FILTER")
	)
	(segment
		(start 93.505274 -136.172448)
		(end 94.238826 -136.906)
		(width 0.635)
		(layer "In7.Cu")
		(net "P52V_HS_FILTER")
	)
	(segment
		(start 41.313354 -136.172448)
		(end 42.046906 -136.906)
		(width 0.635)
		(layer "In7.Cu")
		(net "P52V_HS_FILTER")
	)
	(segment
		(start 94.238826 -136.906)
		(end 94.972378 -137.639552)
		(width 0.635)
		(layer "In7.Cu")
		(net "P52V_HS_FILTER")
	)
	(segment
		(start 106.430826 -136.906)
		(end 107.164378 -136.172448)
		(width 0.635)
		(layer "In7.Cu")
		(net "P52V_HS_FILTER")
	)
	(segment
		(start 106.430826 -136.906)
		(end 107.164378 -137.639552)
		(width 0.635)
		(layer "In7.Cu")
		(net "P52V_HS_FILTER")
	)
	(segment
		(start 53.505354 -136.172448)
		(end 54.238906 -136.906)
		(width 0.635)
		(layer "In7.Cu")
		(net "P52V_HS_FILTER")
	)
	(segment
		(start 93.505274 -137.639552)
		(end 94.238826 -136.906)
		(width 0.635)
		(layer "In7.Cu")
		(net "P52V_HS_FILTER")
	)
	(segment
		(start 54.238906 -136.906)
		(end 54.972458 -137.639552)
		(width 0.635)
		(layer "In7.Cu")
		(net "P52V_HS_FILTER")
	)
	(segment
		(start 122.047 -136.906)
		(end 122.780552 -137.639552)
		(width 0.635)
		(layer "In7.Cu")
		(net "P52V_HS_FILTER")
	)
	(segment
		(start 183.458358 -122.221752)
		(end 184.470294 -121.209816)
		(width 0.889)
		(layer "In7.Cu")
		(net "P52V_HS_FILTER")
	)
	(segment
		(start 145.697448 -136.172448)
		(end 146.431 -136.906)
		(width 0.635)
		(layer "In7.Cu")
		(net "P52V_HS_FILTER")
	)
	(segment
		(start 184.470294 -121.209816)
		(end 185.48223 -122.221752)
		(width 0.889)
		(layer "In7.Cu")
		(net "P52V_HS_FILTER")
	)
	(segment
		(start 64.470026 -121.209816)
		(end 65.481962 -122.221752)
		(width 0.889)
		(layer "In7.Cu")
		(net "P52V_HS_FILTER")
	)
	(segment
		(start 82.046826 -136.906)
		(end 82.780378 -136.172448)
		(width 0.635)
		(layer "In7.Cu")
		(net "P52V_HS_FILTER")
	)
	(segment
		(start 66.430906 -136.906)
		(end 67.164458 -136.172448)
		(width 0.635)
		(layer "In7.Cu")
		(net "P52V_HS_FILTER")
	)
	(segment
		(start 104.469946 -121.209816)
		(end 105.481882 -120.19788)
		(width 0.889)
		(layer "In7.Cu")
		(net "P52V_HS_FILTER")
	)
	(segment
		(start 82.046826 -136.906)
		(end 82.780378 -137.639552)
		(width 0.635)
		(layer "In7.Cu")
		(net "P52V_HS_FILTER")
	)
	(segment
		(start 134.239 -136.906)
		(end 134.972552 -137.639552)
		(width 0.635)
		(layer "In7.Cu")
		(net "P52V_HS_FILTER")
	)
	(segment
		(start 104.469946 -121.209816)
		(end 105.481882 -122.221752)
		(width 0.889)
		(layer "In7.Cu")
		(net "P52V_HS_FILTER")
	)
	(segment
		(start 144.47012 -121.209816)
		(end 145.482056 -122.221752)
		(width 0.889)
		(layer "In7.Cu")
		(net "P52V_HS_FILTER")
	)
	(segment
		(start 162.047174 -136.906)
		(end 162.780726 -137.639552)
		(width 0.635)
		(layer "In7.Cu")
		(net "P52V_HS_FILTER")
	)
	(segment
		(start 185.697622 -136.172448)
		(end 186.431174 -136.906)
		(width 0.635)
		(layer "In7.Cu")
		(net "P52V_HS_FILTER")
	)
	(segment
		(start 105.697274 -136.172448)
		(end 106.430826 -136.906)
		(width 0.635)
		(layer "In7.Cu")
		(net "P52V_HS_FILTER")
	)
	(segment
		(start 186.431174 -136.906)
		(end 187.164726 -136.172448)
		(width 0.635)
		(layer "In7.Cu")
		(net "P52V_HS_FILTER")
	)
	(segment
		(start 121.313448 -137.639552)
		(end 122.047 -136.906)
		(width 0.635)
		(layer "In7.Cu")
		(net "P52V_HS_FILTER")
	)
	(segment
		(start 173.505622 -136.172448)
		(end 174.239174 -136.906)
		(width 0.635)
		(layer "In7.Cu")
		(net "P52V_HS_FILTER")
	)
	(segment
		(start 42.046906 -136.906)
		(end 42.780458 -137.639552)
		(width 0.635)
		(layer "In7.Cu")
		(net "P52V_HS_FILTER")
	)
	(segment
		(start 64.470026 -121.209816)
		(end 65.481962 -120.19788)
		(width 0.889)
		(layer "In7.Cu")
		(net "P52V_HS_FILTER")
	)
	(segment
		(start 81.313274 -137.639552)
		(end 82.046826 -136.906)
		(width 0.635)
		(layer "In7.Cu")
		(net "P52V_HS_FILTER")
	)
	(segment
		(start 122.047 -136.906)
		(end 122.780552 -136.172448)
		(width 0.635)
		(layer "In7.Cu")
		(net "P52V_HS_FILTER")
	)
	(segment
		(start 184.470294 -121.209816)
		(end 185.48223 -120.19788)
		(width 0.889)
		(layer "In7.Cu")
		(net "P52V_HS_FILTER")
	)
	(segment
		(start 134.239 -136.906)
		(end 134.972552 -136.172448)
		(width 0.635)
		(layer "In7.Cu")
		(net "P52V_HS_FILTER")
	)
	(segment
		(start 133.505448 -137.639552)
		(end 134.239 -136.906)
		(width 0.635)
		(layer "In7.Cu")
		(net "P52V_HS_FILTER")
	)
	(segment
		(start 53.505354 -137.639552)
		(end 54.238906 -136.906)
		(width 0.635)
		(layer "In7.Cu")
		(net "P52V_HS_FILTER")
	)
	(segment
		(start 161.313622 -136.172448)
		(end 162.047174 -136.906)
		(width 0.635)
		(layer "In7.Cu")
		(net "P52V_HS_FILTER")
	)
	(segment
		(start 66.430906 -136.906)
		(end 67.164458 -137.639552)
		(width 0.635)
		(layer "In7.Cu")
		(net "P52V_HS_FILTER")
	)
	(segment
		(start 143.458184 -122.221752)
		(end 144.47012 -121.209816)
		(width 0.889)
		(layer "In7.Cu")
		(net "P52V_HS_FILTER")
	)
	(segment
		(start 133.505448 -136.172448)
		(end 134.239 -136.906)
		(width 0.635)
		(layer "In7.Cu")
		(net "P52V_HS_FILTER")
	)
	(segment
		(start 183.458358 -120.19788)
		(end 184.470294 -121.209816)
		(width 0.889)
		(layer "In7.Cu")
		(net "P52V_HS_FILTER")
	)
	(segment
		(start 63.45809 -120.19788)
		(end 64.470026 -121.209816)
		(width 0.889)
		(layer "In7.Cu")
		(net "P52V_HS_FILTER")
	)
	(segment
		(start 65.697354 -136.172448)
		(end 66.430906 -136.906)
		(width 0.635)
		(layer "In7.Cu")
		(net "P52V_HS_FILTER")
	)
	(segment
		(start 81.313274 -136.172448)
		(end 82.046826 -136.906)
		(width 0.635)
		(layer "In7.Cu")
		(net "P52V_HS_FILTER")
	)
	(segment
		(start 94.238826 -136.906)
		(end 94.972378 -136.172448)
		(width 0.635)
		(layer "In7.Cu")
		(net "P52V_HS_FILTER")
	)
	(segment
		(start 105.697274 -137.639552)
		(end 106.430826 -136.906)
		(width 0.635)
		(layer "In7.Cu")
		(net "P52V_HS_FILTER")
	)
	(segment
		(start 144.47012 -121.209816)
		(end 145.482056 -120.19788)
		(width 0.889)
		(layer "In7.Cu")
		(net "P52V_HS_FILTER")
	)
	(segment
		(start 121.313448 -136.172448)
		(end 122.047 -136.906)
		(width 0.635)
		(layer "In7.Cu")
		(net "P52V_HS_FILTER")
	)
	(segment
		(start 41.313354 -137.639552)
		(end 42.046906 -136.906)
		(width 0.635)
		(layer "In7.Cu")
		(net "P52V_HS_FILTER")
	)
	(segment
		(start 103.45801 -120.19788)
		(end 104.469946 -121.209816)
		(width 0.889)
		(layer "In7.Cu")
		(net "P52V_HS_FILTER")
	)
	(via
		(at 211.709 -68.21805)
		(size 0.762)
		(drill 0.254)
		(layers "F.Cu" "B.Cu")
		(net "SKU_ID_2")
	)
	(segment
		(start 211.074 -71.119746)
		(end 211.074 -70.12305)
		(width 0.17272)
		(layer "B.Cu")
		(net "SKU_ID_2")
	)
	(segment
		(start 211.709 -68.21805)
		(end 211.074 -67.58305)
		(width 0.17272)
		(layer "B.Cu")
		(net "SKU_ID_2")
	)
	(segment
		(start 210.860894 -71.332852)
		(end 211.074 -71.119746)
		(width 0.17272)
		(layer "B.Cu")
		(net "SKU_ID_2")
	)
	(segment
		(start 211.308696 -70.12305)
		(end 211.709 -69.722746)
		(width 0.17272)
		(layer "B.Cu")
		(net "SKU_ID_2")
	)
	(segment
		(start 210.860894 -73.152)
		(end 210.860894 -71.332852)
		(width 0.17272)
		(layer "B.Cu")
		(net "SKU_ID_2")
	)
	(segment
		(start 211.074 -70.12305)
		(end 211.308696 -70.12305)
		(width 0.17272)
		(layer "B.Cu")
		(net "SKU_ID_2")
	)
	(segment
		(start 211.709 -69.722746)
		(end 211.709 -68.21805)
		(width 0.17272)
		(layer "B.Cu")
		(net "SKU_ID_2")
	)
	(via
		(at 211.709 -71.374)
		(size 0.6604)
		(drill 0.3302)
		(layers "F.Cu" "B.Cu")
		(net "SKU_ID_1")
	)
	(segment
		(start 211.709 -71.52005)
		(end 211.709 -71.374)
		(width 0.17272)
		(layer "B.Cu")
		(net "SKU_ID_1")
	)
	(segment
		(start 212.979 -69.595746)
		(end 212.979 -68.21805)
		(width 0.17272)
		(layer "B.Cu")
		(net "SKU_ID_1")
	)
	(segment
		(start 212.344 -70.12305)
		(end 212.451696 -70.12305)
		(width 0.17272)
		(layer "B.Cu")
		(net "SKU_ID_1")
	)
	(segment
		(start 211.709 -71.374)
		(end 212.344 -70.739)
		(width 0.17272)
		(layer "B.Cu")
		(net "SKU_ID_1")
	)
	(segment
		(start 211.51088 -71.71817)
		(end 211.709 -71.52005)
		(width 0.17272)
		(layer "B.Cu")
		(net "SKU_ID_1")
	)
	(segment
		(start 212.979 -68.21805)
		(end 212.344 -67.58305)
		(width 0.17272)
		(layer "B.Cu")
		(net "SKU_ID_1")
	)
	(segment
		(start 212.451696 -70.12305)
		(end 212.979 -69.595746)
		(width 0.17272)
		(layer "B.Cu")
		(net "SKU_ID_1")
	)
	(segment
		(start 211.51088 -73.152)
		(end 211.51088 -71.71817)
		(width 0.17272)
		(layer "B.Cu")
		(net "SKU_ID_1")
	)
	(segment
		(start 212.344 -70.739)
		(end 212.344 -70.12305)
		(width 0.17272)
		(layer "B.Cu")
		(net "SKU_ID_1")
	)
	(via
		(at 214.249 -68.21805)
		(size 0.762)
		(drill 0.254)
		(layers "F.Cu" "B.Cu")
		(net "SKU_ID_0")
	)
	(segment
		(start 214.249 -69.723)
		(end 214.249 -68.21805)
		(width 0.17272)
		(layer "B.Cu")
		(net "SKU_ID_0")
	)
	(segment
		(start 213.106 -71.07301)
		(end 213.106 -70.63105)
		(width 0.17272)
		(layer "B.Cu")
		(net "SKU_ID_0")
	)
	(segment
		(start 213.84895 -70.12305)
		(end 214.249 -69.723)
		(width 0.17272)
		(layer "B.Cu")
		(net "SKU_ID_0")
	)
	(segment
		(start 212.16112 -73.152)
		(end 212.16112 -72.01789)
		(width 0.17272)
		(layer "B.Cu")
		(net "SKU_ID_0")
	)
	(segment
		(start 213.614 -70.12305)
		(end 213.84895 -70.12305)
		(width 0.17272)
		(layer "B.Cu")
		(net "SKU_ID_0")
	)
	(segment
		(start 214.249 -68.21805)
		(end 213.614 -67.58305)
		(width 0.17272)
		(layer "B.Cu")
		(net "SKU_ID_0")
	)
	(segment
		(start 213.106 -70.63105)
		(end 213.614 -70.12305)
		(width 0.17272)
		(layer "B.Cu")
		(net "SKU_ID_0")
	)
	(segment
		(start 212.16112 -72.01789)
		(end 213.106 -71.07301)
		(width 0.17272)
		(layer "B.Cu")
		(net "SKU_ID_0")
	)
	(segment
		(start 269.61846 -160.194498)
		(end 194.717416 -160.194498)
		(width 0.12954)
		(layer "In7.Cu")
		(net "TDR_SE_50_OHM_IN2")
	)
	(segment
		(start 269.748 -162.604958)
		(end 269.748 -160.324038)
		(width 0.12954)
		(layer "In7.Cu")
		(net "TDR_SE_50_OHM_IN2")
	)
	(segment
		(start 269.61846 -162.734498)
		(end 269.748 -162.604958)
		(width 0.12954)
		(layer "In7.Cu")
		(net "TDR_SE_50_OHM_IN2")
	)
	(segment
		(start 269.748 -160.324038)
		(end 269.61846 -160.194498)
		(width 0.12954)
		(layer "In7.Cu")
		(net "TDR_SE_50_OHM_IN2")
	)
	(segment
		(start 194.717416 -162.734498)
		(end 269.61846 -162.734498)
		(width 0.12954)
		(layer "In7.Cu")
		(net "TDR_SE_50_OHM_IN2")
	)
	(segment
		(start 200.17232 -155.585668)
		(end 275.039582 -155.585668)
		(width 0.17272)
		(layer "B.Cu")
		(net "TDR_SE_50_OHM_BOT")
	)
	(segment
		(start 199.9996 -153.218388)
		(end 199.9996 -155.412948)
		(width 0.17272)
		(layer "B.Cu")
		(net "TDR_SE_50_OHM_BOT")
	)
	(segment
		(start 275.039582 -153.045668)
		(end 200.17232 -153.045668)
		(width 0.17272)
		(layer "B.Cu")
		(net "TDR_SE_50_OHM_BOT")
	)
	(segment
		(start 199.9996 -155.412948)
		(end 200.17232 -155.585668)
		(width 0.17272)
		(layer "B.Cu")
		(net "TDR_SE_50_OHM_BOT")
	)
	(segment
		(start 200.17232 -153.045668)
		(end 199.9996 -153.218388)
		(width 0.17272)
		(layer "B.Cu")
		(net "TDR_SE_50_OHM_BOT")
	)
	(segment
		(start 269.721076 -153.175208)
		(end 269.591536 -153.045668)
		(width 0.12954)
		(layer "In2.Cu")
		(net "TDR_SE_50_OHM_IN1")
	)
	(segment
		(start 269.721076 -155.456128)
		(end 269.721076 -153.175208)
		(width 0.12954)
		(layer "In2.Cu")
		(net "TDR_SE_50_OHM_IN1")
	)
	(segment
		(start 269.591536 -153.045668)
		(end 194.690492 -153.045668)
		(width 0.12954)
		(layer "In2.Cu")
		(net "TDR_SE_50_OHM_IN1")
	)
	(segment
		(start 194.690492 -155.585668)
		(end 269.591536 -155.585668)
		(width 0.12954)
		(layer "In2.Cu")
		(net "TDR_SE_50_OHM_IN1")
	)
	(segment
		(start 269.591536 -155.585668)
		(end 269.721076 -155.456128)
		(width 0.12954)
		(layer "In2.Cu")
		(net "TDR_SE_50_OHM_IN1")
	)
	(segment
		(start 199.9996 -160.367218)
		(end 199.9996 -162.561778)
		(width 0.17272)
		(layer "F.Cu")
		(net "TDR_SE_50_OHM_TOP")
	)
	(segment
		(start 200.17232 -160.194498)
		(end 199.9996 -160.367218)
		(width 0.17272)
		(layer "F.Cu")
		(net "TDR_SE_50_OHM_TOP")
	)
	(segment
		(start 199.9996 -162.561778)
		(end 200.17232 -162.734498)
		(width 0.17272)
		(layer "F.Cu")
		(net "TDR_SE_50_OHM_TOP")
	)
	(segment
		(start 275.039582 -160.194498)
		(end 200.17232 -160.194498)
		(width 0.17272)
		(layer "F.Cu")
		(net "TDR_SE_50_OHM_TOP")
	)
	(segment
		(start 200.17232 -162.734498)
		(end 275.039582 -162.734498)
		(width 0.17272)
		(layer "F.Cu")
		(net "TDR_SE_50_OHM_TOP")
	)
	(segment
		(start 149.212554 -91.38666)
		(end 9.35863 -91.38666)
		(width 0.17272)
		(layer "B.Cu")
		(net "FAN_PWR_EN_BUF")
	)
	(segment
		(start 210.730846 -95.570548)
		(end 196.279008 -95.570548)
		(width 0.17272)
		(layer "B.Cu")
		(net "FAN_PWR_EN_BUF")
	)
	(segment
		(start 153.055574 -87.54364)
		(end 149.212554 -91.38666)
		(width 0.17272)
		(layer "B.Cu")
		(net "FAN_PWR_EN_BUF")
	)
	(segment
		(start 8.736584 -86.132416)
		(end 9.58088 -85.28812)
		(width 0.17272)
		(layer "B.Cu")
		(net "FAN_PWR_EN_BUF")
	)
	(segment
		(start 178.71694 -87.54364)
		(end 153.055574 -87.54364)
		(width 0.17272)
		(layer "B.Cu")
		(net "FAN_PWR_EN_BUF")
	)
	(segment
		(start 9.35863 -91.38666)
		(end 6.858 -88.88603)
		(width 0.17272)
		(layer "B.Cu")
		(net "FAN_PWR_EN_BUF")
	)
	(segment
		(start 6.858 -87.00897)
		(end 7.734554 -86.132416)
		(width 0.17272)
		(layer "B.Cu")
		(net "FAN_PWR_EN_BUF")
	)
	(segment
		(start 9.58088 -85.28812)
		(end 10.851896 -85.28812)
		(width 0.17272)
		(layer "B.Cu")
		(net "FAN_PWR_EN_BUF")
	)
	(segment
		(start 195.766944 -96.082612)
		(end 187.255912 -96.082612)
		(width 0.17272)
		(layer "B.Cu")
		(net "FAN_PWR_EN_BUF")
	)
	(segment
		(start 10.851896 -85.28812)
		(end 11.12012 -85.019896)
		(width 0.17272)
		(layer "B.Cu")
		(net "FAN_PWR_EN_BUF")
	)
	(segment
		(start 196.279008 -95.570548)
		(end 195.766944 -96.082612)
		(width 0.17272)
		(layer "B.Cu")
		(net "FAN_PWR_EN_BUF")
	)
	(segment
		(start 214.122 -92.179394)
		(end 210.730846 -95.570548)
		(width 0.17272)
		(layer "B.Cu")
		(net "FAN_PWR_EN_BUF")
	)
	(segment
		(start 187.255912 -96.082612)
		(end 178.71694 -87.54364)
		(width 0.17272)
		(layer "B.Cu")
		(net "FAN_PWR_EN_BUF")
	)
	(segment
		(start 6.858 -88.88603)
		(end 6.858 -87.00897)
		(width 0.17272)
		(layer "B.Cu")
		(net "FAN_PWR_EN_BUF")
	)
	(segment
		(start 7.734554 -86.132416)
		(end 8.736584 -86.132416)
		(width 0.17272)
		(layer "B.Cu")
		(net "FAN_PWR_EN_BUF")
	)
	(segment
		(start 214.122 -91.45905)
		(end 214.122 -92.179394)
		(width 0.17272)
		(layer "B.Cu")
		(net "FAN_PWR_EN_BUF")
	)
	(via
		(at 214.336122 -90.002868)
		(size 0.762)
		(drill 0.254)
		(layers "F.Cu" "B.Cu")
		(net "FAN_PWR_EN_BUF_R")
	)
	(segment
		(start 214.122 -90.21699)
		(end 214.336122 -90.002868)
		(width 0.17272)
		(layer "B.Cu")
		(net "FAN_PWR_EN_BUF_R")
	)
	(segment
		(start 214.336122 -90.002868)
		(end 214.56904 -89.76995)
		(width 0.17272)
		(layer "B.Cu")
		(net "FAN_PWR_EN_BUF_R")
	)
	(segment
		(start 215.265 -90.65895)
		(end 214.122 -90.65895)
		(width 0.17272)
		(layer "B.Cu")
		(net "FAN_PWR_EN_BUF_R")
	)
	(segment
		(start 214.56904 -89.76995)
		(end 214.56904 -88.855042)
		(width 0.17272)
		(layer "B.Cu")
		(net "FAN_PWR_EN_BUF_R")
	)
	(segment
		(start 214.122 -90.65895)
		(end 214.122 -90.21699)
		(width 0.17272)
		(layer "B.Cu")
		(net "FAN_PWR_EN_BUF_R")
	)
	(segment
		(start 239.776 -72.0852)
		(end 241.554 -73.8632)
		(width 0.17272)
		(layer "F.Cu")
		(net "SMB_MB_PDB_SDA")
	)
	(segment
		(start 241.554 -73.8632)
		(end 241.554 -78.119224)
		(width 0.17272)
		(layer "F.Cu")
		(net "SMB_MB_PDB_SDA")
	)
	(segment
		(start 241.554 -78.119224)
		(end 239.565434 -80.10779)
		(width 0.17272)
		(layer "F.Cu")
		(net "SMB_MB_PDB_SDA")
	)
	(segment
		(start 238.76 -72.0852)
		(end 239.776 -72.0852)
		(width 0.17272)
		(layer "F.Cu")
		(net "SMB_MB_PDB_SDA")
	)
	(via
		(at 239.565434 -80.10779)
		(size 0.508)
		(drill 0.254)
		(layers "F.Cu" "B.Cu")
		(net "SMB_MB_PDB_SDA")
	)
	(via
		(at 238.76 -72.0852)
		(size 0.762)
		(drill 0.254)
		(layers "F.Cu" "B.Cu")
		(net "SMB_MB_PDB_SDA")
	)
	(segment
		(start 238.76 -72.0852)
		(end 238.76 -71.39305)
		(width 0.17272)
		(layer "B.Cu")
		(net "SMB_MB_PDB_SDA")
	)
	(segment
		(start 239.565434 -80.10779)
		(end 238.955834 -80.10779)
		(width 0.17272)
		(layer "B.Cu")
		(net "SMB_MB_PDB_SDA")
	)
	(segment
		(start 238.372904 -81.939384)
		(end 238.372904 -80.70977)
		(width 0.17272)
		(layer "B.Cu")
		(net "SMB_MB_PDB_SDA")
	)
	(segment
		(start 238.372904 -80.70977)
		(end 238.955834 -80.12684)
		(width 0.17272)
		(layer "B.Cu")
		(net "SMB_MB_PDB_SDA")
	)
	(segment
		(start 238.955834 -80.12684)
		(end 238.955834 -80.10779)
		(width 0.17272)
		(layer "B.Cu")
		(net "SMB_MB_PDB_SDA")
	)
	(via
		(at 241.808 -72.771)
		(size 0.6604)
		(drill 0.3302)
		(layers "F.Cu" "B.Cu")
		(net "SMB_MB_PDB_SCL")
	)
	(segment
		(start 242.03914 -73.00214)
		(end 242.03914 -87.525606)
		(width 0.17272)
		(layer "B.Cu")
		(net "SMB_MB_PDB_SCL")
	)
	(segment
		(start 238.372904 -87.63381)
		(end 239.082834 -88.34374)
		(width 0.17272)
		(layer "B.Cu")
		(net "SMB_MB_PDB_SCL")
	)
	(segment
		(start 238.372904 -86.404196)
		(end 238.372904 -87.63381)
		(width 0.17272)
		(layer "B.Cu")
		(net "SMB_MB_PDB_SCL")
	)
	(segment
		(start 240.538 -71.39305)
		(end 240.538 -71.501)
		(width 0.17272)
		(layer "B.Cu")
		(net "SMB_MB_PDB_SCL")
	)
	(segment
		(start 239.082834 -88.34374)
		(end 239.082834 -88.36279)
		(width 0.17272)
		(layer "B.Cu")
		(net "SMB_MB_PDB_SCL")
	)
	(segment
		(start 242.03914 -87.525606)
		(end 241.201956 -88.36279)
		(width 0.17272)
		(layer "B.Cu")
		(net "SMB_MB_PDB_SCL")
	)
	(segment
		(start 241.808 -72.771)
		(end 242.03914 -73.00214)
		(width 0.17272)
		(layer "B.Cu")
		(net "SMB_MB_PDB_SCL")
	)
	(segment
		(start 241.201956 -88.36279)
		(end 239.082834 -88.36279)
		(width 0.17272)
		(layer "B.Cu")
		(net "SMB_MB_PDB_SCL")
	)
	(segment
		(start 240.538 -71.501)
		(end 241.808 -72.771)
		(width 0.17272)
		(layer "B.Cu")
		(net "SMB_MB_PDB_SCL")
	)
	(via
		(at 238.169704 -68.162424)
		(size 0.6604)
		(drill 0.3302)
		(layers "F.Cu" "B.Cu")
		(net "SMB_MB_PDB_R_SDA")
	)
	(segment
		(start 237.076488 -67.069208)
		(end 236.3724 -66.36512)
		(width 0.17272)
		(layer "B.Cu")
		(net "SMB_MB_PDB_R_SDA")
	)
	(segment
		(start 236.656372 -67.719448)
		(end 237.076488 -67.299332)
		(width 0.17272)
		(layer "B.Cu")
		(net "SMB_MB_PDB_R_SDA")
	)
	(segment
		(start 236.3724 -66.36512)
		(end 225.914204 -66.36512)
		(width 0.17272)
		(layer "B.Cu")
		(net "SMB_MB_PDB_R_SDA")
	)
	(segment
		(start 212.491828 -35.008058)
		(end 212.227414 -34.632392)
		(width 0.17272)
		(layer "B.Cu")
		(net "SMB_MB_PDB_R_SDA")
	)
	(segment
		(start 239.55502 -74.62393)
		(end 239.55502 -73.92797)
		(width 0.17272)
		(layer "B.Cu")
		(net "SMB_MB_PDB_R_SDA")
	)
	(segment
		(start 212.227414 -34.632392)
		(end 208.929986 -32.869632)
		(width 0.17272)
		(layer "B.Cu")
		(net "SMB_MB_PDB_R_SDA")
	)
	(segment
		(start 237.700058 -67.692778)
		(end 237.469934 -67.692778)
		(width 0.17272)
		(layer "B.Cu")
		(net "SMB_MB_PDB_R_SDA")
	)
	(segment
		(start 238.125 -72.49795)
		(end 238.76 -73.13295)
		(width 0.17272)
		(layer "B.Cu")
		(net "SMB_MB_PDB_R_SDA")
	)
	(segment
		(start 212.823806 -38.246812)
		(end 212.823806 -36.33343)
		(width 0.17272)
		(layer "B.Cu")
		(net "SMB_MB_PDB_R_SDA")
	)
	(segment
		(start 225.914204 -66.36512)
		(end 220.853 -61.303916)
		(width 0.17272)
		(layer "B.Cu")
		(net "SMB_MB_PDB_R_SDA")
	)
	(segment
		(start 238.76 -70.59295)
		(end 238.76 -68.75272)
		(width 0.17272)
		(layer "B.Cu")
		(net "SMB_MB_PDB_R_SDA")
	)
	(segment
		(start 236.656372 -67.949572)
		(end 236.656372 -67.719448)
		(width 0.17272)
		(layer "B.Cu")
		(net "SMB_MB_PDB_R_SDA")
	)
	(segment
		(start 238.125 -71.22795)
		(end 238.125 -72.49795)
		(width 0.17272)
		(layer "B.Cu")
		(net "SMB_MB_PDB_R_SDA")
	)
	(segment
		(start 238.169704 -68.162424)
		(end 237.700058 -67.692778)
		(width 0.17272)
		(layer "B.Cu")
		(net "SMB_MB_PDB_R_SDA")
	)
	(segment
		(start 212.823806 -36.33343)
		(end 212.491828 -35.008058)
		(width 0.17272)
		(layer "B.Cu")
		(net "SMB_MB_PDB_R_SDA")
	)
	(segment
		(start 236.819694 -68.112894)
		(end 236.656372 -67.949572)
		(width 0.17272)
		(layer "B.Cu")
		(net "SMB_MB_PDB_R_SDA")
	)
	(segment
		(start 237.049818 -68.112894)
		(end 236.819694 -68.112894)
		(width 0.17272)
		(layer "B.Cu")
		(net "SMB_MB_PDB_R_SDA")
	)
	(segment
		(start 237.076488 -67.299332)
		(end 237.076488 -67.069208)
		(width 0.17272)
		(layer "B.Cu")
		(net "SMB_MB_PDB_R_SDA")
	)
	(segment
		(start 239.55502 -73.92797)
		(end 238.76 -73.13295)
		(width 0.17272)
		(layer "B.Cu")
		(net "SMB_MB_PDB_R_SDA")
	)
	(segment
		(start 238.76 -75.41895)
		(end 239.55502 -74.62393)
		(width 0.17272)
		(layer "B.Cu")
		(net "SMB_MB_PDB_R_SDA")
	)
	(segment
		(start 220.853 -46.276006)
		(end 212.823806 -38.246812)
		(width 0.17272)
		(layer "B.Cu")
		(net "SMB_MB_PDB_R_SDA")
	)
	(segment
		(start 238.76 -70.59295)
		(end 238.125 -71.22795)
		(width 0.17272)
		(layer "B.Cu")
		(net "SMB_MB_PDB_R_SDA")
	)
	(segment
		(start 238.76 -68.75272)
		(end 238.169704 -68.162424)
		(width 0.17272)
		(layer "B.Cu")
		(net "SMB_MB_PDB_R_SDA")
	)
	(segment
		(start 237.469934 -67.692778)
		(end 237.049818 -68.112894)
		(width 0.17272)
		(layer "B.Cu")
		(net "SMB_MB_PDB_R_SDA")
	)
	(segment
		(start 220.853 -61.303916)
		(end 220.853 -46.276006)
		(width 0.17272)
		(layer "B.Cu")
		(net "SMB_MB_PDB_R_SDA")
	)
	(via
		(at 240.081054 -69.254624)
		(size 0.6604)
		(drill 0.3302)
		(layers "F.Cu" "B.Cu")
		(net "SMB_MB_PDB_R_SCL")
	)
	(segment
		(start 240.538 -69.71157)
		(end 240.081054 -69.254624)
		(width 0.17272)
		(layer "B.Cu")
		(net "SMB_MB_PDB_R_SCL")
	)
	(segment
		(start 221.4372 -45.735748)
		(end 221.4372 -61.068966)
		(width 0.17272)
		(layer "B.Cu")
		(net "SMB_MB_PDB_R_SCL")
	)
	(segment
		(start 226.154234 -65.786)
		(end 236.61243 -65.786)
		(width 0.17272)
		(layer "B.Cu")
		(net "SMB_MB_PDB_R_SCL")
	)
	(segment
		(start 212.361272 -33.677606)
		(end 213.211156 -34.713164)
		(width 0.17272)
		(layer "B.Cu")
		(net "SMB_MB_PDB_R_SCL")
	)
	(segment
		(start 241.3889 -74.56805)
		(end 241.3889 -73.7489)
		(width 0.17272)
		(layer "B.Cu")
		(net "SMB_MB_PDB_R_SCL")
	)
	(segment
		(start 221.4372 -61.068966)
		(end 226.154234 -65.786)
		(width 0.17272)
		(layer "B.Cu")
		(net "SMB_MB_PDB_R_SCL")
	)
	(segment
		(start 236.61243 -65.786)
		(end 240.081054 -69.254624)
		(width 0.17272)
		(layer "B.Cu")
		(net "SMB_MB_PDB_R_SCL")
	)
	(segment
		(start 211.469986 -32.869632)
		(end 212.361272 -33.677606)
		(width 0.17272)
		(layer "B.Cu")
		(net "SMB_MB_PDB_R_SCL")
	)
	(segment
		(start 240.538 -70.59295)
		(end 240.51895 -70.59295)
		(width 0.17272)
		(layer "B.Cu")
		(net "SMB_MB_PDB_R_SCL")
	)
	(segment
		(start 239.95888 -71.15302)
		(end 239.95888 -72.55383)
		(width 0.17272)
		(layer "B.Cu")
		(net "SMB_MB_PDB_R_SCL")
	)
	(segment
		(start 241.3889 -73.7489)
		(end 240.77295 -73.13295)
		(width 0.17272)
		(layer "B.Cu")
		(net "SMB_MB_PDB_R_SCL")
	)
	(segment
		(start 240.538 -70.59295)
		(end 240.538 -69.71157)
		(width 0.17272)
		(layer "B.Cu")
		(net "SMB_MB_PDB_R_SCL")
	)
	(segment
		(start 213.211156 -34.713164)
		(end 213.695026 -36.06546)
		(width 0.17272)
		(layer "B.Cu")
		(net "SMB_MB_PDB_R_SCL")
	)
	(segment
		(start 213.695026 -36.06546)
		(end 213.695026 -37.993574)
		(width 0.17272)
		(layer "B.Cu")
		(net "SMB_MB_PDB_R_SCL")
	)
	(segment
		(start 240.538 -75.41895)
		(end 241.3889 -74.56805)
		(width 0.17272)
		(layer "B.Cu")
		(net "SMB_MB_PDB_R_SCL")
	)
	(segment
		(start 240.51895 -70.59295)
		(end 239.95888 -71.15302)
		(width 0.17272)
		(layer "B.Cu")
		(net "SMB_MB_PDB_R_SCL")
	)
	(segment
		(start 239.95888 -72.55383)
		(end 240.538 -73.13295)
		(width 0.17272)
		(layer "B.Cu")
		(net "SMB_MB_PDB_R_SCL")
	)
	(segment
		(start 213.695026 -37.993574)
		(end 221.4372 -45.735748)
		(width 0.17272)
		(layer "B.Cu")
		(net "SMB_MB_PDB_R_SCL")
	)
	(segment
		(start 240.77295 -73.13295)
		(end 240.538 -73.13295)
		(width 0.17272)
		(layer "B.Cu")
		(net "SMB_MB_PDB_R_SCL")
	)
	(via
		(at 225.552 -72.00265)
		(size 0.508)
		(drill 0.254)
		(layers "F.Cu" "B.Cu")
		(net "GPU_HSC_EN")
	)
	(via
		(at 197.8914 -83.01228)
		(size 0.508)
		(drill 0.254)
		(layers "F.Cu" "B.Cu")
		(net "GPU_HSC_EN")
	)
	(segment
		(start 184.598056 -81.63052)
		(end 183.063896 -83.16468)
		(width 0.17272)
		(layer "B.Cu")
		(net "GPU_HSC_EN")
	)
	(segment
		(start 11.398504 -82.75828)
		(end 11.12012 -82.479896)
		(width 0.17272)
		(layer "B.Cu")
		(net "GPU_HSC_EN")
	)
	(segment
		(start 197.8914 -83.01228)
		(end 193.14668 -83.01228)
		(width 0.17272)
		(layer "B.Cu")
		(net "GPU_HSC_EN")
	)
	(segment
		(start 149.012148 -85.852)
		(end 45.969428 -85.852)
		(width 0.17272)
		(layer "B.Cu")
		(net "GPU_HSC_EN")
	)
	(segment
		(start 15.575026 -82.75828)
		(end 11.398504 -82.75828)
		(width 0.17272)
		(layer "B.Cu")
		(net "GPU_HSC_EN")
	)
	(segment
		(start 38.130226 -83.28152)
		(end 35.813746 -85.598)
		(width 0.17272)
		(layer "B.Cu")
		(net "GPU_HSC_EN")
	)
	(segment
		(start 183.063896 -83.16468)
		(end 151.699468 -83.16468)
		(width 0.17272)
		(layer "B.Cu")
		(net "GPU_HSC_EN")
	)
	(segment
		(start 18.414746 -85.598)
		(end 15.575026 -82.75828)
		(width 0.17272)
		(layer "B.Cu")
		(net "GPU_HSC_EN")
	)
	(segment
		(start 151.699468 -83.16468)
		(end 149.012148 -85.852)
		(width 0.17272)
		(layer "B.Cu")
		(net "GPU_HSC_EN")
	)
	(segment
		(start 35.813746 -85.598)
		(end 18.414746 -85.598)
		(width 0.17272)
		(layer "B.Cu")
		(net "GPU_HSC_EN")
	)
	(segment
		(start 191.76492 -81.63052)
		(end 184.598056 -81.63052)
		(width 0.17272)
		(layer "B.Cu")
		(net "GPU_HSC_EN")
	)
	(segment
		(start 193.14668 -83.01228)
		(end 191.76492 -81.63052)
		(width 0.17272)
		(layer "B.Cu")
		(net "GPU_HSC_EN")
	)
	(segment
		(start 45.969428 -85.852)
		(end 43.398948 -83.28152)
		(width 0.17272)
		(layer "B.Cu")
		(net "GPU_HSC_EN")
	)
	(segment
		(start 225.552 -72.00265)
		(end 225.552 -71.39305)
		(width 0.17272)
		(layer "B.Cu")
		(net "GPU_HSC_EN")
	)
	(segment
		(start 43.398948 -83.28152)
		(end 38.130226 -83.28152)
		(width 0.17272)
		(layer "B.Cu")
		(net "GPU_HSC_EN")
	)
	(segment
		(start 223.266 -82.169)
		(end 225.552 -79.883)
		(width 0.12954)
		(layer "In7.Cu")
		(net "GPU_HSC_EN")
	)
	(segment
		(start 212.13826 -81.83626)
		(end 212.471 -82.169)
		(width 0.12954)
		(layer "In7.Cu")
		(net "GPU_HSC_EN")
	)
	(segment
		(start 212.471 -82.169)
		(end 223.266 -82.169)
		(width 0.12954)
		(layer "In7.Cu")
		(net "GPU_HSC_EN")
	)
	(segment
		(start 198.209916 -83.330796)
		(end 203.443332 -83.330796)
		(width 0.12954)
		(layer "In7.Cu")
		(net "GPU_HSC_EN")
	)
	(segment
		(start 197.8914 -83.01228)
		(end 198.209916 -83.330796)
		(width 0.12954)
		(layer "In7.Cu")
		(net "GPU_HSC_EN")
	)
	(segment
		(start 204.937868 -81.83626)
		(end 212.13826 -81.83626)
		(width 0.12954)
		(layer "In7.Cu")
		(net "GPU_HSC_EN")
	)
	(segment
		(start 225.552 -79.883)
		(end 225.552 -72.00265)
		(width 0.12954)
		(layer "In7.Cu")
		(net "GPU_HSC_EN")
	)
	(segment
		(start 203.443332 -83.330796)
		(end 204.937868 -81.83626)
		(width 0.12954)
		(layer "In7.Cu")
		(net "GPU_HSC_EN")
	)
	(via
		(at 221.234 -88.392)
		(size 0.6604)
		(drill 0.3302)
		(layers "F.Cu" "B.Cu")
		(net "SMB_FRU_CLK")
	)
	(segment
		(start 221.234 -88.392)
		(end 220.98 -88.138)
		(width 0.17272)
		(layer "B.Cu")
		(net "SMB_FRU_CLK")
	)
	(segment
		(start 220.726 -89.64295)
		(end 221.234 -89.13495)
		(width 0.17272)
		(layer "B.Cu")
		(net "SMB_FRU_CLK")
	)
	(segment
		(start 221.234 -89.13495)
		(end 221.234 -88.392)
		(width 0.17272)
		(layer "B.Cu")
		(net "SMB_FRU_CLK")
	)
	(segment
		(start 220.98 -88.138)
		(end 220.98 -86.0806)
		(width 0.17272)
		(layer "B.Cu")
		(net "SMB_FRU_CLK")
	)
	(via
		(at 218.44 -88.392)
		(size 0.6604)
		(drill 0.3302)
		(layers "F.Cu" "B.Cu")
		(net "SMB_FRU_DAT")
	)
	(segment
		(start 218.44 -88.49995)
		(end 218.44 -88.392)
		(width 0.17272)
		(layer "B.Cu")
		(net "SMB_FRU_DAT")
	)
	(segment
		(start 219.71 -87.122)
		(end 219.71 -86.0806)
		(width 0.17272)
		(layer "B.Cu")
		(net "SMB_FRU_DAT")
	)
	(segment
		(start 218.44 -88.392)
		(end 219.71 -87.122)
		(width 0.17272)
		(layer "B.Cu")
		(net "SMB_FRU_DAT")
	)
	(segment
		(start 219.583 -89.64295)
		(end 218.44 -88.49995)
		(width 0.17272)
		(layer "B.Cu")
		(net "SMB_FRU_DAT")
	)
	(via
		(at 237.072678 -87.590122)
		(size 0.762)
		(drill 0.254)
		(layers "F.Cu" "B.Cu")
		(net "MB_MISC_I2C_EN")
	)
	(segment
		(start 237.072678 -88.302846)
		(end 237.031784 -88.34374)
		(width 0.17272)
		(layer "B.Cu")
		(net "MB_MISC_I2C_EN")
	)
	(segment
		(start 237.072678 -87.590122)
		(end 237.072678 -88.302846)
		(width 0.17272)
		(layer "B.Cu")
		(net "MB_MISC_I2C_EN")
	)
	(segment
		(start 237.072678 -86.404196)
		(end 237.072678 -87.590122)
		(width 0.17272)
		(layer "B.Cu")
		(net "MB_MISC_I2C_EN")
	)
	(segment
		(start 184.023 -78.486)
		(end 184.023 -77.23505)
		(width 0.4572)
		(layer "B.Cu")
		(net "P12V_MB1_SENSE+")
	)
	(segment
		(start 149.4536 -80.4418)
		(end 182.0672 -80.4418)
		(width 0.4572)
		(layer "B.Cu")
		(net "P12V_MB1_SENSE+")
	)
	(segment
		(start 132.21462 -82.43062)
		(end 147.46478 -82.43062)
		(width 0.4572)
		(layer "B.Cu")
		(net "P12V_MB1_SENSE+")
	)
	(segment
		(start 184.023 -77.23505)
		(end 183.896 -77.10805)
		(width 0.4572)
		(layer "B.Cu")
		(net "P12V_MB1_SENSE+")
	)
	(segment
		(start 102.849934 -76.30795)
		(end 102.873302 -76.331318)
		(width 0.381)
		(layer "B.Cu")
		(net "P12V_MB1_SENSE+")
	)
	(segment
		(start 102.824534 -76.30795)
		(end 102.849934 -76.30795)
		(width 0.381)
		(layer "B.Cu")
		(net "P12V_MB1_SENSE+")
	)
	(segment
		(start 103.886 -77.10805)
		(end 126.89205 -77.10805)
		(width 0.4572)
		(layer "B.Cu")
		(net "P12V_MB1_SENSE+")
	)
	(segment
		(start 126.89205 -77.10805)
		(end 132.21462 -82.43062)
		(width 0.4572)
		(layer "B.Cu")
		(net "P12V_MB1_SENSE+")
	)
	(segment
		(start 101.854 -68.86575)
		(end 101.854 -74.295)
		(width 0.4572)
		(layer "B.Cu")
		(net "P12V_MB1_SENSE+")
	)
	(segment
		(start 147.46478 -82.43062)
		(end 149.4536 -80.4418)
		(width 0.4572)
		(layer "B.Cu")
		(net "P12V_MB1_SENSE+")
	)
	(segment
		(start 102.991412 -76.331318)
		(end 103.768144 -77.10805)
		(width 0.381)
		(layer "B.Cu")
		(net "P12V_MB1_SENSE+")
	)
	(segment
		(start 102.873302 -76.331318)
		(end 102.991412 -76.331318)
		(width 0.381)
		(layer "B.Cu")
		(net "P12V_MB1_SENSE+")
	)
	(segment
		(start 102.849934 -67.869816)
		(end 101.854 -68.86575)
		(width 0.4572)
		(layer "B.Cu")
		(net "P12V_MB1_SENSE+")
	)
	(segment
		(start 103.768144 -77.10805)
		(end 103.886 -77.10805)
		(width 0.381)
		(layer "B.Cu")
		(net "P12V_MB1_SENSE+")
	)
	(segment
		(start 102.824534 -75.265534)
		(end 102.824534 -76.30795)
		(width 0.4572)
		(layer "B.Cu")
		(net "P12V_MB1_SENSE+")
	)
	(segment
		(start 182.0672 -80.4418)
		(end 184.023 -78.486)
		(width 0.4572)
		(layer "B.Cu")
		(net "P12V_MB1_SENSE+")
	)
	(segment
		(start 101.854 -74.295)
		(end 102.824534 -75.265534)
		(width 0.4572)
		(layer "B.Cu")
		(net "P12V_MB1_SENSE+")
	)
	(segment
		(start 99.314 -66.802)
		(end 95.917766 -66.802)
		(width 0.17272)
		(layer "B.Cu")
		(net "SMB_BRICK1_SDA")
	)
	(segment
		(start 95.917766 -66.802)
		(end 94.84995 -67.869816)
		(width 0.17272)
		(layer "B.Cu")
		(net "SMB_BRICK1_SDA")
	)
	(segment
		(start 99.822 -75.71105)
		(end 99.822 -67.31)
		(width 0.17272)
		(layer "B.Cu")
		(net "SMB_BRICK1_SDA")
	)
	(segment
		(start 99.20605 -76.327)
		(end 99.822 -75.71105)
		(width 0.17272)
		(layer "B.Cu")
		(net "SMB_BRICK1_SDA")
	)
	(segment
		(start 99.822 -67.31)
		(end 99.314 -66.802)
		(width 0.17272)
		(layer "B.Cu")
		(net "SMB_BRICK1_SDA")
	)
	(segment
		(start 100.849938 -76.30795)
		(end 100.849938 -67.869816)
		(width 0.17272)
		(layer "B.Cu")
		(net "BRICK1_PMBADD")
	)
	(segment
		(start 94.76105 -76.327)
		(end 94.76105 -69.958712)
		(width 0.17272)
		(layer "B.Cu")
		(net "SMB_BRICK1_ALERT")
	)
	(segment
		(start 94.76105 -69.958712)
		(end 96.849946 -67.869816)
		(width 0.17272)
		(layer "B.Cu")
		(net "SMB_BRICK1_ALERT")
	)
	(segment
		(start 92.849954 -67.869816)
		(end 92.849954 -76.30795)
		(width 0.4572)
		(layer "B.Cu")
		(net "P12V_MB1_SENSE-")
	)
	(segment
		(start 98.09861 -74.825352)
		(end 97.11944 -74.825352)
		(width 0.17272)
		(layer "B.Cu")
		(net "SMB_BRICK1_SCL")
	)
	(segment
		(start 98.09861 -72.783192)
		(end 98.298 -72.583802)
		(width 0.17272)
		(layer "B.Cu")
		(net "SMB_BRICK1_SCL")
	)
	(segment
		(start 98.298 -72.583802)
		(end 98.298 -72.301862)
		(width 0.17272)
		(layer "B.Cu")
		(net "SMB_BRICK1_SCL")
	)
	(segment
		(start 97.11944 -75.506072)
		(end 98.09861 -75.506072)
		(width 0.17272)
		(layer "B.Cu")
		(net "SMB_BRICK1_SCL")
	)
	(segment
		(start 98.09861 -73.463912)
		(end 97.11944 -73.463912)
		(width 0.17272)
		(layer "B.Cu")
		(net "SMB_BRICK1_SCL")
	)
	(segment
		(start 97.11944 -72.783192)
		(end 98.09861 -72.783192)
		(width 0.17272)
		(layer "B.Cu")
		(net "SMB_BRICK1_SCL")
	)
	(segment
		(start 98.298 -75.024742)
		(end 98.09861 -74.825352)
		(width 0.17272)
		(layer "B.Cu")
		(net "SMB_BRICK1_SCL")
	)
	(segment
		(start 96.92005 -73.264522)
		(end 96.92005 -72.982582)
		(width 0.17272)
		(layer "B.Cu")
		(net "SMB_BRICK1_SCL")
	)
	(segment
		(start 98.298 -75.306682)
		(end 98.298 -75.024742)
		(width 0.17272)
		(layer "B.Cu")
		(net "SMB_BRICK1_SCL")
	)
	(segment
		(start 97.11944 -72.102472)
		(end 96.92005 -71.903082)
		(width 0.17272)
		(layer "B.Cu")
		(net "SMB_BRICK1_SCL")
	)
	(segment
		(start 96.92005 -74.625962)
		(end 96.92005 -74.344022)
		(width 0.17272)
		(layer "B.Cu")
		(net "SMB_BRICK1_SCL")
	)
	(segment
		(start 98.09861 -74.144632)
		(end 98.298 -73.945242)
		(width 0.17272)
		(layer "B.Cu")
		(net "SMB_BRICK1_SCL")
	)
	(segment
		(start 96.92005 -76.327)
		(end 96.92005 -75.705462)
		(width 0.17272)
		(layer "B.Cu")
		(net "SMB_BRICK1_SCL")
	)
	(segment
		(start 96.92005 -72.982582)
		(end 97.11944 -72.783192)
		(width 0.17272)
		(layer "B.Cu")
		(net "SMB_BRICK1_SCL")
	)
	(segment
		(start 96.92005 -75.705462)
		(end 97.11944 -75.506072)
		(width 0.17272)
		(layer "B.Cu")
		(net "SMB_BRICK1_SCL")
	)
	(segment
		(start 98.09861 -75.506072)
		(end 98.298 -75.306682)
		(width 0.17272)
		(layer "B.Cu")
		(net "SMB_BRICK1_SCL")
	)
	(segment
		(start 98.298 -73.663302)
		(end 98.09861 -73.463912)
		(width 0.17272)
		(layer "B.Cu")
		(net "SMB_BRICK1_SCL")
	)
	(segment
		(start 97.11944 -74.825352)
		(end 96.92005 -74.625962)
		(width 0.17272)
		(layer "B.Cu")
		(net "SMB_BRICK1_SCL")
	)
	(segment
		(start 96.92005 -69.799708)
		(end 98.849942 -67.869816)
		(width 0.17272)
		(layer "B.Cu")
		(net "SMB_BRICK1_SCL")
	)
	(segment
		(start 98.09861 -72.102472)
		(end 97.11944 -72.102472)
		(width 0.17272)
		(layer "B.Cu")
		(net "SMB_BRICK1_SCL")
	)
	(segment
		(start 98.298 -73.945242)
		(end 98.298 -73.663302)
		(width 0.17272)
		(layer "B.Cu")
		(net "SMB_BRICK1_SCL")
	)
	(segment
		(start 97.11944 -73.463912)
		(end 96.92005 -73.264522)
		(width 0.17272)
		(layer "B.Cu")
		(net "SMB_BRICK1_SCL")
	)
	(segment
		(start 96.92005 -74.344022)
		(end 97.11944 -74.144632)
		(width 0.17272)
		(layer "B.Cu")
		(net "SMB_BRICK1_SCL")
	)
	(segment
		(start 98.298 -72.301862)
		(end 98.09861 -72.102472)
		(width 0.17272)
		(layer "B.Cu")
		(net "SMB_BRICK1_SCL")
	)
	(segment
		(start 97.11944 -74.144632)
		(end 98.09861 -74.144632)
		(width 0.17272)
		(layer "B.Cu")
		(net "SMB_BRICK1_SCL")
	)
	(segment
		(start 96.92005 -71.903082)
		(end 96.92005 -69.799708)
		(width 0.17272)
		(layer "B.Cu")
		(net "SMB_BRICK1_SCL")
	)
	(via
		(at 210.185 -80.899)
		(size 0.6604)
		(drill 0.3302)
		(layers "F.Cu" "B.Cu")
		(net "PCA9555_A2")
	)
	(segment
		(start 209.560922 -78.994)
		(end 209.560922 -80.274922)
		(width 0.17272)
		(layer "B.Cu")
		(net "PCA9555_A2")
	)
	(segment
		(start 210.185 -82.14995)
		(end 209.169 -82.14995)
		(width 0.17272)
		(layer "B.Cu")
		(net "PCA9555_A2")
	)
	(segment
		(start 210.185 -80.899)
		(end 210.185 -82.14995)
		(width 0.17272)
		(layer "B.Cu")
		(net "PCA9555_A2")
	)
	(segment
		(start 209.560922 -80.274922)
		(end 210.185 -80.899)
		(width 0.17272)
		(layer "B.Cu")
		(net "PCA9555_A2")
	)
	(segment
		(start 96.849946 -116.47805)
		(end 96.849946 -121.209816)
		(width 0.17272)
		(layer "B.Cu")
		(net "BRICK_P12V1_ON_OFF_R")
	)
	(via
		(at 208.153 -80.899)
		(size 0.762)
		(drill 0.254)
		(layers "F.Cu" "B.Cu")
		(net "PCA9555_A1")
	)
	(segment
		(start 208.910936 -78.994)
		(end 208.910936 -80.141064)
		(width 0.17272)
		(layer "B.Cu")
		(net "PCA9555_A1")
	)
	(segment
		(start 208.910936 -80.141064)
		(end 208.153 -80.899)
		(width 0.17272)
		(layer "B.Cu")
		(net "PCA9555_A1")
	)
	(segment
		(start 208.153 -80.899)
		(end 208.153 -82.14995)
		(width 0.17272)
		(layer "B.Cu")
		(net "PCA9555_A1")
	)
	(segment
		(start 207.137 -82.14995)
		(end 208.153 -82.14995)
		(width 0.17272)
		(layer "B.Cu")
		(net "PCA9555_A1")
	)
	(via
		(at 176.379124 -75.057)
		(size 0.508)
		(drill 0.254)
		(layers "F.Cu" "B.Cu")
		(net "P12V_BRICK2_ALERT_N")
	)
	(via
		(at 177.81016 -65.77584)
		(size 0.508)
		(drill 0.254)
		(layers "F.Cu" "B.Cu")
		(net "P12V_BRICK2_ALERT_N")
	)
	(via
		(at 202.819 -69.2404)
		(size 0.6604)
		(drill 0.3302)
		(layers "F.Cu" "B.Cu")
		(net "P12V_BRICK2_ALERT_N")
	)
	(segment
		(start 210.76412 -76.2)
		(end 207.645 -76.2)
		(width 0.17272)
		(layer "B.Cu")
		(net "P12V_BRICK2_ALERT_N")
	)
	(segment
		(start 176.379124 -76.327)
		(end 176.379124 -75.057)
		(width 0.17272)
		(layer "B.Cu")
		(net "P12V_BRICK2_ALERT_N")
	)
	(segment
		(start 207.645 -76.2)
		(end 203.4032 -71.9582)
		(width 0.17272)
		(layer "B.Cu")
		(net "P12V_BRICK2_ALERT_N")
	)
	(segment
		(start 212.16112 -78.994)
		(end 212.16112 -77.597)
		(width 0.17272)
		(layer "B.Cu")
		(net "P12V_BRICK2_ALERT_N")
	)
	(segment
		(start 203.4032 -69.8246)
		(end 202.819 -69.2404)
		(width 0.17272)
		(layer "B.Cu")
		(net "P12V_BRICK2_ALERT_N")
	)
	(segment
		(start 201.7522 -68.1736)
		(end 202.819 -69.2404)
		(width 0.17272)
		(layer "B.Cu")
		(net "P12V_BRICK2_ALERT_N")
	)
	(segment
		(start 176.379124 -78.867)
		(end 176.379124 -77.597)
		(width 0.17272)
		(layer "B.Cu")
		(net "P12V_BRICK2_ALERT_N")
	)
	(segment
		(start 199.04964 -65.77584)
		(end 201.4474 -68.1736)
		(width 0.17272)
		(layer "B.Cu")
		(net "P12V_BRICK2_ALERT_N")
	)
	(segment
		(start 177.81016 -65.77584)
		(end 199.04964 -65.77584)
		(width 0.17272)
		(layer "B.Cu")
		(net "P12V_BRICK2_ALERT_N")
	)
	(segment
		(start 212.16112 -77.597)
		(end 210.76412 -76.2)
		(width 0.17272)
		(layer "B.Cu")
		(net "P12V_BRICK2_ALERT_N")
	)
	(segment
		(start 201.4474 -68.1736)
		(end 201.7522 -68.1736)
		(width 0.17272)
		(layer "B.Cu")
		(net "P12V_BRICK2_ALERT_N")
	)
	(segment
		(start 176.379124 -77.597)
		(end 176.379124 -76.327)
		(width 0.17272)
		(layer "B.Cu")
		(net "P12V_BRICK2_ALERT_N")
	)
	(segment
		(start 203.4032 -71.9582)
		(end 203.4032 -69.8246)
		(width 0.17272)
		(layer "B.Cu")
		(net "P12V_BRICK2_ALERT_N")
	)
	(segment
		(start 177.8 -73.636124)
		(end 176.379124 -75.057)
		(width 0.12954)
		(layer "In7.Cu")
		(net "P12V_BRICK2_ALERT_N")
	)
	(segment
		(start 177.8 -65.786)
		(end 177.8 -73.636124)
		(width 0.12954)
		(layer "In7.Cu")
		(net "P12V_BRICK2_ALERT_N")
	)
	(segment
		(start 177.81016 -65.77584)
		(end 177.8 -65.786)
		(width 0.12954)
		(layer "In7.Cu")
		(net "P12V_BRICK2_ALERT_N")
	)
	(via
		(at 210.210908 -72.009)
		(size 0.762)
		(drill 0.254)
		(layers "F.Cu" "B.Cu")
		(net "PCA9555_A0")
	)
	(segment
		(start 210.439 -68.21805)
		(end 209.804 -67.58305)
		(width 0.17272)
		(layer "B.Cu")
		(net "PCA9555_A0")
	)
	(segment
		(start 210.038696 -70.12305)
		(end 210.439 -69.722746)
		(width 0.17272)
		(layer "B.Cu")
		(net "PCA9555_A0")
	)
	(segment
		(start 210.210908 -71.374508)
		(end 209.804 -70.9676)
		(width 0.17272)
		(layer "B.Cu")
		(net "PCA9555_A0")
	)
	(segment
		(start 210.210908 -72.009)
		(end 210.210908 -71.374508)
		(width 0.17272)
		(layer "B.Cu")
		(net "PCA9555_A0")
	)
	(segment
		(start 209.804 -70.9676)
		(end 209.804 -70.12305)
		(width 0.17272)
		(layer "B.Cu")
		(net "PCA9555_A0")
	)
	(segment
		(start 209.804 -70.12305)
		(end 210.038696 -70.12305)
		(width 0.17272)
		(layer "B.Cu")
		(net "PCA9555_A0")
	)
	(segment
		(start 210.210908 -73.152)
		(end 210.210908 -72.009)
		(width 0.17272)
		(layer "B.Cu")
		(net "PCA9555_A0")
	)
	(segment
		(start 210.439 -69.722746)
		(end 210.439 -68.21805)
		(width 0.17272)
		(layer "B.Cu")
		(net "PCA9555_A0")
	)
	(via
		(at 17.71523 -88.910668)
		(size 0.6604)
		(drill 0.3302)
		(layers "F.Cu" "B.Cu")
		(net "SMB_HPDB_MISC_R_SDA")
	)
	(segment
		(start 13.959332 -88.910668)
		(end 13.02512 -89.84488)
		(width 0.17272)
		(layer "B.Cu")
		(net "SMB_HPDB_MISC_R_SDA")
	)
	(segment
		(start 9.58088 -89.84488)
		(end 8.58012 -88.84412)
		(width 0.17272)
		(layer "B.Cu")
		(net "SMB_HPDB_MISC_R_SDA")
	)
	(segment
		(start 38.58895 -89.027)
		(end 38.472618 -88.910668)
		(width 0.17272)
		(layer "B.Cu")
		(net "SMB_HPDB_MISC_R_SDA")
	)
	(segment
		(start 17.71523 -88.910668)
		(end 13.959332 -88.910668)
		(width 0.17272)
		(layer "B.Cu")
		(net "SMB_HPDB_MISC_R_SDA")
	)
	(segment
		(start 13.02512 -89.84488)
		(end 9.58088 -89.84488)
		(width 0.17272)
		(layer "B.Cu")
		(net "SMB_HPDB_MISC_R_SDA")
	)
	(segment
		(start 8.58012 -88.84412)
		(end 8.58012 -87.559896)
		(width 0.17272)
		(layer "B.Cu")
		(net "SMB_HPDB_MISC_R_SDA")
	)
	(segment
		(start 38.472618 -88.910668)
		(end 17.71523 -88.910668)
		(width 0.17272)
		(layer "B.Cu")
		(net "SMB_HPDB_MISC_R_SDA")
	)
	(segment
		(start 12.065 -87.884)
		(end 11.43 -88.519)
		(width 0.17272)
		(layer "B.Cu")
		(net "SMB_HPDB_MISC_R_SCL")
	)
	(segment
		(start 38.58895 -88.011)
		(end 15.621 -88.011)
		(width 0.17272)
		(layer "B.Cu")
		(net "SMB_HPDB_MISC_R_SCL")
	)
	(segment
		(start 15.621 -88.011)
		(end 15.494 -87.884)
		(width 0.17272)
		(layer "B.Cu")
		(net "SMB_HPDB_MISC_R_SCL")
	)
	(segment
		(start 11.43 -88.519)
		(end 10.161016 -88.519)
		(width 0.17272)
		(layer "B.Cu")
		(net "SMB_HPDB_MISC_R_SCL")
	)
	(segment
		(start 10.161016 -88.519)
		(end 9.85012 -88.829896)
		(width 0.17272)
		(layer "B.Cu")
		(net "SMB_HPDB_MISC_R_SCL")
	)
	(segment
		(start 15.494 -87.884)
		(end 12.065 -87.884)
		(width 0.17272)
		(layer "B.Cu")
		(net "SMB_HPDB_MISC_R_SCL")
	)
	(via
		(at 221.615 -76.684124)
		(size 0.6604)
		(drill 0.3302)
		(layers "F.Cu" "B.Cu")
		(net "FRU_ADDR1")
	)
	(segment
		(start 221.615 -76.684124)
		(end 221.615 -78.12405)
		(width 0.17272)
		(layer "B.Cu")
		(net "FRU_ADDR1")
	)
	(segment
		(start 221.615 -78.12405)
		(end 222.25 -78.75905)
		(width 0.17272)
		(layer "B.Cu")
		(net "FRU_ADDR1")
	)
	(segment
		(start 222.25 -78.75905)
		(end 222.25 -80.7974)
		(width 0.17272)
		(layer "B.Cu")
		(net "FRU_ADDR1")
	)
	(segment
		(start 221.615 -76.09205)
		(end 221.615 -76.684124)
		(width 0.17272)
		(layer "B.Cu")
		(net "FRU_ADDR1")
	)
	(segment
		(start 222.25 -75.45705)
		(end 221.615 -76.09205)
		(width 0.17272)
		(layer "B.Cu")
		(net "FRU_ADDR1")
	)
	(via
		(at 207.01 -80.899)
		(size 0.6604)
		(drill 0.3302)
		(layers "F.Cu" "B.Cu")
		(net "PU_U4_PIN1")
	)
	(segment
		(start 208.26095 -79.64805)
		(end 207.01 -80.899)
		(width 0.17272)
		(layer "B.Cu")
		(net "PU_U4_PIN1")
	)
	(segment
		(start 208.26095 -78.994)
		(end 208.26095 -79.64805)
		(width 0.17272)
		(layer "B.Cu")
		(net "PU_U4_PIN1")
	)
	(segment
		(start 207.01 -80.899)
		(end 206.121 -81.788)
		(width 0.17272)
		(layer "B.Cu")
		(net "PU_U4_PIN1")
	)
	(segment
		(start 206.121 -81.788)
		(end 206.121 -82.14995)
		(width 0.17272)
		(layer "B.Cu")
		(net "PU_U4_PIN1")
	)
	(via
		(at 223.52 -79.46517)
		(size 0.762)
		(drill 0.254)
		(layers "F.Cu" "B.Cu")
		(net "FRU_ADDR0")
	)
	(segment
		(start 222.885 -78.200504)
		(end 223.443546 -78.75905)
		(width 0.17272)
		(layer "B.Cu")
		(net "FRU_ADDR0")
	)
	(segment
		(start 223.52 -79.46517)
		(end 223.52 -80.7974)
		(width 0.17272)
		(layer "B.Cu")
		(net "FRU_ADDR0")
	)
	(segment
		(start 222.885 -76.09205)
		(end 222.885 -78.200504)
		(width 0.17272)
		(layer "B.Cu")
		(net "FRU_ADDR0")
	)
	(segment
		(start 223.443546 -78.75905)
		(end 223.52 -78.75905)
		(width 0.17272)
		(layer "B.Cu")
		(net "FRU_ADDR0")
	)
	(segment
		(start 223.52 -78.75905)
		(end 223.52 -79.46517)
		(width 0.17272)
		(layer "B.Cu")
		(net "FRU_ADDR0")
	)
	(segment
		(start 223.52 -75.45705)
		(end 222.885 -76.09205)
		(width 0.17272)
		(layer "B.Cu")
		(net "FRU_ADDR0")
	)
	(via
		(at 93.96095 -72.988678)
		(size 0.6604)
		(drill 0.3302)
		(layers "F.Cu" "B.Cu")
		(net "P12V_BRICK1_ALERT_N")
	)
	(segment
		(start 93.96095 -72.988678)
		(end 93.96095 -67.20205)
		(width 0.17272)
		(layer "B.Cu")
		(net "P12V_BRICK1_ALERT_N")
	)
	(segment
		(start 94.94012 -66.22288)
		(end 99.62388 -66.22288)
		(width 0.17272)
		(layer "B.Cu")
		(net "P12V_BRICK1_ALERT_N")
	)
	(segment
		(start 93.96095 -76.327)
		(end 93.96095 -77.47)
		(width 0.17272)
		(layer "B.Cu")
		(net "P12V_BRICK1_ALERT_N")
	)
	(segment
		(start 99.62388 -66.22288)
		(end 99.7966 -66.3956)
		(width 0.17272)
		(layer "B.Cu")
		(net "P12V_BRICK1_ALERT_N")
	)
	(segment
		(start 199.134222 -67.99072)
		(end 200.39457 -67.99072)
		(width 0.17272)
		(layer "B.Cu")
		(net "P12V_BRICK1_ALERT_N")
	)
	(segment
		(start 93.96095 -77.47)
		(end 93.96095 -78.613)
		(width 0.17272)
		(layer "B.Cu")
		(net "P12V_BRICK1_ALERT_N")
	)
	(segment
		(start 202.74788 -70.34403)
		(end 202.74788 -72.19188)
		(width 0.17272)
		(layer "B.Cu")
		(net "P12V_BRICK1_ALERT_N")
	)
	(segment
		(start 211.51088 -77.77988)
		(end 211.51088 -78.994)
		(width 0.17272)
		(layer "B.Cu")
		(net "P12V_BRICK1_ALERT_N")
	)
	(segment
		(start 202.74788 -72.19188)
		(end 207.391 -76.835)
		(width 0.17272)
		(layer "B.Cu")
		(net "P12V_BRICK1_ALERT_N")
	)
	(segment
		(start 99.7966 -66.3956)
		(end 197.539102 -66.3956)
		(width 0.17272)
		(layer "B.Cu")
		(net "P12V_BRICK1_ALERT_N")
	)
	(segment
		(start 93.96095 -67.20205)
		(end 94.94012 -66.22288)
		(width 0.17272)
		(layer "B.Cu")
		(net "P12V_BRICK1_ALERT_N")
	)
	(segment
		(start 93.96095 -72.988678)
		(end 93.96095 -76.327)
		(width 0.17272)
		(layer "B.Cu")
		(net "P12V_BRICK1_ALERT_N")
	)
	(segment
		(start 210.566 -76.835)
		(end 211.51088 -77.77988)
		(width 0.17272)
		(layer "B.Cu")
		(net "P12V_BRICK1_ALERT_N")
	)
	(segment
		(start 200.39457 -67.99072)
		(end 202.74788 -70.34403)
		(width 0.17272)
		(layer "B.Cu")
		(net "P12V_BRICK1_ALERT_N")
	)
	(segment
		(start 207.391 -76.835)
		(end 210.566 -76.835)
		(width 0.17272)
		(layer "B.Cu")
		(net "P12V_BRICK1_ALERT_N")
	)
	(segment
		(start 197.539102 -66.3956)
		(end 199.134222 -67.99072)
		(width 0.17272)
		(layer "B.Cu")
		(net "P12V_BRICK1_ALERT_N")
	)
	(via
		(at 210.058 -89.535)
		(size 0.762)
		(drill 0.254)
		(layers "F.Cu" "B.Cu")
		(net "PWRGD_GPU_HSC_BUF")
	)
	(segment
		(start 208.661 -90.15095)
		(end 210.058 -90.15095)
		(width 0.17272)
		(layer "B.Cu")
		(net "PWRGD_GPU_HSC_BUF")
	)
	(segment
		(start 210.058 -89.535)
		(end 210.058 -89.102946)
		(width 0.17272)
		(layer "B.Cu")
		(net "PWRGD_GPU_HSC_BUF")
	)
	(segment
		(start 210.058 -90.15095)
		(end 210.058 -89.535)
		(width 0.17272)
		(layer "B.Cu")
		(net "PWRGD_GPU_HSC_BUF")
	)
	(segment
		(start 210.058 -89.102946)
		(end 209.789014 -88.83396)
		(width 0.17272)
		(layer "B.Cu")
		(net "PWRGD_GPU_HSC_BUF")
	)
	(via
		(at 233.908346 -69.297296)
		(size 0.6604)
		(drill 0.3302)
		(layers "F.Cu" "B.Cu")
		(net "P3V3_AUX_SCALED")
	)
	(segment
		(start 218.7194 -47.23765)
		(end 218.7194 -60.808616)
		(width 0.17272)
		(layer "B.Cu")
		(net "P3V3_AUX_SCALED")
	)
	(segment
		(start 206.389986 -40.400986)
		(end 209.55 -43.561)
		(width 0.17272)
		(layer "B.Cu")
		(net "P3V3_AUX_SCALED")
	)
	(segment
		(start 232.13441 -67.52336)
		(end 233.908346 -69.297296)
		(width 0.17272)
		(layer "B.Cu")
		(net "P3V3_AUX_SCALED")
	)
	(segment
		(start 209.55 -43.561)
		(end 215.04275 -43.561)
		(width 0.17272)
		(layer "B.Cu")
		(net "P3V3_AUX_SCALED")
	)
	(segment
		(start 235.204 -70.59295)
		(end 233.908346 -69.297296)
		(width 0.17272)
		(layer "B.Cu")
		(net "P3V3_AUX_SCALED")
	)
	(segment
		(start 206.389986 -37.949632)
		(end 206.389986 -40.400986)
		(width 0.17272)
		(layer "B.Cu")
		(net "P3V3_AUX_SCALED")
	)
	(segment
		(start 225.434144 -67.52336)
		(end 232.13441 -67.52336)
		(width 0.17272)
		(layer "B.Cu")
		(net "P3V3_AUX_SCALED")
	)
	(segment
		(start 218.7194 -60.808616)
		(end 225.434144 -67.52336)
		(width 0.17272)
		(layer "B.Cu")
		(net "P3V3_AUX_SCALED")
	)
	(segment
		(start 215.04275 -43.561)
		(end 218.7194 -47.23765)
		(width 0.17272)
		(layer "B.Cu")
		(net "P3V3_AUX_SCALED")
	)
	(via
		(at 223.275652 -68.980304)
		(size 0.6604)
		(drill 0.3302)
		(layers "F.Cu" "B.Cu")
		(net "GPU_HSC_R_EN")
	)
	(segment
		(start 216.80932 -48.447452)
		(end 213.853776 -45.491908)
		(width 0.17272)
		(layer "B.Cu")
		(net "GPU_HSC_R_EN")
	)
	(segment
		(start 225.552 -70.59295)
		(end 224.536 -70.59295)
		(width 0.17272)
		(layer "B.Cu")
		(net "GPU_HSC_R_EN")
	)
	(segment
		(start 207.556354 -28.956)
		(end 208.929986 -30.329632)
		(width 0.17272)
		(layer "B.Cu")
		(net "GPU_HSC_R_EN")
	)
	(segment
		(start 213.853776 -45.491908)
		(end 208.265776 -45.491908)
		(width 0.17272)
		(layer "B.Cu")
		(net "GPU_HSC_R_EN")
	)
	(segment
		(start 205.74 -28.956)
		(end 207.556354 -28.956)
		(width 0.17272)
		(layer "B.Cu")
		(net "GPU_HSC_R_EN")
	)
	(segment
		(start 216.80932 -62.513972)
		(end 216.80932 -48.447452)
		(width 0.17272)
		(layer "B.Cu")
		(net "GPU_HSC_R_EN")
	)
	(segment
		(start 225.552 -70.59295)
		(end 224.68205 -69.723)
		(width 0.17272)
		(layer "B.Cu")
		(net "GPU_HSC_R_EN")
	)
	(segment
		(start 203.7842 -30.9118)
		(end 205.74 -28.956)
		(width 0.17272)
		(layer "B.Cu")
		(net "GPU_HSC_R_EN")
	)
	(segment
		(start 224.018348 -69.723)
		(end 223.275652 -68.980304)
		(width 0.17272)
		(layer "B.Cu")
		(net "GPU_HSC_R_EN")
	)
	(segment
		(start 203.7842 -41.010332)
		(end 203.7842 -30.9118)
		(width 0.17272)
		(layer "B.Cu")
		(net "GPU_HSC_R_EN")
	)
	(segment
		(start 224.68205 -69.723)
		(end 224.018348 -69.723)
		(width 0.17272)
		(layer "B.Cu")
		(net "GPU_HSC_R_EN")
	)
	(segment
		(start 208.265776 -45.491908)
		(end 203.7842 -41.010332)
		(width 0.17272)
		(layer "B.Cu")
		(net "GPU_HSC_R_EN")
	)
	(segment
		(start 223.275652 -68.980304)
		(end 216.80932 -62.513972)
		(width 0.17272)
		(layer "B.Cu")
		(net "GPU_HSC_R_EN")
	)
	(via
		(at 229.600506 -69.307456)
		(size 0.6604)
		(drill 0.3302)
		(layers "F.Cu" "B.Cu")
		(net "FAN_PWR_R_EN")
	)
	(segment
		(start 210.431126 -31.369)
		(end 205.867 -31.369)
		(width 0.17272)
		(layer "B.Cu")
		(net "FAN_PWR_R_EN")
	)
	(segment
		(start 230.886 -70.59295)
		(end 229.87 -70.59295)
		(width 0.17272)
		(layer "B.Cu")
		(net "FAN_PWR_R_EN")
	)
	(segment
		(start 208.747868 -44.536868)
		(end 214.3506 -44.536868)
		(width 0.17272)
		(layer "B.Cu")
		(net "FAN_PWR_R_EN")
	)
	(segment
		(start 204.7748 -40.5638)
		(end 208.747868 -44.536868)
		(width 0.17272)
		(layer "B.Cu")
		(net "FAN_PWR_R_EN")
	)
	(segment
		(start 228.920294 -68.627244)
		(end 229.600506 -69.307456)
		(width 0.17272)
		(layer "B.Cu")
		(net "FAN_PWR_R_EN")
	)
	(segment
		(start 211.469986 -30.329632)
		(end 211.469986 -30.33014)
		(width 0.17272)
		(layer "B.Cu")
		(net "FAN_PWR_R_EN")
	)
	(segment
		(start 224.677732 -68.627244)
		(end 228.920294 -68.627244)
		(width 0.17272)
		(layer "B.Cu")
		(net "FAN_PWR_R_EN")
	)
	(segment
		(start 214.3506 -44.536868)
		(end 217.76436 -47.950628)
		(width 0.17272)
		(layer "B.Cu")
		(net "FAN_PWR_R_EN")
	)
	(segment
		(start 211.469986 -30.33014)
		(end 210.431126 -31.369)
		(width 0.17272)
		(layer "B.Cu")
		(net "FAN_PWR_R_EN")
	)
	(segment
		(start 205.867 -31.369)
		(end 204.7748 -32.4612)
		(width 0.17272)
		(layer "B.Cu")
		(net "FAN_PWR_R_EN")
	)
	(segment
		(start 204.7748 -32.4612)
		(end 204.7748 -40.5638)
		(width 0.17272)
		(layer "B.Cu")
		(net "FAN_PWR_R_EN")
	)
	(segment
		(start 229.600506 -69.307456)
		(end 230.886 -70.59295)
		(width 0.17272)
		(layer "B.Cu")
		(net "FAN_PWR_R_EN")
	)
	(segment
		(start 217.76436 -61.713872)
		(end 224.677732 -68.627244)
		(width 0.17272)
		(layer "B.Cu")
		(net "FAN_PWR_R_EN")
	)
	(segment
		(start 217.76436 -47.950628)
		(end 217.76436 -61.713872)
		(width 0.17272)
		(layer "B.Cu")
		(net "FAN_PWR_R_EN")
	)
	(segment
		(start 213.36 -85.725)
		(end 213.36 -85.344)
		(width 0.17272)
		(layer "F.Cu")
		(net "LED_D1_R5")
	)
	(segment
		(start 213.36 -85.344)
		(end 211.92998 -83.91398)
		(width 0.17272)
		(layer "F.Cu")
		(net "LED_D1_R5")
	)
	(segment
		(start 211.530946 -85.725)
		(end 213.36 -85.725)
		(width 0.17272)
		(layer "F.Cu")
		(net "LED_D1_R5")
	)
	(segment
		(start 211.92998 -83.91398)
		(end 211.92998 -83.566)
		(width 0.17272)
		(layer "F.Cu")
		(net "LED_D1_R5")
	)
	(via
		(at 213.36 -85.725)
		(size 0.762)
		(drill 0.381)
		(layers "F.Cu" "B.Cu")
		(net "LED_D1_R5")
	)
	(segment
		(start 201.257916 -67.356736)
		(end 201.257916 -67.385946)
		(width 0.17272)
		(layer "F.Cu")
		(net "LED_D2_R3")
	)
	(segment
		(start 201.9046 -67.558666)
		(end 202.654916 -67.558666)
		(width 0.17272)
		(layer "F.Cu")
		(net "LED_D2_R3")
	)
	(segment
		(start 201.430636 -67.558666)
		(end 201.9046 -67.558666)
		(width 0.17272)
		(layer "F.Cu")
		(net "LED_D2_R3")
	)
	(segment
		(start 201.257916 -67.385946)
		(end 201.430636 -67.558666)
		(width 0.17272)
		(layer "F.Cu")
		(net "LED_D2_R3")
	)
	(via
		(at 201.9046 -67.558666)
		(size 0.508)
		(drill 0.254)
		(layers "F.Cu" "B.Cu")
		(net "LED_D2_R3")
	)
	(via
		(at 15.3924 -85.217)
		(size 0.6604)
		(drill 0.3302)
		(layers "F.Cu" "B.Cu")
		(net "SMB_P52V_HPDB_R_SCL")
	)
	(segment
		(start 11.43 -85.979)
		(end 10.161016 -85.979)
		(width 0.17272)
		(layer "B.Cu")
		(net "SMB_P52V_HPDB_R_SCL")
	)
	(segment
		(start 38.58895 -85.217)
		(end 36.81095 -86.995)
		(width 0.17272)
		(layer "B.Cu")
		(net "SMB_P52V_HPDB_R_SCL")
	)
	(segment
		(start 17.1704 -86.995)
		(end 15.3924 -85.217)
		(width 0.17272)
		(layer "B.Cu")
		(net "SMB_P52V_HPDB_R_SCL")
	)
	(segment
		(start 10.161016 -85.979)
		(end 9.85012 -86.289896)
		(width 0.17272)
		(layer "B.Cu")
		(net "SMB_P52V_HPDB_R_SCL")
	)
	(segment
		(start 15.3924 -85.217)
		(end 12.192 -85.217)
		(width 0.17272)
		(layer "B.Cu")
		(net "SMB_P52V_HPDB_R_SCL")
	)
	(segment
		(start 36.81095 -86.995)
		(end 17.1704 -86.995)
		(width 0.17272)
		(layer "B.Cu")
		(net "SMB_P52V_HPDB_R_SCL")
	)
	(segment
		(start 12.192 -85.217)
		(end 11.43 -85.979)
		(width 0.17272)
		(layer "B.Cu")
		(net "SMB_P52V_HPDB_R_SCL")
	)
	(segment
		(start 10.697464 -84.171536)
		(end 11.527536 -84.171536)
		(width 0.17272)
		(layer "B.Cu")
		(net "SMB_P52V_HPDB_R_SDA")
	)
	(segment
		(start 36.068 -86.41588)
		(end 38.40988 -84.074)
		(width 0.17272)
		(layer "B.Cu")
		(net "SMB_P52V_HPDB_R_SDA")
	)
	(segment
		(start 8.58012 -85.019896)
		(end 8.891016 -84.709)
		(width 0.17272)
		(layer "B.Cu")
		(net "SMB_P52V_HPDB_R_SDA")
	)
	(segment
		(start 38.40988 -84.074)
		(end 38.58895 -84.074)
		(width 0.17272)
		(layer "B.Cu")
		(net "SMB_P52V_HPDB_R_SDA")
	)
	(segment
		(start 16.31188 -84.63788)
		(end 18.08988 -86.41588)
		(width 0.17272)
		(layer "B.Cu")
		(net "SMB_P52V_HPDB_R_SDA")
	)
	(segment
		(start 11.527536 -84.171536)
		(end 11.99388 -84.63788)
		(width 0.17272)
		(layer "B.Cu")
		(net "SMB_P52V_HPDB_R_SDA")
	)
	(segment
		(start 10.16 -84.709)
		(end 10.697464 -84.171536)
		(width 0.17272)
		(layer "B.Cu")
		(net "SMB_P52V_HPDB_R_SDA")
	)
	(segment
		(start 8.891016 -84.709)
		(end 10.16 -84.709)
		(width 0.17272)
		(layer "B.Cu")
		(net "SMB_P52V_HPDB_R_SDA")
	)
	(segment
		(start 18.08988 -86.41588)
		(end 36.068 -86.41588)
		(width 0.17272)
		(layer "B.Cu")
		(net "SMB_P52V_HPDB_R_SDA")
	)
	(segment
		(start 11.99388 -84.63788)
		(end 16.31188 -84.63788)
		(width 0.17272)
		(layer "B.Cu")
		(net "SMB_P52V_HPDB_R_SDA")
	)
	(segment
		(start 263.54278 -37.30498)
		(end 263.54278 -37.942774)
		(width 0.17272)
		(layer "F.Cu")
		(net "P52V_HS1_OV")
	)
	(segment
		(start 284.794452 -46.17974)
		(end 283.083 -47.891192)
		(width 0.17272)
		(layer "F.Cu")
		(net "P52V_HS1_OV")
	)
	(segment
		(start 281.94 -48.87595)
		(end 282.956 -48.87595)
		(width 0.17272)
		(layer "F.Cu")
		(net "P52V_HS1_OV")
	)
	(segment
		(start 284.794452 -45.790866)
		(end 284.794452 -46.17974)
		(width 0.17272)
		(layer "F.Cu")
		(net "P52V_HS1_OV")
	)
	(segment
		(start 263.398 -37.1602)
		(end 263.54278 -37.30498)
		(width 0.17272)
		(layer "F.Cu")
		(net "P52V_HS1_OV")
	)
	(segment
		(start 283.083 -47.891192)
		(end 283.083 -47.9298)
		(width 0.17272)
		(layer "F.Cu")
		(net "P52V_HS1_OV")
	)
	(segment
		(start 283.083 -47.9298)
		(end 282.956 -48.0568)
		(width 0.17272)
		(layer "F.Cu")
		(net "P52V_HS1_OV")
	)
	(segment
		(start 282.956 -48.0568)
		(end 282.956 -48.87595)
		(width 0.17272)
		(layer "F.Cu")
		(net "P52V_HS1_OV")
	)
	(via
		(at 283.083 -47.9298)
		(size 0.508)
		(drill 0.254)
		(layers "F.Cu" "B.Cu")
		(net "P52V_HS1_OV")
	)
	(via
		(at 263.398 -37.1602)
		(size 0.508)
		(drill 0.254)
		(layers "F.Cu" "B.Cu")
		(net "P52V_HS1_OV")
	)
	(segment
		(start 291.592 -52.39004)
		(end 291.592 -50.419)
		(width 0.17272)
		(layer "B.Cu")
		(net "P52V_HS1_OV")
	)
	(segment
		(start 263.398 -37.1602)
		(end 263.398 -38.3032)
		(width 0.17272)
		(layer "B.Cu")
		(net "P52V_HS1_OV")
	)
	(segment
		(start 263.779 -42.631614)
		(end 266.319 -45.171614)
		(width 0.17272)
		(layer "B.Cu")
		(net "P52V_HS1_OV")
	)
	(segment
		(start 284.48 -47.498)
		(end 283.5148 -47.498)
		(width 0.17272)
		(layer "B.Cu")
		(net "P52V_HS1_OV")
	)
	(segment
		(start 282.558744 -48.454056)
		(end 283.083 -47.9298)
		(width 0.17272)
		(layer "B.Cu")
		(net "P52V_HS1_OV")
	)
	(segment
		(start 283.5148 -47.498)
		(end 283.083 -47.9298)
		(width 0.17272)
		(layer "B.Cu")
		(net "P52V_HS1_OV")
	)
	(segment
		(start 274.872958 -48.454056)
		(end 282.558744 -48.454056)
		(width 0.17272)
		(layer "B.Cu")
		(net "P52V_HS1_OV")
	)
	(segment
		(start 289.604958 -48.431958)
		(end 285.413958 -48.431958)
		(width 0.17272)
		(layer "B.Cu")
		(net "P52V_HS1_OV")
	)
	(segment
		(start 266.319 -48.640746)
		(end 268.356334 -50.67808)
		(width 0.17272)
		(layer "B.Cu")
		(net "P52V_HS1_OV")
	)
	(segment
		(start 266.319 -45.171614)
		(end 266.319 -48.640746)
		(width 0.17272)
		(layer "B.Cu")
		(net "P52V_HS1_OV")
	)
	(segment
		(start 268.356334 -50.67808)
		(end 272.648934 -50.67808)
		(width 0.17272)
		(layer "B.Cu")
		(net "P52V_HS1_OV")
	)
	(segment
		(start 263.398 -38.3032)
		(end 263.779 -38.6842)
		(width 0.17272)
		(layer "B.Cu")
		(net "P52V_HS1_OV")
	)
	(segment
		(start 272.648934 -50.67808)
		(end 274.872958 -48.454056)
		(width 0.17272)
		(layer "B.Cu")
		(net "P52V_HS1_OV")
	)
	(segment
		(start 285.413958 -48.431958)
		(end 284.48 -47.498)
		(width 0.17272)
		(layer "B.Cu")
		(net "P52V_HS1_OV")
	)
	(segment
		(start 291.592 -50.419)
		(end 289.604958 -48.431958)
		(width 0.17272)
		(layer "B.Cu")
		(net "P52V_HS1_OV")
	)
	(segment
		(start 263.779 -38.6842)
		(end 263.779 -42.631614)
		(width 0.17272)
		(layer "B.Cu")
		(net "P52V_HS1_OV")
	)
	(via
		(at 278.384 -41.91)
		(size 0.6604)
		(drill 0.3302)
		(layers "F.Cu" "B.Cu")
		(net "P52V_HS1_EFAULT")
	)
	(segment
		(start 279.50795 -41.91)
		(end 278.384 -41.91)
		(width 0.17272)
		(layer "B.Cu")
		(net "P52V_HS1_EFAULT")
	)
	(segment
		(start 277.13305 -41.656)
		(end 277.13305 -42.545)
		(width 0.17272)
		(layer "B.Cu")
		(net "P52V_HS1_EFAULT")
	)
	(segment
		(start 277.749 -42.545)
		(end 277.13305 -42.545)
		(width 0.17272)
		(layer "B.Cu")
		(net "P52V_HS1_EFAULT")
	)
	(segment
		(start 278.384 -41.91)
		(end 277.749 -42.545)
		(width 0.17272)
		(layer "B.Cu")
		(net "P52V_HS1_EFAULT")
	)
	(via
		(at 278.384 -43.307)
		(size 0.6604)
		(drill 0.3302)
		(layers "F.Cu" "B.Cu")
		(net "P52V_HS1_ESTART")
	)
	(segment
		(start 278.892 -42.799)
		(end 279.50795 -42.799)
		(width 0.17272)
		(layer "B.Cu")
		(net "P52V_HS1_ESTART")
	)
	(segment
		(start 277.13305 -43.434)
		(end 277.13305 -44.323)
		(width 0.17272)
		(layer "B.Cu")
		(net "P52V_HS1_ESTART")
	)
	(segment
		(start 278.384 -43.307)
		(end 278.892 -42.799)
		(width 0.17272)
		(layer "B.Cu")
		(net "P52V_HS1_ESTART")
	)
	(segment
		(start 278.257 -43.434)
		(end 278.384 -43.307)
		(width 0.17272)
		(layer "B.Cu")
		(net "P52V_HS1_ESTART")
	)
	(segment
		(start 277.13305 -43.434)
		(end 278.257 -43.434)
		(width 0.17272)
		(layer "B.Cu")
		(net "P52V_HS1_ESTART")
	)
	(segment
		(start 294.027098 -37.061902)
		(end 292.50259 -37.061902)
		(width 0.17272)
		(layer "F.Cu")
		(net "P52V_HS1_DV_DT")
	)
	(segment
		(start 294.3225 -36.7665)
		(end 294.027098 -37.061902)
		(width 0.17272)
		(layer "F.Cu")
		(net "P52V_HS1_DV_DT")
	)
	(segment
		(start 292.902132 -35.346132)
		(end 294.3225 -36.7665)
		(width 0.17272)
		(layer "F.Cu")
		(net "P52V_HS1_DV_DT")
	)
	(segment
		(start 292.757098 -35.346132)
		(end 292.902132 -35.346132)
		(width 0.17272)
		(layer "F.Cu")
		(net "P52V_HS1_DV_DT")
	)
	(via
		(at 294.3225 -36.7665)
		(size 0.762)
		(drill 0.381)
		(layers "F.Cu" "B.Cu")
		(net "P52V_HS1_DV_DT")
	)
	(via
		(at 293.07663 -40.918892)
		(size 0.762)
		(drill 0.381)
		(layers "F.Cu" "B.Cu")
		(net "P52V_HS1_VCP")
	)
	(segment
		(start 286.795972 -45.790866)
		(end 286.795972 -46.254162)
		(width 0.254)
		(layer "F.Cu")
		(net "P52V_HS1_TEMPN")
	)
	(segment
		(start 286.795972 -46.254162)
		(end 286.74568 -46.304454)
		(width 0.254)
		(layer "F.Cu")
		(net "P52V_HS1_TEMPN")
	)
	(segment
		(start 286.74568 -47.034196)
		(end 286.54756 -47.232316)
		(width 0.254)
		(layer "F.Cu")
		(net "P52V_HS1_TEMPN")
	)
	(segment
		(start 286.783272 -48.960024)
		(end 286.783272 -49.657)
		(width 0.254)
		(layer "F.Cu")
		(net "P52V_HS1_TEMPN")
	)
	(segment
		(start 283.18206 -56.957214)
		(end 283.79166 -56.957214)
		(width 0.254)
		(layer "F.Cu")
		(net "P52V_HS1_TEMPN")
	)
	(segment
		(start 286.54756 -47.232316)
		(end 286.54756 -48.724312)
		(width 0.254)
		(layer "F.Cu")
		(net "P52V_HS1_TEMPN")
	)
	(segment
		(start 286.54756 -48.724312)
		(end 286.783272 -48.960024)
		(width 0.254)
		(layer "F.Cu")
		(net "P52V_HS1_TEMPN")
	)
	(segment
		(start 286.74568 -46.304454)
		(end 286.74568 -47.034196)
		(width 0.254)
		(layer "F.Cu")
		(net "P52V_HS1_TEMPN")
	)
	(via
		(at 283.79166 -56.957214)
		(size 0.508)
		(drill 0.254)
		(layers "F.Cu" "B.Cu")
		(net "P52V_HS1_TEMPN")
	)
	(via
		(at 286.783272 -49.657)
		(size 0.508)
		(drill 0.254)
		(layers "F.Cu" "B.Cu")
		(net "P52V_HS1_TEMPN")
	)
	(segment
		(start 283.52877 -57.716166)
		(end 283.785564 -57.465468)
		(width 0.254)
		(layer "In2.Cu")
		(net "P52V_HS1_TEMPN")
	)
	(segment
		(start 286.783272 -49.657)
		(end 286.58312 -49.857152)
		(width 0.254)
		(layer "In2.Cu")
		(net "P52V_HS1_TEMPN")
	)
	(segment
		(start 282.7528 -56.0578)
		(end 282.7528 -57.458102)
		(width 0.254)
		(layer "In2.Cu")
		(net "P52V_HS1_TEMPN")
	)
	(segment
		(start 283.169868 -57.712102)
		(end 283.52877 -57.716166)
		(width 0.254)
		(layer "In2.Cu")
		(net "P52V_HS1_TEMPN")
	)
	(segment
		(start 286.58312 -49.857152)
		(end 286.58312 -52.22748)
		(width 0.254)
		(layer "In2.Cu")
		(net "P52V_HS1_TEMPN")
	)
	(segment
		(start 286.58312 -52.22748)
		(end 282.7528 -56.0578)
		(width 0.254)
		(layer "In2.Cu")
		(net "P52V_HS1_TEMPN")
	)
	(segment
		(start 282.7528 -57.458102)
		(end 283.0068 -57.712102)
		(width 0.254)
		(layer "In2.Cu")
		(net "P52V_HS1_TEMPN")
	)
	(segment
		(start 283.0068 -57.712102)
		(end 283.169868 -57.712102)
		(width 0.254)
		(layer "In2.Cu")
		(net "P52V_HS1_TEMPN")
	)
	(segment
		(start 283.785564 -57.465468)
		(end 283.79166 -56.957214)
		(width 0.254)
		(layer "In2.Cu")
		(net "P52V_HS1_TEMPN")
	)
	(segment
		(start 283.176726 -39.590726)
		(end 283.595572 -39.590726)
		(width 0.17272)
		(layer "F.Cu")
		(net "P52V_HS1_MCB")
	)
	(segment
		(start 280.543 -36.08705)
		(end 280.564336 -36.08705)
		(width 0.17272)
		(layer "F.Cu")
		(net "P52V_HS1_MCB")
	)
	(segment
		(start 282.575 -38.989)
		(end 283.176726 -39.590726)
		(width 0.17272)
		(layer "F.Cu")
		(net "P52V_HS1_MCB")
	)
	(segment
		(start 280.564336 -36.08705)
		(end 280.943812 -36.466526)
		(width 0.17272)
		(layer "F.Cu")
		(net "P52V_HS1_MCB")
	)
	(segment
		(start 280.943812 -36.466526)
		(end 280.943812 -36.722812)
		(width 0.17272)
		(layer "F.Cu")
		(net "P52V_HS1_MCB")
	)
	(segment
		(start 280.943812 -36.722812)
		(end 282.575 -38.354)
		(width 0.17272)
		(layer "F.Cu")
		(net "P52V_HS1_MCB")
	)
	(segment
		(start 282.575 -38.354)
		(end 282.575 -38.989)
		(width 0.17272)
		(layer "F.Cu")
		(net "P52V_HS1_MCB")
	)
	(via
		(at 282.575 -38.354)
		(size 0.762)
		(drill 0.381)
		(layers "F.Cu" "B.Cu")
		(net "P52V_HS1_MCB")
	)
	(via
		(at 280.71318 -46.38802)
		(size 0.762)
		(drill 0.381)
		(layers "F.Cu" "B.Cu")
		(net "P52V_HS1_ISET")
	)
	(via
		(at 278.765 -51.7398)
		(size 0.508)
		(drill 0.254)
		(layers "F.Cu" "B.Cu")
		(net "P52V_HS1_ISET")
	)
	(via
		(at 279.4 -51.7398)
		(size 0.508)
		(drill 0.254)
		(layers "F.Cu" "B.Cu")
		(net "P52V_HS1_ISET")
	)
	(segment
		(start 279.781254 -44.704)
		(end 281.559 -44.704)
		(width 0.17272)
		(layer "F.Cu")
		(net "P52V_HS1_ISTART")
	)
	(segment
		(start 279.50795 -44.069)
		(end 279.50795 -44.430696)
		(width 0.17272)
		(layer "F.Cu")
		(net "P52V_HS1_ISTART")
	)
	(segment
		(start 282.814268 -44.591986)
		(end 283.595572 -44.591986)
		(width 0.17272)
		(layer "F.Cu")
		(net "P52V_HS1_ISTART")
	)
	(segment
		(start 282.702254 -44.704)
		(end 282.814268 -44.591986)
		(width 0.17272)
		(layer "F.Cu")
		(net "P52V_HS1_ISTART")
	)
	(segment
		(start 279.50795 -44.430696)
		(end 279.781254 -44.704)
		(width 0.17272)
		(layer "F.Cu")
		(net "P52V_HS1_ISTART")
	)
	(segment
		(start 278.40305 -44.069)
		(end 279.50795 -44.069)
		(width 0.17272)
		(layer "F.Cu")
		(net "P52V_HS1_ISTART")
	)
	(segment
		(start 281.559 -44.704)
		(end 282.702254 -44.704)
		(width 0.17272)
		(layer "F.Cu")
		(net "P52V_HS1_ISTART")
	)
	(via
		(at 281.559 -44.704)
		(size 0.762)
		(drill 0.381)
		(layers "F.Cu" "B.Cu")
		(net "P52V_HS1_ISTART")
	)
	(segment
		(start 287.782 -47.961296)
		(end 287.782 -48.87595)
		(width 0.17272)
		(layer "F.Cu")
		(net "P52V_HS1_VREG")
	)
	(segment
		(start 287.296352 -47.475648)
		(end 287.782 -47.961296)
		(width 0.17272)
		(layer "F.Cu")
		(net "P52V_HS1_VREG")
	)
	(segment
		(start 287.296352 -45.790866)
		(end 287.296352 -47.475648)
		(width 0.17272)
		(layer "F.Cu")
		(net "P52V_HS1_VREG")
	)
	(via
		(at 287.296352 -47.475648)
		(size 0.762)
		(drill 0.381)
		(layers "F.Cu" "B.Cu")
		(net "P52V_HS1_VREG")
	)
	(via
		(at 271.190466 -80.757268)
		(size 0.508)
		(drill 0.254)
		(layers "F.Cu" "B.Cu")
		(net "P52V_HS1_GATE5")
	)
	(segment
		(start 275.95195 -25.54605)
		(end 275.95195 -26.162)
		(width 0.17272)
		(layer "F.Cu")
		(net "P52V_HS1_EN")
	)
	(segment
		(start 276.098 -25.4)
		(end 275.95195 -25.54605)
		(width 0.17272)
		(layer "F.Cu")
		(net "P52V_HS1_EN")
	)
	(via
		(at 276.098 -25.4)
		(size 0.508)
		(drill 0.254)
		(layers "F.Cu" "B.Cu")
		(net "P52V_HS1_EN")
	)
	(via
		(at 270.129 -28.321)
		(size 0.6604)
		(drill 0.3302)
		(layers "F.Cu" "B.Cu")
		(net "P52V_HS1_EN")
	)
	(segment
		(start 273.685 -25.543002)
		(end 269.731998 -25.543002)
		(width 0.17272)
		(layer "B.Cu")
		(net "P52V_HS1_EN")
	)
	(segment
		(start 269.731998 -25.543002)
		(end 269.715996 -25.527)
		(width 0.17272)
		(layer "B.Cu")
		(net "P52V_HS1_EN")
	)
	(segment
		(start 270.129 -28.321)
		(end 270.129 -27.6606)
		(width 0.17272)
		(layer "B.Cu")
		(net "P52V_HS1_EN")
	)
	(segment
		(start 275.954998 -25.543002)
		(end 273.685 -25.543002)
		(width 0.17272)
		(layer "B.Cu")
		(net "P52V_HS1_EN")
	)
	(segment
		(start 276.098 -25.4)
		(end 275.954998 -25.543002)
		(width 0.17272)
		(layer "B.Cu")
		(net "P52V_HS1_EN")
	)
	(segment
		(start 268.53896 -28.321)
		(end 270.129 -28.321)
		(width 0.17272)
		(layer "B.Cu")
		(net "P52V_HS1_EN")
	)
	(segment
		(start 269.715996 -27.247596)
		(end 269.715996 -25.527)
		(width 0.17272)
		(layer "B.Cu")
		(net "P52V_HS1_EN")
	)
	(segment
		(start 270.129 -27.6606)
		(end 269.715996 -27.247596)
		(width 0.17272)
		(layer "B.Cu")
		(net "P52V_HS1_EN")
	)
	(segment
		(start 294.894 -22.9616)
		(end 291.0586 -26.797)
		(width 0.12954)
		(layer "In7.Cu")
		(net "P52V_HS1_EN")
	)
	(segment
		(start 277.749 -26.797)
		(end 276.352 -25.4)
		(width 0.12954)
		(layer "In7.Cu")
		(net "P52V_HS1_EN")
	)
	(segment
		(start 276.352 -25.4)
		(end 276.098 -25.4)
		(width 0.12954)
		(layer "In7.Cu")
		(net "P52V_HS1_EN")
	)
	(segment
		(start 291.0586 -26.797)
		(end 277.749 -26.797)
		(width 0.12954)
		(layer "In7.Cu")
		(net "P52V_HS1_EN")
	)
	(via
		(at 289.003232 -47.647352)
		(size 0.762)
		(drill 0.381)
		(layers "F.Cu" "B.Cu")
		(net "P52V_HS1_VCC")
	)
	(via
		(at 288.6202 -43.7642)
		(size 0.508)
		(drill 0.254)
		(layers "F.Cu" "B.Cu")
		(net "P52V_HS1_VCC")
	)
	(via
		(at 288.6202 -40.9194)
		(size 0.508)
		(drill 0.254)
		(layers "F.Cu" "B.Cu")
		(net "P52V_HS1_VCC")
	)
	(via
		(at 289.56 -40.9194)
		(size 0.508)
		(drill 0.254)
		(layers "F.Cu" "B.Cu")
		(net "P52V_HS1_VCC")
	)
	(via
		(at 289.56 -43.7642)
		(size 0.508)
		(drill 0.254)
		(layers "F.Cu" "B.Cu")
		(net "P52V_HS1_VCC")
	)
	(segment
		(start 265.978386 -35.937698)
		(end 265.978386 -36.620704)
		(width 0.17272)
		(layer "F.Cu")
		(net "P52V_HS1_ADR0")
	)
	(segment
		(start 265.978386 -36.620704)
		(end 265.542776 -37.672518)
		(width 0.17272)
		(layer "F.Cu")
		(net "P52V_HS1_ADR0")
	)
	(segment
		(start 282.734766 -42.092626)
		(end 283.595572 -42.092626)
		(width 0.17272)
		(layer "F.Cu")
		(net "P52V_HS1_ADR0")
	)
	(segment
		(start 265.542776 -37.672518)
		(end 265.542776 -37.942774)
		(width 0.17272)
		(layer "F.Cu")
		(net "P52V_HS1_ADR0")
	)
	(via
		(at 282.734766 -42.092626)
		(size 0.508)
		(drill 0.254)
		(layers "F.Cu" "B.Cu")
		(net "P52V_HS1_ADR0")
	)
	(via
		(at 265.978386 -35.937698)
		(size 0.508)
		(drill 0.254)
		(layers "F.Cu" "B.Cu")
		(net "P52V_HS1_ADR0")
	)
	(segment
		(start 266.59205 -35.324034)
		(end 265.978386 -35.937698)
		(width 0.17272)
		(layer "B.Cu")
		(net "P52V_HS1_ADR0")
	)
	(segment
		(start 267.156184 -41.426384)
		(end 267.156184 -37.389816)
		(width 0.17272)
		(layer "B.Cu")
		(net "P52V_HS1_ADR0")
	)
	(segment
		(start 276.62505 -46.08195)
		(end 277.749 -44.958)
		(width 0.17272)
		(layer "B.Cu")
		(net "P52V_HS1_ADR0")
	)
	(segment
		(start 280.034746 -44.958)
		(end 280.30805 -45.231304)
		(width 0.17272)
		(layer "B.Cu")
		(net "P52V_HS1_ADR0")
	)
	(segment
		(start 267.36548 -35.256216)
		(end 267.034264 -34.925)
		(width 0.17272)
		(layer "B.Cu")
		(net "P52V_HS1_ADR0")
	)
	(segment
		(start 266.59205 -34.925)
		(end 266.59205 -35.324034)
		(width 0.17272)
		(layer "B.Cu")
		(net "P52V_HS1_ADR0")
	)
	(segment
		(start 280.30805 -45.231304)
		(end 280.30805 -45.72)
		(width 0.17272)
		(layer "B.Cu")
		(net "P52V_HS1_ADR0")
	)
	(segment
		(start 267.034264 -34.925)
		(end 266.59205 -34.925)
		(width 0.17272)
		(layer "B.Cu")
		(net "P52V_HS1_ADR0")
	)
	(segment
		(start 280.30805 -45.72)
		(end 281.559 -45.72)
		(width 0.17272)
		(layer "B.Cu")
		(net "P52V_HS1_ADR0")
	)
	(segment
		(start 283.464 -42.82186)
		(end 282.734766 -42.092626)
		(width 0.17272)
		(layer "B.Cu")
		(net "P52V_HS1_ADR0")
	)
	(segment
		(start 283.464 -43.815)
		(end 283.464 -42.82186)
		(width 0.17272)
		(layer "B.Cu")
		(net "P52V_HS1_ADR0")
	)
	(segment
		(start 267.156184 -37.389816)
		(end 267.36548 -37.18052)
		(width 0.17272)
		(layer "B.Cu")
		(net "P52V_HS1_ADR0")
	)
	(segment
		(start 267.36548 -37.18052)
		(end 267.36548 -35.256216)
		(width 0.17272)
		(layer "B.Cu")
		(net "P52V_HS1_ADR0")
	)
	(segment
		(start 274.955 -46.08195)
		(end 276.62505 -46.08195)
		(width 0.17272)
		(layer "B.Cu")
		(net "P52V_HS1_ADR0")
	)
	(segment
		(start 277.749 -44.958)
		(end 280.034746 -44.958)
		(width 0.17272)
		(layer "B.Cu")
		(net "P52V_HS1_ADR0")
	)
	(segment
		(start 273.558 -46.08195)
		(end 274.955 -46.08195)
		(width 0.17272)
		(layer "B.Cu")
		(net "P52V_HS1_ADR0")
	)
	(segment
		(start 271.81175 -46.08195)
		(end 267.156184 -41.426384)
		(width 0.17272)
		(layer "B.Cu")
		(net "P52V_HS1_ADR0")
	)
	(segment
		(start 273.558 -46.08195)
		(end 271.81175 -46.08195)
		(width 0.17272)
		(layer "B.Cu")
		(net "P52V_HS1_ADR0")
	)
	(segment
		(start 281.559 -45.72)
		(end 283.464 -43.815)
		(width 0.17272)
		(layer "B.Cu")
		(net "P52V_HS1_ADR0")
	)
	(segment
		(start 201.257916 -66.556636)
		(end 201.257916 -66.190876)
		(width 0.17272)
		(layer "F.Cu")
		(net "LED_D2_R2")
	)
	(segment
		(start 201.257916 -66.190876)
		(end 201.008488 -65.941448)
		(width 0.17272)
		(layer "F.Cu")
		(net "LED_D2_R2")
	)
	(segment
		(start 201.008488 -65.941448)
		(end 200.66 -65.941448)
		(width 0.17272)
		(layer "F.Cu")
		(net "LED_D2_R2")
	)
	(segment
		(start 200.66 -65.941448)
		(end 200.177908 -65.941448)
		(width 0.17272)
		(layer "F.Cu")
		(net "LED_D2_R2")
	)
	(segment
		(start 199.987916 -66.13144)
		(end 199.987916 -66.556636)
		(width 0.17272)
		(layer "F.Cu")
		(net "LED_D2_R2")
	)
	(segment
		(start 200.177908 -65.941448)
		(end 199.987916 -66.13144)
		(width 0.17272)
		(layer "F.Cu")
		(net "LED_D2_R2")
	)
	(via
		(at 200.66 -65.941448)
		(size 0.508)
		(drill 0.254)
		(layers "F.Cu" "B.Cu")
		(net "LED_D2_R2")
	)
	(segment
		(start 198.717916 -67.356736)
		(end 199.35317 -67.356736)
		(width 0.17272)
		(layer "F.Cu")
		(net "LED_D2_R1")
	)
	(segment
		(start 199.35317 -67.356736)
		(end 199.987916 -67.356736)
		(width 0.17272)
		(layer "F.Cu")
		(net "LED_D2_R1")
	)
	(via
		(at 199.35317 -67.356736)
		(size 0.508)
		(drill 0.254)
		(layers "F.Cu" "B.Cu")
		(net "LED_D2_R1")
	)
	(segment
		(start 282.498546 -43.18)
		(end 282.5877 -43.090846)
		(width 0.17272)
		(layer "F.Cu")
		(net "P52V_HS1_EFAULT_R")
	)
	(segment
		(start 282.5877 -43.090846)
		(end 283.595572 -43.090846)
		(width 0.17272)
		(layer "F.Cu")
		(net "P52V_HS1_EFAULT_R")
	)
	(segment
		(start 282.1432 -43.18)
		(end 282.498546 -43.18)
		(width 0.17272)
		(layer "F.Cu")
		(net "P52V_HS1_EFAULT_R")
	)
	(via
		(at 282.1432 -43.18)
		(size 0.762)
		(drill 0.254)
		(layers "F.Cu" "B.Cu")
		(net "P52V_HS1_EFAULT_R")
	)
	(segment
		(start 281.686 -43.053)
		(end 281.813 -43.18)
		(width 0.17272)
		(layer "B.Cu")
		(net "P52V_HS1_EFAULT_R")
	)
	(segment
		(start 281.45105 -43.053)
		(end 281.686 -43.053)
		(width 0.17272)
		(layer "B.Cu")
		(net "P52V_HS1_EFAULT_R")
	)
	(segment
		(start 281.813 -43.18)
		(end 282.1432 -43.18)
		(width 0.17272)
		(layer "B.Cu")
		(net "P52V_HS1_EFAULT_R")
	)
	(segment
		(start 280.30805 -41.91)
		(end 281.45105 -43.053)
		(width 0.17272)
		(layer "B.Cu")
		(net "P52V_HS1_EFAULT_R")
	)
	(segment
		(start 208.331054 -87.757)
		(end 207.7974 -87.757)
		(width 0.17272)
		(layer "F.Cu")
		(net "LED_D1_R4")
	)
	(segment
		(start 207.7974 -87.757)
		(end 206.7687 -86.7283)
		(width 0.17272)
		(layer "F.Cu")
		(net "LED_D1_R4")
	)
	(segment
		(start 207.772 -85.725)
		(end 208.331054 -85.725)
		(width 0.17272)
		(layer "F.Cu")
		(net "LED_D1_R4")
	)
	(segment
		(start 206.7687 -86.7283)
		(end 207.772 -85.725)
		(width 0.17272)
		(layer "F.Cu")
		(net "LED_D1_R4")
	)
	(via
		(at 206.7687 -86.7283)
		(size 0.762)
		(drill 0.381)
		(layers "F.Cu" "B.Cu")
		(net "LED_D1_R4")
	)
	(segment
		(start 283.595572 -43.591226)
		(end 282.795472 -43.591226)
		(width 0.17272)
		(layer "F.Cu")
		(net "P52V_HS1_ESTART_R")
	)
	(via
		(at 282.795472 -43.591226)
		(size 0.508)
		(drill 0.254)
		(layers "F.Cu" "B.Cu")
		(net "P52V_HS1_ESTART_R")
	)
	(segment
		(start 280.30805 -42.799)
		(end 280.30805 -43.453304)
		(width 0.17272)
		(layer "B.Cu")
		(net "P52V_HS1_ESTART_R")
	)
	(segment
		(start 280.30805 -43.453304)
		(end 281.177746 -44.323)
		(width 0.17272)
		(layer "B.Cu")
		(net "P52V_HS1_ESTART_R")
	)
	(segment
		(start 281.177746 -44.323)
		(end 282.063698 -44.323)
		(width 0.17272)
		(layer "B.Cu")
		(net "P52V_HS1_ESTART_R")
	)
	(segment
		(start 282.063698 -44.323)
		(end 282.795472 -43.591226)
		(width 0.17272)
		(layer "B.Cu")
		(net "P52V_HS1_ESTART_R")
	)
	(segment
		(start 213.36 -87.757)
		(end 213.36 -90.296746)
		(width 0.17272)
		(layer "F.Cu")
		(net "LED_D1_R3")
	)
	(segment
		(start 213.36 -90.296746)
		(end 212.064346 -91.5924)
		(width 0.17272)
		(layer "F.Cu")
		(net "LED_D1_R3")
	)
	(segment
		(start 212.064346 -91.5924)
		(end 211.530946 -91.5924)
		(width 0.17272)
		(layer "F.Cu")
		(net "LED_D1_R3")
	)
	(segment
		(start 211.530946 -87.757)
		(end 213.36 -87.757)
		(width 0.17272)
		(layer "F.Cu")
		(net "LED_D1_R3")
	)
	(via
		(at 213.36 -87.757)
		(size 0.762)
		(drill 0.381)
		(layers "F.Cu" "B.Cu")
		(net "LED_D1_R3")
	)
	(segment
		(start 206.5274 -92.938854)
		(end 207.873854 -91.5924)
		(width 0.17272)
		(layer "F.Cu")
		(net "LED_D1_R2")
	)
	(segment
		(start 206.5274 -93.6244)
		(end 206.5274 -92.938854)
		(width 0.17272)
		(layer "F.Cu")
		(net "LED_D1_R2")
	)
	(segment
		(start 208.331054 -93.6244)
		(end 206.5274 -93.6244)
		(width 0.17272)
		(layer "F.Cu")
		(net "LED_D1_R2")
	)
	(segment
		(start 207.873854 -91.5924)
		(end 208.331054 -91.5924)
		(width 0.17272)
		(layer "F.Cu")
		(net "LED_D1_R2")
	)
	(via
		(at 206.5274 -93.6244)
		(size 0.762)
		(drill 0.381)
		(layers "F.Cu" "B.Cu")
		(net "LED_D1_R2")
	)
	(via
		(at 271.196054 -68.692268)
		(size 0.508)
		(drill 0.254)
		(layers "F.Cu" "B.Cu")
		(net "P52V_HS1_GATE6")
	)
	(segment
		(start 211.530946 -93.6244)
		(end 212.953346 -92.202)
		(width 0.17272)
		(layer "F.Cu")
		(net "LED_D1_R1")
	)
	(segment
		(start 213.36 -92.202)
		(end 213.36 -93.904054)
		(width 0.17272)
		(layer "F.Cu")
		(net "LED_D1_R1")
	)
	(segment
		(start 212.953346 -92.202)
		(end 213.36 -92.202)
		(width 0.17272)
		(layer "F.Cu")
		(net "LED_D1_R1")
	)
	(via
		(at 213.36 -92.202)
		(size 0.762)
		(drill 0.381)
		(layers "F.Cu" "B.Cu")
		(net "LED_D1_R1")
	)
	(via
		(at 271.197578 -92.822268)
		(size 0.508)
		(drill 0.254)
		(layers "F.Cu" "B.Cu")
		(net "P52V_HS1_GATE4")
	)
	(segment
		(start 278.49195 -45.593)
		(end 277.882096 -45.593)
		(width 0.381)
		(layer "F.Cu")
		(net "P52V_HS1_VCAP")
	)
	(via
		(at 277.882096 -45.593)
		(size 0.508)
		(drill 0.254)
		(layers "F.Cu" "B.Cu")
		(net "P52V_HS1_VCAP")
	)
	(via
		(at 278.257 -46.609)
		(size 0.6604)
		(drill 0.3302)
		(layers "F.Cu" "B.Cu")
		(net "P52V_HS1_VCAP")
	)
	(via
		(at 281.432 -43.688)
		(size 0.508)
		(drill 0.254)
		(layers "F.Cu" "B.Cu")
		(net "P52V_HS1_VCAP")
	)
	(segment
		(start 279.146 -45.593)
		(end 279.273 -45.72)
		(width 0.381)
		(layer "B.Cu")
		(net "P52V_HS1_VCAP")
	)
	(segment
		(start 277.882096 -46.234096)
		(end 278.257 -46.609)
		(width 0.381)
		(layer "B.Cu")
		(net "P52V_HS1_VCAP")
	)
	(segment
		(start 277.882096 -45.593)
		(end 277.882096 -46.234096)
		(width 0.381)
		(layer "B.Cu")
		(net "P52V_HS1_VCAP")
	)
	(segment
		(start 278.257 -46.609)
		(end 279.50795 -46.609)
		(width 0.381)
		(layer "B.Cu")
		(net "P52V_HS1_VCAP")
	)
	(segment
		(start 279.273 -45.72)
		(end 279.50795 -45.72)
		(width 0.381)
		(layer "B.Cu")
		(net "P52V_HS1_VCAP")
	)
	(segment
		(start 277.882096 -45.593)
		(end 279.146 -45.593)
		(width 0.381)
		(layer "B.Cu")
		(net "P52V_HS1_VCAP")
	)
	(segment
		(start 280.797 -43.688)
		(end 280.416 -44.069)
		(width 0.381)
		(layer "In7.Cu")
		(net "P52V_HS1_VCAP")
	)
	(segment
		(start 280.416 -44.069)
		(end 280.416 -44.831)
		(width 0.381)
		(layer "In7.Cu")
		(net "P52V_HS1_VCAP")
	)
	(segment
		(start 280.416 -44.831)
		(end 279.654 -45.593)
		(width 0.381)
		(layer "In7.Cu")
		(net "P52V_HS1_VCAP")
	)
	(segment
		(start 281.432 -43.688)
		(end 280.797 -43.688)
		(width 0.381)
		(layer "In7.Cu")
		(net "P52V_HS1_VCAP")
	)
	(segment
		(start 279.654 -45.593)
		(end 277.882096 -45.593)
		(width 0.381)
		(layer "In7.Cu")
		(net "P52V_HS1_VCAP")
	)
	(segment
		(start 285.115 -47.752)
		(end 285.115 -48.74895)
		(width 0.17272)
		(layer "F.Cu")
		(net "P52V_HS1_UVH")
	)
	(segment
		(start 285.795212 -45.790866)
		(end 285.795212 -46.690788)
		(width 0.17272)
		(layer "F.Cu")
		(net "P52V_HS1_UVH")
	)
	(segment
		(start 285.795212 -46.690788)
		(end 285.369 -47.117)
		(width 0.17272)
		(layer "F.Cu")
		(net "P52V_HS1_UVH")
	)
	(segment
		(start 283.972 -48.87595)
		(end 284.988 -48.87595)
		(width 0.17272)
		(layer "F.Cu")
		(net "P52V_HS1_UVH")
	)
	(segment
		(start 285.369 -47.498)
		(end 285.115 -47.752)
		(width 0.17272)
		(layer "F.Cu")
		(net "P52V_HS1_UVH")
	)
	(segment
		(start 285.369 -47.117)
		(end 285.369 -47.498)
		(width 0.17272)
		(layer "F.Cu")
		(net "P52V_HS1_UVH")
	)
	(segment
		(start 285.115 -48.74895)
		(end 284.988 -48.87595)
		(width 0.17272)
		(layer "F.Cu")
		(net "P52V_HS1_UVH")
	)
	(via
		(at 285.369 -47.498)
		(size 0.508)
		(drill 0.254)
		(layers "F.Cu" "B.Cu")
		(net "P52V_HS1_UVH")
	)
	(segment
		(start 285.369 -47.498)
		(end 285.693358 -47.822358)
		(width 0.17272)
		(layer "B.Cu")
		(net "P52V_HS1_UVH")
	)
	(segment
		(start 293.497 -51.435)
		(end 293.497 -52.39004)
		(width 0.17272)
		(layer "B.Cu")
		(net "P52V_HS1_UVH")
	)
	(segment
		(start 285.693358 -47.822358)
		(end 289.884358 -47.822358)
		(width 0.17272)
		(layer "B.Cu")
		(net "P52V_HS1_UVH")
	)
	(segment
		(start 289.884358 -47.822358)
		(end 293.497 -51.435)
		(width 0.17272)
		(layer "B.Cu")
		(net "P52V_HS1_UVH")
	)
	(segment
		(start 284.294072 -45.790866)
		(end 284.294072 -45.86859)
		(width 0.17272)
		(layer "F.Cu")
		(net "P52V_HS1_RND")
	)
	(segment
		(start 284.294072 -45.86859)
		(end 283.045662 -47.117)
		(width 0.17272)
		(layer "F.Cu")
		(net "P52V_HS1_RND")
	)
	(segment
		(start 282.17495 -47.625)
		(end 280.924 -48.87595)
		(width 0.17272)
		(layer "F.Cu")
		(net "P52V_HS1_RND")
	)
	(segment
		(start 283.045662 -47.117)
		(end 282.68295 -47.117)
		(width 0.17272)
		(layer "F.Cu")
		(net "P52V_HS1_RND")
	)
	(segment
		(start 282.68295 -47.117)
		(end 282.17495 -47.625)
		(width 0.17272)
		(layer "F.Cu")
		(net "P52V_HS1_RND")
	)
	(via
		(at 282.17495 -47.625)
		(size 0.762)
		(drill 0.381)
		(layers "F.Cu" "B.Cu")
		(net "P52V_HS1_RND")
	)
	(segment
		(start 280.1366 -36.9316)
		(end 280.67 -37.465)
		(width 0.17272)
		(layer "F.Cu")
		(net "SMB_CM_HS1_3V3SB_DATO")
	)
	(segment
		(start 279.766776 -36.358576)
		(end 280.1366 -36.7284)
		(width 0.17272)
		(layer "F.Cu")
		(net "SMB_CM_HS1_3V3SB_DATO")
	)
	(segment
		(start 282.788106 -40.091106)
		(end 281.559 -38.862)
		(width 0.17272)
		(layer "F.Cu")
		(net "SMB_CM_HS1_3V3SB_DATO")
	)
	(segment
		(start 283.595572 -40.091106)
		(end 282.788106 -40.091106)
		(width 0.17272)
		(layer "F.Cu")
		(net "SMB_CM_HS1_3V3SB_DATO")
	)
	(segment
		(start 279.427178 -36.358576)
		(end 279.766776 -36.358576)
		(width 0.17272)
		(layer "F.Cu")
		(net "SMB_CM_HS1_3V3SB_DATO")
	)
	(segment
		(start 281.559 -38.862)
		(end 281.559 -38.354)
		(width 0.17272)
		(layer "F.Cu")
		(net "SMB_CM_HS1_3V3SB_DATO")
	)
	(segment
		(start 280.1366 -36.7284)
		(end 280.1366 -36.9316)
		(width 0.17272)
		(layer "F.Cu")
		(net "SMB_CM_HS1_3V3SB_DATO")
	)
	(segment
		(start 281.559 -38.354)
		(end 280.67 -37.465)
		(width 0.17272)
		(layer "F.Cu")
		(net "SMB_CM_HS1_3V3SB_DATO")
	)
	(via
		(at 280.67 -37.465)
		(size 0.762)
		(drill 0.381)
		(layers "F.Cu" "B.Cu")
		(net "SMB_CM_HS1_3V3SB_DATO")
	)
	(segment
		(start 177.8 -5.207)
		(end 177.18405 -5.82295)
		(width 0.4572)
		(layer "F.Cu")
		(net "P3V3_AUX")
	)
	(segment
		(start 177.18405 -8.128)
		(end 177.160936 -8.104886)
		(width 0.4572)
		(layer "F.Cu")
		(net "P3V3_AUX")
	)
	(segment
		(start 204.089 -66.52895)
		(end 204.089 -65.91935)
		(width 0.4572)
		(layer "F.Cu")
		(net "P3V3_AUX")
	)
	(segment
		(start 278.610822 -39.649146)
		(end 278.610822 -38.571424)
		(width 0.381)
		(layer "F.Cu")
		(net "P3V3_AUX")
	)
	(segment
		(start 177.18405 -5.82295)
		(end 177.18405 -6.858)
		(width 0.4572)
		(layer "F.Cu")
		(net "P3V3_AUX")
	)
	(segment
		(start 177.160936 -6.881114)
		(end 177.18405 -6.858)
		(width 0.4572)
		(layer "F.Cu")
		(net "P3V3_AUX")
	)
	(segment
		(start 281.559 -35.28695)
		(end 281.559 -34.671)
		(width 0.381)
		(layer "F.Cu")
		(net "P3V3_AUX")
	)
	(segment
		(start 178.16195 -8.128)
		(end 177.18405 -8.128)
		(width 0.4572)
		(layer "F.Cu")
		(net "P3V3_AUX")
	)
	(segment
		(start 191.135 -6.87705)
		(end 191.135 -5.715)
		(width 0.4572)
		(layer "F.Cu")
		(net "P3V3_AUX")
	)
	(segment
		(start 177.160936 -8.104886)
		(end 177.160936 -6.881114)
		(width 0.4572)
		(layer "F.Cu")
		(net "P3V3_AUX")
	)
	(segment
		(start 191.135 -6.87705)
		(end 191.24295 -6.985)
		(width 0.4572)
		(layer "F.Cu")
		(net "P3V3_AUX")
	)
	(segment
		(start 190.627 -5.207)
		(end 177.8 -5.207)
		(width 0.4572)
		(layer "F.Cu")
		(net "P3V3_AUX")
	)
	(segment
		(start 278.610822 -38.571424)
		(end 278.001222 -38.571424)
		(width 0.381)
		(layer "F.Cu")
		(net "P3V3_AUX")
	)
	(segment
		(start 191.135 -5.715)
		(end 190.627 -5.207)
		(width 0.4572)
		(layer "F.Cu")
		(net "P3V3_AUX")
	)
	(via
		(at 190.43904 -14.1224)
		(size 0.508)
		(drill 0.254)
		(layers "F.Cu" "B.Cu")
		(net "P3V3_AUX")
	)
	(via
		(at 178.3588 -90.424)
		(size 0.508)
		(drill 0.254)
		(layers "F.Cu" "B.Cu")
		(net "P3V3_AUX")
	)
	(via
		(at 239.565688 -78.96479)
		(size 0.508)
		(drill 0.254)
		(layers "F.Cu" "B.Cu")
		(net "P3V3_AUX")
	)
	(via
		(at 210.693 -90.15095)
		(size 0.508)
		(drill 0.254)
		(layers "F.Cu" "B.Cu")
		(net "P3V3_AUX")
	)
	(via
		(at 191.15024 -16.2814)
		(size 0.508)
		(drill 0.254)
		(layers "F.Cu" "B.Cu")
		(net "P3V3_AUX")
	)
	(via
		(at 204.1906 -70.97395)
		(size 0.508)
		(drill 0.254)
		(layers "F.Cu" "B.Cu")
		(net "P3V3_AUX")
	)
	(via
		(at 137.78865 -78.867)
		(size 0.508)
		(drill 0.254)
		(layers "F.Cu" "B.Cu")
		(net "P3V3_AUX")
	)
	(via
		(at 135.50265 -78.867)
		(size 0.508)
		(drill 0.254)
		(layers "F.Cu" "B.Cu")
		(net "P3V3_AUX")
	)
	(via
		(at 42.12336 -62.94247)
		(size 0.508)
		(drill 0.254)
		(layers "F.Cu" "B.Cu")
		(net "P3V3_AUX")
	)
	(via
		(at 91.694 -77.71765)
		(size 0.508)
		(drill 0.254)
		(layers "F.Cu" "B.Cu")
		(net "P3V3_AUX")
	)
	(via
		(at 223.52 -77.34935)
		(size 0.762)
		(drill 0.254)
		(layers "F.Cu" "B.Cu")
		(net "P3V3_AUX")
	)
	(via
		(at 233.68 -90.30335)
		(size 0.508)
		(drill 0.254)
		(layers "F.Cu" "B.Cu")
		(net "P3V3_AUX")
	)
	(via
		(at 212.344 -68.707)
		(size 0.508)
		(drill 0.254)
		(layers "F.Cu" "B.Cu")
		(net "P3V3_AUX")
	)
	(via
		(at 57.65165 -78.613)
		(size 0.508)
		(drill 0.254)
		(layers "F.Cu" "B.Cu")
		(net "P3V3_AUX")
	)
	(via
		(at 191.15024 -7.6454)
		(size 0.508)
		(drill 0.254)
		(layers "F.Cu" "B.Cu")
		(net "P3V3_AUX")
	)
	(via
		(at 224.917 -89.64295)
		(size 0.508)
		(drill 0.254)
		(layers "F.Cu" "B.Cu")
		(net "P3V3_AUX")
	)
	(via
		(at 188.468 -86.741)
		(size 0.508)
		(drill 0.254)
		(layers "F.Cu" "B.Cu")
		(net "P3V3_AUX")
	)
	(via
		(at 188.595 -83.439)
		(size 0.508)
		(drill 0.254)
		(layers "F.Cu" "B.Cu")
		(net "P3V3_AUX")
	)
	(via
		(at 188.595 -89.7128)
		(size 0.508)
		(drill 0.254)
		(layers "F.Cu" "B.Cu")
		(net "P3V3_AUX")
	)
	(via
		(at 207.137 -83.566)
		(size 0.508)
		(drill 0.254)
		(layers "F.Cu" "B.Cu")
		(net "P3V3_AUX")
	)
	(via
		(at 177.788824 -78.867)
		(size 0.508)
		(drill 0.254)
		(layers "F.Cu" "B.Cu")
		(net "P3V3_AUX")
	)
	(via
		(at 189.77864 -9.779)
		(size 0.508)
		(drill 0.254)
		(layers "F.Cu" "B.Cu")
		(net "P3V3_AUX")
	)
	(via
		(at 235.458 -90.91295)
		(size 0.508)
		(drill 0.254)
		(layers "F.Cu" "B.Cu")
		(net "P3V3_AUX")
	)
	(via
		(at 203.34605 -85.852)
		(size 0.508)
		(drill 0.254)
		(layers "F.Cu" "B.Cu")
		(net "P3V3_AUX")
	)
	(via
		(at 188.595 -82.423)
		(size 0.508)
		(drill 0.254)
		(layers "F.Cu" "B.Cu")
		(net "P3V3_AUX")
	)
	(via
		(at 99.81565 -78.613)
		(size 0.508)
		(drill 0.254)
		(layers "F.Cu" "B.Cu")
		(net "P3V3_AUX")
	)
	(via
		(at 214.884 -68.71335)
		(size 0.508)
		(drill 0.254)
		(layers "F.Cu" "B.Cu")
		(net "P3V3_AUX")
	)
	(via
		(at 220.98 -77.34935)
		(size 0.762)
		(drill 0.254)
		(layers "F.Cu" "B.Cu")
		(net "P3V3_AUX")
	)
	(via
		(at 221.996 -91.05265)
		(size 0.508)
		(drill 0.254)
		(layers "F.Cu" "B.Cu")
		(net "P3V3_AUX")
	)
	(via
		(at 43.13936 -62.94247)
		(size 0.508)
		(drill 0.254)
		(layers "F.Cu" "B.Cu")
		(net "P3V3_AUX")
	)
	(via
		(at 191.15024 -14.1224)
		(size 0.508)
		(drill 0.254)
		(layers "F.Cu" "B.Cu")
		(net "P3V3_AUX")
	)
	(via
		(at 191.15024 -11.9634)
		(size 0.508)
		(drill 0.254)
		(layers "F.Cu" "B.Cu")
		(net "P3V3_AUX")
	)
	(via
		(at 203.95565 -91.948)
		(size 0.508)
		(drill 0.254)
		(layers "F.Cu" "B.Cu")
		(net "P3V3_AUX")
	)
	(via
		(at 206.14005 -87.376)
		(size 0.508)
		(drill 0.254)
		(layers "F.Cu" "B.Cu")
		(net "P3V3_AUX")
	)
	(via
		(at 204.089 -65.91935)
		(size 0.508)
		(drill 0.254)
		(layers "F.Cu" "B.Cu")
		(net "P3V3_AUX")
	)
	(via
		(at 203.962 -88.011)
		(size 0.508)
		(drill 0.254)
		(layers "F.Cu" "B.Cu")
		(net "P3V3_AUX")
	)
	(via
		(at 55.499 -78.613)
		(size 0.508)
		(drill 0.254)
		(layers "F.Cu" "B.Cu")
		(net "P3V3_AUX")
	)
	(via
		(at 209.169 -83.566)
		(size 0.508)
		(drill 0.254)
		(layers "F.Cu" "B.Cu")
		(net "P3V3_AUX")
	)
	(via
		(at 95.377 -78.613)
		(size 0.508)
		(drill 0.254)
		(layers "F.Cu" "B.Cu")
		(net "P3V3_AUX")
	)
	(via
		(at 213.614 -68.707)
		(size 0.508)
		(drill 0.254)
		(layers "F.Cu" "B.Cu")
		(net "P3V3_AUX")
	)
	(via
		(at 190.43904 -11.9634)
		(size 0.508)
		(drill 0.254)
		(layers "F.Cu" "B.Cu")
		(net "P3V3_AUX")
	)
	(via
		(at 188.595 -84.963)
		(size 0.508)
		(drill 0.254)
		(layers "F.Cu" "B.Cu")
		(net "P3V3_AUX")
	)
	(via
		(at 235.204 -72.00265)
		(size 0.508)
		(drill 0.254)
		(layers "F.Cu" "B.Cu")
		(net "P3V3_AUX")
	)
	(via
		(at 203.962 -90.678)
		(size 0.508)
		(drill 0.254)
		(layers "F.Cu" "B.Cu")
		(net "P3V3_AUX")
	)
	(via
		(at 190.43904 -7.6454)
		(size 0.508)
		(drill 0.254)
		(layers "F.Cu" "B.Cu")
		(net "P3V3_AUX")
	)
	(via
		(at 189.77864 -11.938)
		(size 0.508)
		(drill 0.254)
		(layers "F.Cu" "B.Cu")
		(net "P3V3_AUX")
	)
	(via
		(at 216.027 -90.65895)
		(size 0.508)
		(drill 0.254)
		(layers "F.Cu" "B.Cu")
		(net "P3V3_AUX")
	)
	(via
		(at 190.5762 -6.9088)
		(size 0.508)
		(drill 0.254)
		(layers "F.Cu" "B.Cu")
		(net "P3V3_AUX")
	)
	(via
		(at 190.01105 -93.091)
		(size 0.508)
		(drill 0.254)
		(layers "F.Cu" "B.Cu")
		(net "P3V3_AUX")
	)
	(via
		(at 231.648 -84.43595)
		(size 0.508)
		(drill 0.254)
		(layers "F.Cu" "B.Cu")
		(net "P3V3_AUX")
	)
	(via
		(at 189.77864 -7.62)
		(size 0.508)
		(drill 0.254)
		(layers "F.Cu" "B.Cu")
		(net "P3V3_AUX")
	)
	(via
		(at 97.52965 -78.613)
		(size 0.508)
		(drill 0.254)
		(layers "F.Cu" "B.Cu")
		(net "P3V3_AUX")
	)
	(via
		(at 205.359 -70.12305)
		(size 0.508)
		(drill 0.254)
		(layers "F.Cu" "B.Cu")
		(net "P3V3_AUX")
	)
	(via
		(at 190.43904 -16.2814)
		(size 0.508)
		(drill 0.254)
		(layers "F.Cu" "B.Cu")
		(net "P3V3_AUX")
	)
	(via
		(at 59.93765 -78.613)
		(size 0.508)
		(drill 0.254)
		(layers "F.Cu" "B.Cu")
		(net "P3V3_AUX")
	)
	(via
		(at 209.804 -68.71335)
		(size 0.508)
		(drill 0.254)
		(layers "F.Cu" "B.Cu")
		(net "P3V3_AUX")
	)
	(via
		(at 210.058 -91.56065)
		(size 0.508)
		(drill 0.254)
		(layers "F.Cu" "B.Cu")
		(net "P3V3_AUX")
	)
	(via
		(at 232.41 -81.89595)
		(size 0.508)
		(drill 0.254)
		(layers "F.Cu" "B.Cu")
		(net "P3V3_AUX")
	)
	(via
		(at 278.001222 -38.571424)
		(size 0.508)
		(drill 0.254)
		(layers "F.Cu" "B.Cu")
		(net "P3V3_AUX")
	)
	(via
		(at 216.154 -68.71335)
		(size 0.508)
		(drill 0.254)
		(layers "F.Cu" "B.Cu")
		(net "P3V3_AUX")
	)
	(via
		(at 188.595 -88.3158)
		(size 0.508)
		(drill 0.254)
		(layers "F.Cu" "B.Cu")
		(net "P3V3_AUX")
	)
	(via
		(at 236.347 -80.12684)
		(size 0.508)
		(drill 0.254)
		(layers "F.Cu" "B.Cu")
		(net "P3V3_AUX")
	)
	(via
		(at 217.12555 -84.05495)
		(size 0.508)
		(drill 0.254)
		(layers "F.Cu" "B.Cu")
		(net "P3V3_AUX")
	)
	(via
		(at 222.25 -77.34935)
		(size 0.508)
		(drill 0.254)
		(layers "F.Cu" "B.Cu")
		(net "P3V3_AUX")
	)
	(via
		(at 238.129064 -76.21905)
		(size 0.508)
		(drill 0.254)
		(layers "F.Cu" "B.Cu")
		(net "P3V3_AUX")
	)
	(via
		(at 109.728 -108.6104)
		(size 0.6604)
		(drill 0.3302)
		(layers "F.Cu" "B.Cu")
		(net "P3V3_AUX")
	)
	(via
		(at 213.281768 -83.716368)
		(size 0.508)
		(drill 0.254)
		(layers "F.Cu" "B.Cu")
		(net "P3V3_AUX")
	)
	(via
		(at 217.424 -68.71335)
		(size 0.508)
		(drill 0.254)
		(layers "F.Cu" "B.Cu")
		(net "P3V3_AUX")
	)
	(via
		(at 189.77864 -16.256)
		(size 0.508)
		(drill 0.254)
		(layers "F.Cu" "B.Cu")
		(net "P3V3_AUX")
	)
	(via
		(at 180.074824 -78.867)
		(size 0.508)
		(drill 0.254)
		(layers "F.Cu" "B.Cu")
		(net "P3V3_AUX")
	)
	(via
		(at 240.538 -76.82865)
		(size 0.508)
		(drill 0.254)
		(layers "F.Cu" "B.Cu")
		(net "P3V3_AUX")
	)
	(via
		(at 146.28495 -108.077)
		(size 0.6604)
		(drill 0.3302)
		(layers "F.Cu" "B.Cu")
		(net "P3V3_AUX")
	)
	(via
		(at 191.15024 -9.8044)
		(size 0.508)
		(drill 0.254)
		(layers "F.Cu" "B.Cu")
		(net "P3V3_AUX")
	)
	(via
		(at 211.074 -68.707)
		(size 0.508)
		(drill 0.254)
		(layers "F.Cu" "B.Cu")
		(net "P3V3_AUX")
	)
	(via
		(at 239.74679 -89.50579)
		(size 0.508)
		(drill 0.254)
		(layers "F.Cu" "B.Cu")
		(net "P3V3_AUX")
	)
	(via
		(at 229.743 -74.168)
		(size 0.508)
		(drill 0.254)
		(layers "F.Cu" "B.Cu")
		(net "P3V3_AUX")
	)
	(via
		(at 140.07465 -78.867)
		(size 0.508)
		(drill 0.254)
		(layers "F.Cu" "B.Cu")
		(net "P3V3_AUX")
	)
	(via
		(at 206.121 -83.566)
		(size 0.508)
		(drill 0.254)
		(layers "F.Cu" "B.Cu")
		(net "P3V3_AUX")
	)
	(via
		(at 190.43904 -9.8044)
		(size 0.508)
		(drill 0.254)
		(layers "F.Cu" "B.Cu")
		(net "P3V3_AUX")
	)
	(via
		(at 189.77864 -14.097)
		(size 0.508)
		(drill 0.254)
		(layers "F.Cu" "B.Cu")
		(net "P3V3_AUX")
	)
	(via
		(at 281.559 -34.671)
		(size 0.508)
		(drill 0.254)
		(layers "F.Cu" "B.Cu")
		(net "P3V3_AUX")
	)
	(via
		(at 175.502824 -78.867)
		(size 0.508)
		(drill 0.254)
		(layers "F.Cu" "B.Cu")
		(net "P3V3_AUX")
	)
	(segment
		(start 220.98 -77.34935)
		(end 220.98 -77.95895)
		(width 0.4572)
		(layer "B.Cu")
		(net "P3V3_AUX")
	)
	(segment
		(start 209.169 -83.566)
		(end 209.169 -82.95005)
		(width 0.381)
		(layer "B.Cu")
		(net "P3V3_AUX")
	)
	(segment
		(start 99.20605 -78.613)
		(end 99.81565 -78.613)
		(width 0.4572)
		(layer "B.Cu")
		(net "P3V3_AUX")
	)
	(segment
		(start 236.347 -80.12684)
		(end 237.031784 -80.12684)
		(width 0.4572)
		(layer "B.Cu")
		(net "P3V3_AUX")
	)
	(segment
		(start 204.089 -65.91935)
		(end 203.708 -66.30035)
		(width 0.381)
		(layer "B.Cu")
		(net "P3V3_AUX")
	)
	(segment
		(start 240.538 -76.82865)
		(end 240.538 -76.21905)
		(width 0.381)
		(layer "B.Cu")
		(net "P3V3_AUX")
	)
	(segment
		(start 205.994 -71.374254)
		(end 205.994 -70.12305)
		(width 0.4572)
		(layer "B.Cu")
		(net "P3V3_AUX")
	)
	(segment
		(start 239.565688 -78.96479)
		(end 238.955834 -78.96479)
		(width 0.381)
		(layer "B.Cu")
		(net "P3V3_AUX")
	)
	(segment
		(start 155.575 -90.424)
		(end 178.3588 -90.424)
		(width 0.4572)
		(layer "B.Cu")
		(net "P3V3_AUX")
	)
	(segment
		(start 216.154 -68.71335)
		(end 216.154 -69.32295)
		(width 0.381)
		(layer "B.Cu")
		(net "P3V3_AUX")
	)
	(segment
		(start 211.088986 -89.29624)
		(end 211.088986 -88.83396)
		(width 0.4572)
		(layer "B.Cu")
		(net "P3V3_AUX")
	)
	(segment
		(start 213.281768 -83.716368)
		(end 212.8774 -83.312)
		(width 0.4572)
		(layer "B.Cu")
		(net "P3V3_AUX")
	)
	(segment
		(start 234.823 -90.91295)
		(end 235.458 -90.91295)
		(width 0.4572)
		(layer "B.Cu")
		(net "P3V3_AUX")
	)
	(segment
		(start 211.455 -89.662254)
		(end 211.088986 -89.29624)
		(width 0.4572)
		(layer "B.Cu")
		(net "P3V3_AUX")
	)
	(segment
		(start 203.34605 -83.82)
		(end 203.34605 -85.09)
		(width 0.381)
		(layer "B.Cu")
		(net "P3V3_AUX")
	)
	(segment
		(start 204.851 -70.97395)
		(end 204.1906 -70.97395)
		(width 0.381)
		(layer "B.Cu")
		(net "P3V3_AUX")
	)
	(segment
		(start 223.52 -88.88095)
		(end 224.282 -89.64295)
		(width 0.4572)
		(layer "B.Cu")
		(net "P3V3_AUX")
	)
	(segment
		(start 203.95565 -91.948)
		(end 203.34605 -91.948)
		(width 0.4572)
		(layer "B.Cu")
		(net "P3V3_AUX")
	)
	(segment
		(start 213.614 -68.707)
		(end 213.614 -69.32295)
		(width 0.381)
		(layer "B.Cu")
		(net "P3V3_AUX")
	)
	(segment
		(start 188.95695 -86.741)
		(end 189.21095 -86.995)
		(width 0.254)
		(layer "B.Cu")
		(net "P3V3_AUX")
	)
	(segment
		(start 231.408986 -81.551272)
		(end 231.408986 -80.45196)
		(width 0.4572)
		(layer "B.Cu")
		(net "P3V3_AUX")
	)
	(segment
		(start 204.216 -70.94855)
		(end 204.1906 -70.97395)
		(width 0.381)
		(layer "B.Cu")
		(net "P3V3_AUX")
	)
	(segment
		(start 211.074 -68.707)
		(end 211.074 -69.32295)
		(width 0.381)
		(layer "B.Cu")
		(net "P3V3_AUX")
	)
	(segment
		(start 193.11112 -91.317064)
		(end 192.731136 -91.317064)
		(width 0.381)
		(layer "B.Cu")
		(net "P3V3_AUX")
	)
	(segment
		(start 207.390746 -72.771)
		(end 205.994 -71.374254)
		(width 0.4572)
		(layer "B.Cu")
		(net "P3V3_AUX")
	)
	(segment
		(start 210.693 -90.15095)
		(end 211.455 -90.15095)
		(width 0.381)
		(layer "B.Cu")
		(net "P3V3_AUX")
	)
	(segment
		(start 239.74679 -89.50579)
		(end 239.082834 -89.50579)
		(width 0.381)
		(layer "B.Cu")
		(net "P3V3_AUX")
	)
	(segment
		(start 177.9778 -88.7984)
		(end 178.3588 -89.1794)
		(width 0.381)
		(layer "B.Cu")
		(net "P3V3_AUX")
	)
	(segment
		(start 212.8774 -83.312)
		(end 212.74405 -83.312)
		(width 0.4572)
		(layer "B.Cu")
		(net "P3V3_AUX")
	)
	(segment
		(start 190.01105 -91.821)
		(end 190.01105 -93.091)
		(width 0.381)
		(layer "B.Cu")
		(net "P3V3_AUX")
	)
	(segment
		(start 57.04205 -78.613)
		(end 57.65165 -78.613)
		(width 0.4572)
		(layer "B.Cu")
		(net "P3V3_AUX")
	)
	(segment
		(start 178.3588 -89.1794)
		(end 178.3588 -90.424)
		(width 0.381)
		(layer "B.Cu")
		(net "P3V3_AUX")
	)
	(segment
		(start 189.21095 -89.7128)
		(end 188.595 -89.7128)
		(width 0.381)
		(layer "B.Cu")
		(net "P3V3_AUX")
	)
	(segment
		(start 207.137 -83.566)
		(end 207.137 -82.95005)
		(width 0.381)
		(layer "B.Cu")
		(net "P3V3_AUX")
	)
	(segment
		(start 192.2272 -91.821)
		(end 190.01105 -91.821)
		(width 0.381)
		(layer "B.Cu")
		(net "P3V3_AUX")
	)
	(segment
		(start 234.62996 -89.109042)
		(end 234.62996 -90.135456)
		(width 0.4572)
		(layer "B.Cu")
		(net "P3V3_AUX")
	)
	(segment
		(start 212.344 -68.707)
		(end 212.344 -69.32295)
		(width 0.381)
		(layer "B.Cu")
		(net "P3V3_AUX")
	)
	(segment
		(start 205.359 -70.12305)
		(end 205.994 -70.12305)
		(width 0.4572)
		(layer "B.Cu")
		(net "P3V3_AUX")
	)
	(segment
		(start 231.753664 -81.89595)
		(end 231.408986 -81.551272)
		(width 0.4572)
		(layer "B.Cu")
		(net "P3V3_AUX")
	)
	(segment
		(start 188.595 -82.423)
		(end 189.21095 -82.423)
		(width 0.381)
		(layer "B.Cu")
		(net "P3V3_AUX")
	)
	(segment
		(start 206.14005 -86.614)
		(end 206.14005 -87.376)
		(width 0.381)
		(layer "B.Cu")
		(net "P3V3_AUX")
	)
	(segment
		(start 209.804 -68.71335)
		(end 209.804 -69.32295)
		(width 0.381)
		(layer "B.Cu")
		(net "P3V3_AUX")
	)
	(segment
		(start 216.46896 -89.850214)
		(end 216.46896 -88.855042)
		(width 0.4572)
		(layer "B.Cu")
		(net "P3V3_AUX")
	)
	(segment
		(start 223.52 -77.34935)
		(end 223.52 -77.95895)
		(width 0.4572)
		(layer "B.Cu")
		(net "P3V3_AUX")
	)
	(segment
		(start 217.424 -68.71335)
		(end 217.424 -69.32295)
		(width 0.381)
		(layer "B.Cu")
		(net "P3V3_AUX")
	)
	(segment
		(start 188.595 -83.439)
		(end 189.21095 -83.439)
		(width 0.381)
		(layer "B.Cu")
		(net "P3V3_AUX")
	)
	(segment
		(start 203.708 -66.30035)
		(end 203.708 -68.453)
		(width 0.381)
		(layer "B.Cu")
		(net "P3V3_AUX")
	)
	(segment
		(start 235.204 -72.00265)
		(end 235.204 -71.39305)
		(width 0.381)
		(layer "B.Cu")
		(net "P3V3_AUX")
	)
	(segment
		(start 231.648 -84.43595)
		(end 231.013 -84.43595)
		(width 0.381)
		(layer "B.Cu")
		(net "P3V3_AUX")
	)
	(segment
		(start 188.595 -84.963)
		(end 189.21095 -84.963)
		(width 0.381)
		(layer "B.Cu")
		(net "P3V3_AUX")
	)
	(segment
		(start 232.41 -81.89595)
		(end 231.775 -81.89595)
		(width 0.4572)
		(layer "B.Cu")
		(net "P3V3_AUX")
	)
	(segment
		(start 238.129064 -76.21905)
		(end 238.76 -76.21905)
		(width 0.381)
		(layer "B.Cu")
		(net "P3V3_AUX")
	)
	(segment
		(start 188.468 -86.741)
		(end 188.95695 -86.741)
		(width 0.254)
		(layer "B.Cu")
		(net "P3V3_AUX")
	)
	(segment
		(start 211.455 -90.15095)
		(end 211.455 -89.662254)
		(width 0.4572)
		(layer "B.Cu")
		(net "P3V3_AUX")
	)
	(segment
		(start 281.94 -35.052)
		(end 281.559 -34.671)
		(width 0.381)
		(layer "B.Cu")
		(net "P3V3_AUX")
	)
	(segment
		(start 224.282 -89.64295)
		(end 224.917 -89.64295)
		(width 0.4572)
		(layer "B.Cu")
		(net "P3V3_AUX")
	)
	(segment
		(start 189.21095 -88.3158)
		(end 188.595 -88.3158)
		(width 0.381)
		(layer "B.Cu")
		(net "P3V3_AUX")
	)
	(segment
		(start 146.28495 -99.71405)
		(end 155.575 -90.424)
		(width 0.4572)
		(layer "B.Cu")
		(net "P3V3_AUX")
	)
	(segment
		(start 204.216 -68.961)
		(end 204.216 -70.94855)
		(width 0.381)
		(layer "B.Cu")
		(net "P3V3_AUX")
	)
	(segment
		(start 59.32805 -78.613)
		(end 59.93765 -78.613)
		(width 0.4572)
		(layer "B.Cu")
		(net "P3V3_AUX")
	)
	(segment
		(start 208.26095 -73.152)
		(end 207.87995 -72.771)
		(width 0.3556)
		(layer "B.Cu")
		(net "P3V3_AUX")
	)
	(segment
		(start 223.52 -86.0806)
		(end 223.52 -88.88095)
		(width 0.4572)
		(layer "B.Cu")
		(net "P3V3_AUX")
	)
	(segment
		(start 237.031784 -80.12684)
		(end 237.072678 -80.167734)
		(width 0.3556)
		(layer "B.Cu")
		(net "P3V3_AUX")
	)
	(segment
		(start 234.62996 -90.135456)
		(end 234.823 -90.328496)
		(width 0.4572)
		(layer "B.Cu")
		(net "P3V3_AUX")
	)
	(segment
		(start 216.662 -90.043254)
		(end 216.46896 -89.850214)
		(width 0.4572)
		(layer "B.Cu")
		(net "P3V3_AUX")
	)
	(segment
		(start 139.46505 -78.867)
		(end 140.07465 -78.867)
		(width 0.4572)
		(layer "B.Cu")
		(net "P3V3_AUX")
	)
	(segment
		(start 154.0002 -88.7984)
		(end 177.9778 -88.7984)
		(width 0.381)
		(layer "B.Cu")
		(net "P3V3_AUX")
	)
	(segment
		(start 234.823 -90.328496)
		(end 234.823 -90.91295)
		(width 0.4572)
		(layer "B.Cu")
		(net "P3V3_AUX")
	)
	(segment
		(start 54.88305 -78.613)
		(end 55.499 -78.613)
		(width 0.4572)
		(layer "B.Cu")
		(net "P3V3_AUX")
	)
	(segment
		(start 106.284776 -109.640624)
		(end 107.315 -108.6104)
		(width 0.381)
		(layer "B.Cu")
		(net "P3V3_AUX")
	)
	(segment
		(start 134.1882 -108.6104)
		(end 154.0002 -88.7984)
		(width 0.381)
		(layer "B.Cu")
		(net "P3V3_AUX")
	)
	(segment
		(start 237.072678 -80.167734)
		(end 237.072678 -81.939384)
		(width 0.3556)
		(layer "B.Cu")
		(net "P3V3_AUX")
	)
	(segment
		(start 207.87995 -72.771)
		(end 207.390746 -72.771)
		(width 0.4572)
		(layer "B.Cu")
		(net "P3V3_AUX")
	)
	(segment
		(start 107.315 -108.6104)
		(end 109.728 -108.6104)
		(width 0.381)
		(layer "B.Cu")
		(net "P3V3_AUX")
	)
	(segment
		(start 106.284776 -110.109)
		(end 106.284776 -109.640624)
		(width 0.381)
		(layer "B.Cu")
		(net "P3V3_AUX")
	)
	(segment
		(start 179.465224 -78.867)
		(end 180.074824 -78.867)
		(width 0.4572)
		(layer "B.Cu")
		(net "P3V3_AUX")
	)
	(segment
		(start 210.058 -91.56065)
		(end 210.058 -90.95105)
		(width 0.4572)
		(layer "B.Cu")
		(net "P3V3_AUX")
	)
	(segment
		(start 134.89305 -78.867)
		(end 135.50265 -78.867)
		(width 0.4572)
		(layer "B.Cu")
		(net "P3V3_AUX")
	)
	(segment
		(start 216.662 -90.65895)
		(end 216.662 -90.043254)
		(width 0.4572)
		(layer "B.Cu")
		(net "P3V3_AUX")
	)
	(segment
		(start 222.25 -77.34935)
		(end 222.25 -77.95895)
		(width 0.4572)
		(layer "B.Cu")
		(net "P3V3_AUX")
	)
	(segment
		(start 91.694 -77.10805)
		(end 91.694 -77.71765)
		(width 0.381)
		(layer "B.Cu")
		(net "P3V3_AUX")
	)
	(segment
		(start 203.708 -68.453)
		(end 204.216 -68.961)
		(width 0.381)
		(layer "B.Cu")
		(net "P3V3_AUX")
	)
	(segment
		(start 177.179224 -78.867)
		(end 177.788824 -78.867)
		(width 0.4572)
		(layer "B.Cu")
		(net "P3V3_AUX")
	)
	(segment
		(start 203.34605 -88.011)
		(end 203.962 -88.011)
		(width 0.381)
		(layer "B.Cu")
		(net "P3V3_AUX")
	)
	(segment
		(start 174.893224 -78.867)
		(end 175.502824 -78.867)
		(width 0.4572)
		(layer "B.Cu")
		(net "P3V3_AUX")
	)
	(segment
		(start 214.884 -68.71335)
		(end 214.884 -69.32295)
		(width 0.381)
		(layer "B.Cu")
		(net "P3V3_AUX")
	)
	(segment
		(start 229.743 -74.168)
		(end 229.743 -74.78395)
		(width 0.381)
		(layer "B.Cu")
		(net "P3V3_AUX")
	)
	(segment
		(start 137.17905 -78.867)
		(end 137.78865 -78.867)
		(width 0.4572)
		(layer "B.Cu")
		(net "P3V3_AUX")
	)
	(segment
		(start 203.962 -90.678)
		(end 203.34605 -90.678)
		(width 0.4572)
		(layer "B.Cu")
		(net "P3V3_AUX")
	)
	(segment
		(start 109.728 -108.6104)
		(end 134.1882 -108.6104)
		(width 0.381)
		(layer "B.Cu")
		(net "P3V3_AUX")
	)
	(segment
		(start 146.28495 -108.077)
		(end 146.28495 -99.71405)
		(width 0.4572)
		(layer "B.Cu")
		(net "P3V3_AUX")
	)
	(segment
		(start 216.408 -84.05495)
		(end 217.12555 -84.05495)
		(width 0.381)
		(layer "B.Cu")
		(net "P3V3_AUX")
	)
	(segment
		(start 233.68 -90.30335)
		(end 233.68 -90.91295)
		(width 0.381)
		(layer "B.Cu")
		(net "P3V3_AUX")
	)
	(segment
		(start 216.027 -90.65895)
		(end 216.662 -90.65895)
		(width 0.4572)
		(layer "B.Cu")
		(net "P3V3_AUX")
	)
	(segment
		(start 203.34605 -85.852)
		(end 203.34605 -86.614)
		(width 0.381)
		(layer "B.Cu")
		(net "P3V3_AUX")
	)
	(segment
		(start 206.121 -83.566)
		(end 206.121 -82.95005)
		(width 0.381)
		(layer "B.Cu")
		(net "P3V3_AUX")
	)
	(segment
		(start 281.94 -36.04895)
		(end 281.94 -35.052)
		(width 0.381)
		(layer "B.Cu")
		(net "P3V3_AUX")
	)
	(segment
		(start 96.92005 -78.613)
		(end 97.52965 -78.613)
		(width 0.4572)
		(layer "B.Cu")
		(net "P3V3_AUX")
	)
	(segment
		(start 231.775 -81.89595)
		(end 231.753664 -81.89595)
		(width 0.4572)
		(layer "B.Cu")
		(net "P3V3_AUX")
	)
	(segment
		(start 94.76105 -78.613)
		(end 95.377 -78.613)
		(width 0.4572)
		(layer "B.Cu")
		(net "P3V3_AUX")
	)
	(segment
		(start 192.731136 -91.317064)
		(end 192.2272 -91.821)
		(width 0.381)
		(layer "B.Cu")
		(net "P3V3_AUX")
	)
	(segment
		(start 203.34605 -89.408)
		(end 203.34605 -90.678)
		(width 0.4572)
		(layer "B.Cu")
		(net "P3V3_AUX")
	)
	(segment
		(start 221.996 -91.05265)
		(end 221.996 -90.44305)
		(width 0.4572)
		(layer "B.Cu")
		(net "P3V3_AUX")
	)
	(segment
		(start 203.34605 -85.09)
		(end 203.34605 -85.852)
		(width 0.381)
		(layer "B.Cu")
		(net "P3V3_AUX")
	)
	(segment
		(start 146.28495 -110.109)
		(end 146.28495 -108.077)
		(width 0.4572)
		(layer "B.Cu")
		(net "P3V3_AUX")
	)
	(segment
		(start 235.458 -90.91295)
		(end 235.458 -90.17)
		(width 0.381)
		(layer "In2.Cu")
		(net "P3V3_AUX")
	)
	(segment
		(start 216.154 -68.71335)
		(end 216.154 -69.47535)
		(width 0.4572)
		(layer "In4.Cu")
		(net "P3V3_AUX")
	)
	(segment
		(start 204.089 -66.48831)
		(end 204.089 -65.91935)
		(width 0.4572)
		(layer "In4.Cu")
		(net "P3V3_AUX")
	)
	(segment
		(start 203.34605 -85.852)
		(end 204.025754 -85.852)
		(width 0.4572)
		(layer "In4.Cu")
		(net "P3V3_AUX")
	)
	(segment
		(start 188.468 -86.741)
		(end 188.468 -87.249)
		(width 0.508)
		(layer "In4.Cu")
		(net "P3V3_AUX")
	)
	(segment
		(start 214.884 -68.71335)
		(end 214.884 -69.377306)
		(width 0.4572)
		(layer "In4.Cu")
		(net "P3V3_AUX")
	)
	(segment
		(start 203.42606 -67.15125)
		(end 204.089 -66.48831)
		(width 0.4572)
		(layer "In4.Cu")
		(net "P3V3_AUX")
	)
	(segment
		(start 212.344 -68.707)
		(end 212.344 -69.235828)
		(width 0.4572)
		(layer "In4.Cu")
		(net "P3V3_AUX")
	)
	(segment
		(start 178.789584 -89.45118)
		(end 178.3588 -89.881964)
		(width 0.4572)
		(layer "In4.Cu")
		(net "P3V3_AUX")
	)
	(segment
		(start 216.027 -90.65895)
		(end 216.027 -89.573354)
		(width 0.4572)
		(layer "In4.Cu")
		(net "P3V3_AUX")
	)
	(segment
		(start 210.693 -90.444574)
		(end 210.693 -90.15095)
		(width 0.4572)
		(layer "In4.Cu")
		(net "P3V3_AUX")
	)
	(segment
		(start 211.074 -68.707)
		(end 211.074 -69.311266)
		(width 0.4572)
		(layer "In4.Cu")
		(net "P3V3_AUX")
	)
	(segment
		(start 210.82 -90.571574)
		(end 210.693 -90.444574)
		(width 0.4572)
		(layer "In4.Cu")
		(net "P3V3_AUX")
	)
	(segment
		(start 217.250772 -69.655436)
		(end 217.424 -69.482208)
		(width 0.4572)
		(layer "In4.Cu")
		(net "P3V3_AUX")
	)
	(segment
		(start 217.424 -69.482208)
		(end 217.424 -68.71335)
		(width 0.4572)
		(layer "In4.Cu")
		(net "P3V3_AUX")
	)
	(segment
		(start 205.359 -70.12305)
		(end 205.359 -70.971664)
		(width 0.4572)
		(layer "In4.Cu")
		(net "P3V3_AUX")
	)
	(segment
		(start 178.3588 -89.881964)
		(end 178.3588 -90.424)
		(width 0.4572)
		(layer "In4.Cu")
		(net "P3V3_AUX")
	)
	(segment
		(start 213.614 -68.707)
		(end 213.614 -69.205348)
		(width 0.4572)
		(layer "In4.Cu")
		(net "P3V3_AUX")
	)
	(segment
		(start 209.78495 -91.2876)
		(end 210.058 -91.56065)
		(width 0.381)
		(layer "In7.Cu")
		(net "P3V3_AUX")
	)
	(segment
		(start 42.12336 -63.82004)
		(end 38.6715 -67.2719)
		(width 0.381)
		(layer "In7.Cu")
		(net "P3V3_AUX")
	)
	(segment
		(start 203.95565 -91.948)
		(end 204.61605 -91.2876)
		(width 0.381)
		(layer "In7.Cu")
		(net "P3V3_AUX")
	)
	(segment
		(start 38.6715 -72.758046)
		(end 48.844454 -82.931)
		(width 0.381)
		(layer "In7.Cu")
		(net "P3V3_AUX")
	)
	(segment
		(start 43.13936 -62.94247)
		(end 42.12336 -62.94247)
		(width 0.381)
		(layer "In7.Cu")
		(net "P3V3_AUX")
	)
	(segment
		(start 210.058 -91.56065)
		(end 210.693 -90.92565)
		(width 0.381)
		(layer "In7.Cu")
		(net "P3V3_AUX")
	)
	(segment
		(start 204.61605 -91.2876)
		(end 209.78495 -91.2876)
		(width 0.381)
		(layer "In7.Cu")
		(net "P3V3_AUX")
	)
	(segment
		(start 155.829 -82.931)
		(end 165.989 -93.091)
		(width 0.381)
		(layer "In7.Cu")
		(net "P3V3_AUX")
	)
	(segment
		(start 202.81265 -93.091)
		(end 203.95565 -91.948)
		(width 0.381)
		(layer "In7.Cu")
		(net "P3V3_AUX")
	)
	(segment
		(start 48.844454 -82.931)
		(end 155.829 -82.931)
		(width 0.381)
		(layer "In7.Cu")
		(net "P3V3_AUX")
	)
	(segment
		(start 38.6715 -67.2719)
		(end 38.6715 -72.758046)
		(width 0.381)
		(layer "In7.Cu")
		(net "P3V3_AUX")
	)
	(segment
		(start 165.989 -93.091)
		(end 190.01105 -93.091)
		(width 0.381)
		(layer "In7.Cu")
		(net "P3V3_AUX")
	)
	(segment
		(start 210.693 -90.92565)
		(end 210.693 -90.15095)
		(width 0.381)
		(layer "In7.Cu")
		(net "P3V3_AUX")
	)
	(segment
		(start 190.01105 -93.091)
		(end 202.81265 -93.091)
		(width 0.381)
		(layer "In7.Cu")
		(net "P3V3_AUX")
	)
	(segment
		(start 42.12336 -62.94247)
		(end 42.12336 -63.82004)
		(width 0.381)
		(layer "In7.Cu")
		(net "P3V3_AUX")
	)
	(segment
		(start 302.3616 -121.4755)
		(end 302.3616 -119.6975)
		(width 0.4572)
		(layer "F.Cu")
		(net "P52V_HS1_SENSE_P_R1")
	)
	(segment
		(start 302.3616 -122.9995)
		(end 302.3616 -121.4755)
		(width 0.4572)
		(layer "F.Cu")
		(net "P52V_HS1_SENSE_P_R1")
	)
	(segment
		(start 302.3616 -119.6975)
		(end 303.23536 -119.6975)
		(width 0.4572)
		(layer "F.Cu")
		(net "P52V_HS1_SENSE_P_R1")
	)
	(segment
		(start 299.688758 -113.904268)
		(end 300.196758 -114.412268)
		(width 0.254)
		(layer "F.Cu")
		(net "P52V_HS1_SENSE_P_R1")
	)
	(segment
		(start 300.196758 -114.412268)
		(end 300.430692 -114.412268)
		(width 0.254)
		(layer "F.Cu")
		(net "P52V_HS1_SENSE_P_R1")
	)
	(via
		(at 303.23536 -119.6975)
		(size 0.508)
		(drill 0.254)
		(layers "F.Cu" "B.Cu")
		(net "P52V_HS1_SENSE_P_R1")
	)
	(via
		(at 299.688758 -113.904268)
		(size 0.508)
		(drill 0.254)
		(layers "F.Cu" "B.Cu")
		(net "P52V_HS1_SENSE_P_R1")
	)
	(segment
		(start 301.90948 -119.6975)
		(end 303.23536 -119.6975)
		(width 0.4572)
		(layer "B.Cu")
		(net "P52V_HS1_SENSE_P_R1")
	)
	(segment
		(start 299.688758 -113.904268)
		(end 300.32452 -114.54003)
		(width 0.4572)
		(layer "B.Cu")
		(net "P52V_HS1_SENSE_P_R1")
	)
	(segment
		(start 300.32452 -118.11254)
		(end 301.90948 -119.6975)
		(width 0.4572)
		(layer "B.Cu")
		(net "P52V_HS1_SENSE_P_R1")
	)
	(segment
		(start 300.32452 -114.54003)
		(end 300.32452 -118.11254)
		(width 0.4572)
		(layer "B.Cu")
		(net "P52V_HS1_SENSE_P_R1")
	)
	(segment
		(start 284.794452 -38.892226)
		(end 284.794452 -36.703)
		(width 0.17272)
		(layer "F.Cu")
		(net "P52V_HS1_GPO1")
	)
	(via
		(at 284.794452 -36.703)
		(size 0.508)
		(drill 0.254)
		(layers "F.Cu" "B.Cu")
		(net "P52V_HS1_GPO1")
	)
	(segment
		(start 282.956 -36.84905)
		(end 284.648402 -36.84905)
		(width 0.17272)
		(layer "B.Cu")
		(net "P52V_HS1_GPO1")
	)
	(segment
		(start 284.648402 -36.84905)
		(end 284.794452 -36.703)
		(width 0.17272)
		(layer "B.Cu")
		(net "P52V_HS1_GPO1")
	)
	(segment
		(start 282.956 -36.84905)
		(end 281.94 -36.84905)
		(width 0.17272)
		(layer "B.Cu")
		(net "P52V_HS1_GPO1")
	)
	(via
		(at 271.20342 -116.929408)
		(size 0.508)
		(drill 0.254)
		(layers "F.Cu" "B.Cu")
		(net "P52V_HS1_GATE2")
	)
	(via
		(at 233.68 -81.31429)
		(size 0.6604)
		(drill 0.3302)
		(layers "F.Cu" "B.Cu")
		(net "RST_SMB_PDB_N")
	)
	(segment
		(start 237.744 -75.184)
		(end 237.744 -73.024746)
		(width 0.17272)
		(layer "B.Cu")
		(net "RST_SMB_PDB_N")
	)
	(segment
		(start 233.68 -86.658958)
		(end 233.68 -81.31429)
		(width 0.17272)
		(layer "B.Cu")
		(net "RST_SMB_PDB_N")
	)
	(segment
		(start 236.982 -72.262746)
		(end 236.982 -71.39305)
		(width 0.17272)
		(layer "B.Cu")
		(net "RST_SMB_PDB_N")
	)
	(segment
		(start 233.68 -81.31429)
		(end 233.68 -79.248)
		(width 0.17272)
		(layer "B.Cu")
		(net "RST_SMB_PDB_N")
	)
	(segment
		(start 237.744 -73.024746)
		(end 236.982 -72.262746)
		(width 0.17272)
		(layer "B.Cu")
		(net "RST_SMB_PDB_N")
	)
	(segment
		(start 233.68 -79.248)
		(end 237.744 -75.184)
		(width 0.17272)
		(layer "B.Cu")
		(net "RST_SMB_PDB_N")
	)
	(via
		(at 271.237964 -128.937766)
		(size 0.508)
		(drill 0.254)
		(layers "F.Cu" "B.Cu")
		(net "P52V_HS1_GATE1")
	)
	(segment
		(start 218.0844 -74.9808)
		(end 218.0844 -81.6356)
		(width 0.17272)
		(layer "F.Cu")
		(net "FAN_PWR_EN")
	)
	(segment
		(start 230.886 -72.00265)
		(end 230.13035 -71.247)
		(width 0.17272)
		(layer "F.Cu")
		(net "FAN_PWR_EN")
	)
	(segment
		(start 215.519 -84.201)
		(end 215.519 -85.2932)
		(width 0.17272)
		(layer "F.Cu")
		(net "FAN_PWR_EN")
	)
	(segment
		(start 218.0844 -81.6356)
		(end 215.519 -84.201)
		(width 0.17272)
		(layer "F.Cu")
		(net "FAN_PWR_EN")
	)
	(segment
		(start 230.13035 -71.247)
		(end 221.8182 -71.247)
		(width 0.17272)
		(layer "F.Cu")
		(net "FAN_PWR_EN")
	)
	(segment
		(start 221.8182 -71.247)
		(end 218.0844 -74.9808)
		(width 0.17272)
		(layer "F.Cu")
		(net "FAN_PWR_EN")
	)
	(via
		(at 215.519 -85.2932)
		(size 0.762)
		(drill 0.254)
		(layers "F.Cu" "B.Cu")
		(net "FAN_PWR_EN")
	)
	(via
		(at 230.886 -72.00265)
		(size 0.508)
		(drill 0.254)
		(layers "F.Cu" "B.Cu")
		(net "FAN_PWR_EN")
	)
	(segment
		(start 215.519 -85.2932)
		(end 215.519 -86.404958)
		(width 0.17272)
		(layer "B.Cu")
		(net "FAN_PWR_EN")
	)
	(segment
		(start 215.95715 -84.85505)
		(end 215.519 -85.2932)
		(width 0.17272)
		(layer "B.Cu")
		(net "FAN_PWR_EN")
	)
	(segment
		(start 230.886 -72.00265)
		(end 230.886 -71.39305)
		(width 0.17272)
		(layer "B.Cu")
		(net "FAN_PWR_EN")
	)
	(segment
		(start 216.408 -84.85505)
		(end 215.95715 -84.85505)
		(width 0.17272)
		(layer "B.Cu")
		(net "FAN_PWR_EN")
	)
	(segment
		(start 286.295592 -46.285658)
		(end 286.318706 -46.308772)
		(width 0.254)
		(layer "F.Cu")
		(net "P52V_HS1_TEMPP")
	)
	(segment
		(start 285.983172 -48.960024)
		(end 285.983172 -49.636172)
		(width 0.254)
		(layer "F.Cu")
		(net "P52V_HS1_TEMPP")
	)
	(segment
		(start 286.16656 -48.776636)
		(end 285.983172 -48.960024)
		(width 0.254)
		(layer "F.Cu")
		(net "P52V_HS1_TEMPP")
	)
	(segment
		(start 286.16656 -47.074328)
		(end 286.16656 -48.776636)
		(width 0.254)
		(layer "F.Cu")
		(net "P52V_HS1_TEMPP")
	)
	(segment
		(start 286.295592 -45.790866)
		(end 286.295592 -46.285658)
		(width 0.254)
		(layer "F.Cu")
		(net "P52V_HS1_TEMPP")
	)
	(segment
		(start 283.160724 -58.862214)
		(end 283.770324 -58.862214)
		(width 0.254)
		(layer "F.Cu")
		(net "P52V_HS1_TEMPP")
	)
	(segment
		(start 286.318706 -46.308772)
		(end 286.318706 -46.922182)
		(width 0.254)
		(layer "F.Cu")
		(net "P52V_HS1_TEMPP")
	)
	(segment
		(start 286.318706 -46.922182)
		(end 286.16656 -47.074328)
		(width 0.254)
		(layer "F.Cu")
		(net "P52V_HS1_TEMPP")
	)
	(via
		(at 285.983172 -49.636172)
		(size 0.508)
		(drill 0.254)
		(layers "F.Cu" "B.Cu")
		(net "P52V_HS1_TEMPP")
	)
	(via
		(at 283.770324 -58.862214)
		(size 0.508)
		(drill 0.254)
		(layers "F.Cu" "B.Cu")
		(net "P52V_HS1_TEMPP")
	)
	(segment
		(start 282.3718 -55.899812)
		(end 282.3718 -57.616598)
		(width 0.254)
		(layer "In2.Cu")
		(net "P52V_HS1_TEMPP")
	)
	(segment
		(start 282.848304 -58.093102)
		(end 283.16555 -58.093102)
		(width 0.254)
		(layer "In2.Cu")
		(net "P52V_HS1_TEMPP")
	)
	(segment
		(start 286.20212 -49.85512)
		(end 286.20212 -52.069492)
		(width 0.254)
		(layer "In2.Cu")
		(net "P52V_HS1_TEMPP")
	)
	(segment
		(start 283.77642 -58.35396)
		(end 283.770324 -58.862214)
		(width 0.254)
		(layer "In2.Cu")
		(net "P52V_HS1_TEMPP")
	)
	(segment
		(start 286.20212 -52.069492)
		(end 282.3718 -55.899812)
		(width 0.254)
		(layer "In2.Cu")
		(net "P52V_HS1_TEMPP")
	)
	(segment
		(start 285.983172 -49.636172)
		(end 286.20212 -49.85512)
		(width 0.254)
		(layer "In2.Cu")
		(net "P52V_HS1_TEMPP")
	)
	(segment
		(start 283.525214 -58.097166)
		(end 283.77642 -58.35396)
		(width 0.254)
		(layer "In2.Cu")
		(net "P52V_HS1_TEMPP")
	)
	(segment
		(start 283.16555 -58.093102)
		(end 283.525214 -58.097166)
		(width 0.254)
		(layer "In2.Cu")
		(net "P52V_HS1_TEMPP")
	)
	(segment
		(start 282.3718 -57.616598)
		(end 282.848304 -58.093102)
		(width 0.254)
		(layer "In2.Cu")
		(net "P52V_HS1_TEMPP")
	)
	(segment
		(start 299.180504 -114.412014)
		(end 299.688758 -114.920268)
		(width 0.254)
		(layer "F.Cu")
		(net "P52V_HS1_SENSE_N_R1")
	)
	(segment
		(start 296.8244 -122.9995)
		(end 296.8244 -121.4755)
		(width 0.4572)
		(layer "F.Cu")
		(net "P52V_HS1_SENSE_N_R1")
	)
	(segment
		(start 298.877482 -114.412014)
		(end 299.180504 -114.412014)
		(width 0.254)
		(layer "F.Cu")
		(net "P52V_HS1_SENSE_N_R1")
	)
	(segment
		(start 298.877228 -114.412268)
		(end 298.877482 -114.412014)
		(width 0.254)
		(layer "F.Cu")
		(net "P52V_HS1_SENSE_N_R1")
	)
	(segment
		(start 296.8244 -121.4755)
		(end 296.8244 -119.6975)
		(width 0.4572)
		(layer "F.Cu")
		(net "P52V_HS1_SENSE_N_R1")
	)
	(segment
		(start 296.8244 -119.6975)
		(end 295.95826 -119.6975)
		(width 0.4572)
		(layer "F.Cu")
		(net "P52V_HS1_SENSE_N_R1")
	)
	(via
		(at 295.95826 -119.6975)
		(size 0.508)
		(drill 0.254)
		(layers "F.Cu" "B.Cu")
		(net "P52V_HS1_SENSE_N_R1")
	)
	(via
		(at 299.688758 -114.920268)
		(size 0.508)
		(drill 0.254)
		(layers "F.Cu" "B.Cu")
		(net "P52V_HS1_SENSE_N_R1")
	)
	(segment
		(start 298.069254 -119.6975)
		(end 295.95826 -119.6975)
		(width 0.4572)
		(layer "B.Cu")
		(net "P52V_HS1_SENSE_N_R1")
	)
	(segment
		(start 299.74032 -118.026434)
		(end 298.069254 -119.6975)
		(width 0.4572)
		(layer "B.Cu")
		(net "P52V_HS1_SENSE_N_R1")
	)
	(segment
		(start 299.688758 -114.920268)
		(end 299.74032 -114.97183)
		(width 0.4572)
		(layer "B.Cu")
		(net "P52V_HS1_SENSE_N_R1")
	)
	(segment
		(start 299.74032 -114.97183)
		(end 299.74032 -118.026434)
		(width 0.4572)
		(layer "B.Cu")
		(net "P52V_HS1_SENSE_N_R1")
	)
	(segment
		(start 54.85003 -75.69962)
		(end 54.85003 -67.869816)
		(width 0.17272)
		(layer "B.Cu")
		(net "SMB_BRICK3_SDA")
	)
	(segment
		(start 54.88305 -76.327)
		(end 54.88305 -75.73264)
		(width 0.17272)
		(layer "B.Cu")
		(net "SMB_BRICK3_SDA")
	)
	(segment
		(start 54.88305 -75.73264)
		(end 54.85003 -75.69962)
		(width 0.17272)
		(layer "B.Cu")
		(net "SMB_BRICK3_SDA")
	)
	(via
		(at 305.809904 -116.432076)
		(size 0.508)
		(drill 0.254)
		(layers "F.Cu" "B.Cu")
		(net "P52V_1")
	)
	(via
		(at 305.025298 -75.665076)
		(size 0.508)
		(drill 0.254)
		(layers "F.Cu" "B.Cu")
		(net "P52V_1")
	)
	(via
		(at 304.285904 -116.432076)
		(size 0.508)
		(drill 0.254)
		(layers "F.Cu" "B.Cu")
		(net "P52V_1")
	)
	(via
		(at 305.809904 -114.146076)
		(size 0.508)
		(drill 0.254)
		(layers "F.Cu" "B.Cu")
		(net "P52V_1")
	)
	(via
		(at 305.047904 -117.956076)
		(size 0.508)
		(drill 0.254)
		(layers "F.Cu" "B.Cu")
		(net "P52V_1")
	)
	(via
		(at 305.787298 -77.189076)
		(size 0.508)
		(drill 0.254)
		(layers "F.Cu" "B.Cu")
		(net "P52V_1")
	)
	(via
		(at 305.787298 -80.999076)
		(size 0.508)
		(drill 0.254)
		(layers "F.Cu" "B.Cu")
		(net "P52V_1")
	)
	(via
		(at 305.047904 -114.146076)
		(size 0.508)
		(drill 0.254)
		(layers "F.Cu" "B.Cu")
		(net "P52V_1")
	)
	(via
		(at 304.285904 -117.956076)
		(size 0.508)
		(drill 0.254)
		(layers "F.Cu" "B.Cu")
		(net "P52V_1")
	)
	(via
		(at 305.809904 -111.098076)
		(size 0.508)
		(drill 0.254)
		(layers "F.Cu" "B.Cu")
		(net "P52V_1")
	)
	(via
		(at 304.285904 -117.194076)
		(size 0.508)
		(drill 0.254)
		(layers "F.Cu" "B.Cu")
		(net "P52V_1")
	)
	(via
		(at 297.561 -53.594)
		(size 0.508)
		(drill 0.254)
		(layers "F.Cu" "B.Cu")
		(net "P52V_1")
	)
	(via
		(at 304.263298 -78.713076)
		(size 0.508)
		(drill 0.254)
		(layers "F.Cu" "B.Cu")
		(net "P52V_1")
	)
	(via
		(at 304.263298 -81.761076)
		(size 0.508)
		(drill 0.254)
		(layers "F.Cu" "B.Cu")
		(net "P52V_1")
	)
	(via
		(at 304.263298 -75.665076)
		(size 0.508)
		(drill 0.254)
		(layers "F.Cu" "B.Cu")
		(net "P52V_1")
	)
	(via
		(at 305.025298 -77.951076)
		(size 0.508)
		(drill 0.254)
		(layers "F.Cu" "B.Cu")
		(net "P52V_1")
	)
	(via
		(at 305.809904 -117.194076)
		(size 0.508)
		(drill 0.254)
		(layers "F.Cu" "B.Cu")
		(net "P52V_1")
	)
	(via
		(at 304.285904 -111.098076)
		(size 0.508)
		(drill 0.254)
		(layers "F.Cu" "B.Cu")
		(net "P52V_1")
	)
	(via
		(at 304.263298 -77.189076)
		(size 0.508)
		(drill 0.254)
		(layers "F.Cu" "B.Cu")
		(net "P52V_1")
	)
	(via
		(at 305.025298 -74.903076)
		(size 0.508)
		(drill 0.254)
		(layers "F.Cu" "B.Cu")
		(net "P52V_1")
	)
	(via
		(at 305.025298 -80.237076)
		(size 0.508)
		(drill 0.254)
		(layers "F.Cu" "B.Cu")
		(net "P52V_1")
	)
	(via
		(at 305.787298 -78.713076)
		(size 0.508)
		(drill 0.254)
		(layers "F.Cu" "B.Cu")
		(net "P52V_1")
	)
	(via
		(at 305.809904 -115.670076)
		(size 0.508)
		(drill 0.254)
		(layers "F.Cu" "B.Cu")
		(net "P52V_1")
	)
	(via
		(at 305.025298 -78.713076)
		(size 0.508)
		(drill 0.254)
		(layers "F.Cu" "B.Cu")
		(net "P52V_1")
	)
	(via
		(at 305.025298 -77.189076)
		(size 0.508)
		(drill 0.254)
		(layers "F.Cu" "B.Cu")
		(net "P52V_1")
	)
	(via
		(at 304.263298 -79.475076)
		(size 0.508)
		(drill 0.254)
		(layers "F.Cu" "B.Cu")
		(net "P52V_1")
	)
	(via
		(at 297.561 -52.832)
		(size 0.508)
		(drill 0.254)
		(layers "F.Cu" "B.Cu")
		(net "P52V_1")
	)
	(via
		(at 305.809904 -111.860076)
		(size 0.508)
		(drill 0.254)
		(layers "F.Cu" "B.Cu")
		(net "P52V_1")
	)
	(via
		(at 297.561 -54.356)
		(size 0.508)
		(drill 0.254)
		(layers "F.Cu" "B.Cu")
		(net "P52V_1")
	)
	(via
		(at 305.047904 -113.384076)
		(size 0.508)
		(drill 0.254)
		(layers "F.Cu" "B.Cu")
		(net "P52V_1")
	)
	(via
		(at 304.285904 -111.860076)
		(size 0.508)
		(drill 0.254)
		(layers "F.Cu" "B.Cu")
		(net "P52V_1")
	)
	(via
		(at 304.285904 -112.622076)
		(size 0.508)
		(drill 0.254)
		(layers "F.Cu" "B.Cu")
		(net "P52V_1")
	)
	(via
		(at 302.387 -106.68)
		(size 0.762)
		(drill 0.381)
		(layers "F.Cu" "B.Cu")
		(net "P52V_1")
	)
	(via
		(at 305.047904 -114.908076)
		(size 0.508)
		(drill 0.254)
		(layers "F.Cu" "B.Cu")
		(net "P52V_1")
	)
	(via
		(at 305.025298 -80.999076)
		(size 0.508)
		(drill 0.254)
		(layers "F.Cu" "B.Cu")
		(net "P52V_1")
	)
	(via
		(at 312.42 -116.332)
		(size 0.762)
		(drill 0.381)
		(layers "F.Cu" "B.Cu")
		(net "P52V_1")
	)
	(via
		(at 305.787298 -81.761076)
		(size 0.508)
		(drill 0.254)
		(layers "F.Cu" "B.Cu")
		(net "P52V_1")
	)
	(via
		(at 305.047904 -112.622076)
		(size 0.508)
		(drill 0.254)
		(layers "F.Cu" "B.Cu")
		(net "P52V_1")
	)
	(via
		(at 298.323 -52.07)
		(size 0.508)
		(drill 0.254)
		(layers "F.Cu" "B.Cu")
		(net "P52V_1")
	)
	(via
		(at 305.047904 -117.194076)
		(size 0.508)
		(drill 0.254)
		(layers "F.Cu" "B.Cu")
		(net "P52V_1")
	)
	(via
		(at 304.285904 -115.670076)
		(size 0.508)
		(drill 0.254)
		(layers "F.Cu" "B.Cu")
		(net "P52V_1")
	)
	(via
		(at 305.809904 -117.956076)
		(size 0.508)
		(drill 0.254)
		(layers "F.Cu" "B.Cu")
		(net "P52V_1")
	)
	(via
		(at 304.263298 -80.237076)
		(size 0.508)
		(drill 0.254)
		(layers "F.Cu" "B.Cu")
		(net "P52V_1")
	)
	(via
		(at 298.323 -53.594)
		(size 0.508)
		(drill 0.254)
		(layers "F.Cu" "B.Cu")
		(net "P52V_1")
	)
	(via
		(at 304.285904 -113.384076)
		(size 0.508)
		(drill 0.254)
		(layers "F.Cu" "B.Cu")
		(net "P52V_1")
	)
	(via
		(at 298.323 -52.832)
		(size 0.508)
		(drill 0.254)
		(layers "F.Cu" "B.Cu")
		(net "P52V_1")
	)
	(via
		(at 302.006 -63.119)
		(size 0.762)
		(drill 0.381)
		(layers "F.Cu" "B.Cu")
		(net "P52V_1")
	)
	(via
		(at 316.992 -116.332)
		(size 0.762)
		(drill 0.381)
		(layers "F.Cu" "B.Cu")
		(net "P52V_1")
	)
	(via
		(at 305.787298 -79.475076)
		(size 0.508)
		(drill 0.254)
		(layers "F.Cu" "B.Cu")
		(net "P52V_1")
	)
	(via
		(at 304.263298 -77.951076)
		(size 0.508)
		(drill 0.254)
		(layers "F.Cu" "B.Cu")
		(net "P52V_1")
	)
	(via
		(at 304.263298 -80.999076)
		(size 0.508)
		(drill 0.254)
		(layers "F.Cu" "B.Cu")
		(net "P52V_1")
	)
	(via
		(at 305.809904 -112.622076)
		(size 0.508)
		(drill 0.254)
		(layers "F.Cu" "B.Cu")
		(net "P52V_1")
	)
	(via
		(at 298.323 -54.356)
		(size 0.508)
		(drill 0.254)
		(layers "F.Cu" "B.Cu")
		(net "P52V_1")
	)
	(via
		(at 305.787298 -74.903076)
		(size 0.508)
		(drill 0.254)
		(layers "F.Cu" "B.Cu")
		(net "P52V_1")
	)
	(via
		(at 297.561 -52.07)
		(size 0.508)
		(drill 0.254)
		(layers "F.Cu" "B.Cu")
		(net "P52V_1")
	)
	(via
		(at 304.263298 -74.903076)
		(size 0.508)
		(drill 0.254)
		(layers "F.Cu" "B.Cu")
		(net "P52V_1")
	)
	(via
		(at 305.047904 -111.860076)
		(size 0.508)
		(drill 0.254)
		(layers "F.Cu" "B.Cu")
		(net "P52V_1")
	)
	(via
		(at 304.263298 -76.427076)
		(size 0.508)
		(drill 0.254)
		(layers "F.Cu" "B.Cu")
		(net "P52V_1")
	)
	(via
		(at 305.047904 -116.432076)
		(size 0.508)
		(drill 0.254)
		(layers "F.Cu" "B.Cu")
		(net "P52V_1")
	)
	(via
		(at 305.787298 -80.237076)
		(size 0.508)
		(drill 0.254)
		(layers "F.Cu" "B.Cu")
		(net "P52V_1")
	)
	(via
		(at 302.387 -102.235)
		(size 0.762)
		(drill 0.381)
		(layers "F.Cu" "B.Cu")
		(net "P52V_1")
	)
	(via
		(at 305.787298 -77.951076)
		(size 0.508)
		(drill 0.254)
		(layers "F.Cu" "B.Cu")
		(net "P52V_1")
	)
	(via
		(at 305.787298 -75.665076)
		(size 0.508)
		(drill 0.254)
		(layers "F.Cu" "B.Cu")
		(net "P52V_1")
	)
	(via
		(at 305.047904 -111.098076)
		(size 0.508)
		(drill 0.254)
		(layers "F.Cu" "B.Cu")
		(net "P52V_1")
	)
	(via
		(at 302.006 -67.564)
		(size 0.762)
		(drill 0.381)
		(layers "F.Cu" "B.Cu")
		(net "P52V_1")
	)
	(via
		(at 305.787298 -76.427076)
		(size 0.508)
		(drill 0.254)
		(layers "F.Cu" "B.Cu")
		(net "P52V_1")
	)
	(via
		(at 305.809904 -113.384076)
		(size 0.508)
		(drill 0.254)
		(layers "F.Cu" "B.Cu")
		(net "P52V_1")
	)
	(via
		(at 305.025298 -76.427076)
		(size 0.508)
		(drill 0.254)
		(layers "F.Cu" "B.Cu")
		(net "P52V_1")
	)
	(via
		(at 304.285904 -114.908076)
		(size 0.508)
		(drill 0.254)
		(layers "F.Cu" "B.Cu")
		(net "P52V_1")
	)
	(via
		(at 304.285904 -114.146076)
		(size 0.508)
		(drill 0.254)
		(layers "F.Cu" "B.Cu")
		(net "P52V_1")
	)
	(via
		(at 305.047904 -115.670076)
		(size 0.508)
		(drill 0.254)
		(layers "F.Cu" "B.Cu")
		(net "P52V_1")
	)
	(via
		(at 305.025298 -81.761076)
		(size 0.508)
		(drill 0.254)
		(layers "F.Cu" "B.Cu")
		(net "P52V_1")
	)
	(via
		(at 305.809904 -114.908076)
		(size 0.508)
		(drill 0.254)
		(layers "F.Cu" "B.Cu")
		(net "P52V_1")
	)
	(via
		(at 305.025298 -79.475076)
		(size 0.508)
		(drill 0.254)
		(layers "F.Cu" "B.Cu")
		(net "P52V_1")
	)
	(segment
		(start 296.5704 -50.04816)
		(end 296.5704 -54.5846)
		(width 1.016)
		(layer "B.Cu")
		(net "P52V_1")
	)
	(via
		(at 183.896 -74.803)
		(size 0.508)
		(drill 0.254)
		(layers "F.Cu" "B.Cu")
		(net "P12V_MB2_SENSE+")
	)
	(via
		(at 181.8894 -65.020698)
		(size 0.508)
		(drill 0.254)
		(layers "F.Cu" "B.Cu")
		(net "P12V_MB2_SENSE+")
	)
	(segment
		(start 176.642522 -65.020698)
		(end 176.1744 -65.48882)
		(width 0.4572)
		(layer "B.Cu")
		(net "P12V_MB2_SENSE+")
	)
	(segment
		(start 84.49818 -65.48882)
		(end 81.28 -68.707)
		(width 0.4572)
		(layer "B.Cu")
		(net "P12V_MB2_SENSE+")
	)
	(segment
		(start 182.850282 -76.30795)
		(end 181.864 -75.321668)
		(width 0.4572)
		(layer "B.Cu")
		(net "P12V_MB2_SENSE+")
	)
	(segment
		(start 176.1744 -65.48882)
		(end 84.49818 -65.48882)
		(width 0.4572)
		(layer "B.Cu")
		(net "P12V_MB2_SENSE+")
	)
	(segment
		(start 79.73695 -77.10805)
		(end 63.881 -77.10805)
		(width 0.4572)
		(layer "B.Cu")
		(net "P12V_MB2_SENSE+")
	)
	(segment
		(start 183.896 -76.30795)
		(end 183.896 -74.803)
		(width 0.4572)
		(layer "B.Cu")
		(net "P12V_MB2_SENSE+")
	)
	(segment
		(start 181.864 -75.321668)
		(end 181.864 -68.856098)
		(width 0.4572)
		(layer "B.Cu")
		(net "P12V_MB2_SENSE+")
	)
	(segment
		(start 181.864 -68.856098)
		(end 182.850282 -67.869816)
		(width 0.4572)
		(layer "B.Cu")
		(net "P12V_MB2_SENSE+")
	)
	(segment
		(start 183.896 -76.30795)
		(end 182.850282 -76.30795)
		(width 0.4572)
		(layer "B.Cu")
		(net "P12V_MB2_SENSE+")
	)
	(segment
		(start 81.28 -68.707)
		(end 81.28 -75.565)
		(width 0.4572)
		(layer "B.Cu")
		(net "P12V_MB2_SENSE+")
	)
	(segment
		(start 181.8894 -65.020698)
		(end 176.642522 -65.020698)
		(width 0.4572)
		(layer "B.Cu")
		(net "P12V_MB2_SENSE+")
	)
	(segment
		(start 81.28 -75.565)
		(end 79.73695 -77.10805)
		(width 0.4572)
		(layer "B.Cu")
		(net "P12V_MB2_SENSE+")
	)
	(segment
		(start 183.896 -74.803)
		(end 179.856638 -70.763638)
		(width 0.381)
		(layer "In7.Cu")
		(net "P12V_MB2_SENSE+")
	)
	(segment
		(start 179.856638 -67.05346)
		(end 181.8894 -65.020698)
		(width 0.381)
		(layer "In7.Cu")
		(net "P12V_MB2_SENSE+")
	)
	(segment
		(start 179.856638 -70.763638)
		(end 179.856638 -67.05346)
		(width 0.381)
		(layer "In7.Cu")
		(net "P12V_MB2_SENSE+")
	)
	(segment
		(start 280.7208 -39.0398)
		(end 280.7208 -38.6334)
		(width 0.17272)
		(layer "F.Cu")
		(net "SMB_CM_HS1_3V3SB_DATI")
	)
	(segment
		(start 282.272486 -40.591486)
		(end 281.051 -39.37)
		(width 0.17272)
		(layer "F.Cu")
		(net "SMB_CM_HS1_3V3SB_DATI")
	)
	(segment
		(start 280.7208 -38.6334)
		(end 279.5524 -37.465)
		(width 0.17272)
		(layer "F.Cu")
		(net "SMB_CM_HS1_3V3SB_DATI")
	)
	(segment
		(start 283.595572 -40.591486)
		(end 282.272486 -40.591486)
		(width 0.17272)
		(layer "F.Cu")
		(net "SMB_CM_HS1_3V3SB_DATI")
	)
	(segment
		(start 279.5524 -37.465)
		(end 279.41905 -37.465)
		(width 0.17272)
		(layer "F.Cu")
		(net "SMB_CM_HS1_3V3SB_DATI")
	)
	(segment
		(start 281.051 -39.37)
		(end 280.7208 -39.0398)
		(width 0.17272)
		(layer "F.Cu")
		(net "SMB_CM_HS1_3V3SB_DATI")
	)
	(via
		(at 281.051 -39.37)
		(size 0.762)
		(drill 0.381)
		(layers "F.Cu" "B.Cu")
		(net "SMB_CM_HS1_3V3SB_DATI")
	)
	(segment
		(start 56.850026 -116.47805)
		(end 56.850026 -121.209816)
		(width 0.17272)
		(layer "B.Cu")
		(net "BRICK_P12V3_ON_OFF_R")
	)
	(segment
		(start 52.850034 -67.869816)
		(end 52.850034 -76.30795)
		(width 0.4572)
		(layer "B.Cu")
		(net "P12V_MB3_SENSE-")
	)
	(segment
		(start 282.575 -36.08705)
		(end 282.97505 -36.08705)
		(width 0.17272)
		(layer "F.Cu")
		(net "P52V_HS1_GPO2")
	)
	(segment
		(start 284.294072 -37.406072)
		(end 284.294072 -38.892226)
		(width 0.17272)
		(layer "F.Cu")
		(net "P52V_HS1_GPO2")
	)
	(segment
		(start 281.559 -36.08705)
		(end 282.575 -36.08705)
		(width 0.17272)
		(layer "F.Cu")
		(net "P52V_HS1_GPO2")
	)
	(segment
		(start 283.972 -37.084)
		(end 284.294072 -37.406072)
		(width 0.17272)
		(layer "F.Cu")
		(net "P52V_HS1_GPO2")
	)
	(segment
		(start 282.97505 -36.08705)
		(end 283.972 -37.084)
		(width 0.17272)
		(layer "F.Cu")
		(net "P52V_HS1_GPO2")
	)
	(via
		(at 283.972 -37.084)
		(size 0.762)
		(drill 0.381)
		(layers "F.Cu" "B.Cu")
		(net "P52V_HS1_GPO2")
	)
	(segment
		(start 286.02305 -34.19602)
		(end 286.02305 -34.537142)
		(width 0.17272)
		(layer "F.Cu")
		(net "PWRGD_P52V_HS1_PG")
	)
	(segment
		(start 285.354014 -33.526984)
		(end 286.02305 -34.19602)
		(width 0.17272)
		(layer "F.Cu")
		(net "PWRGD_P52V_HS1_PG")
	)
	(segment
		(start 286.154622 -36.209224)
		(end 286.154622 -35.306)
		(width 0.17272)
		(layer "F.Cu")
		(net "PWRGD_P52V_HS1_PG")
	)
	(segment
		(start 286.295592 -37.481764)
		(end 286.295592 -36.790122)
		(width 0.17272)
		(layer "F.Cu")
		(net "PWRGD_P52V_HS1_PG")
	)
	(segment
		(start 286.02305 -34.537142)
		(end 286.02305 -35.168078)
		(width 0.17272)
		(layer "F.Cu")
		(net "PWRGD_P52V_HS1_PG")
	)
	(segment
		(start 286.154622 -36.649152)
		(end 286.154622 -36.209224)
		(width 0.17272)
		(layer "F.Cu")
		(net "PWRGD_P52V_HS1_PG")
	)
	(segment
		(start 286.295592 -38.892226)
		(end 286.295592 -37.481764)
		(width 0.17272)
		(layer "F.Cu")
		(net "PWRGD_P52V_HS1_PG")
	)
	(segment
		(start 286.295592 -36.790122)
		(end 286.154622 -36.649152)
		(width 0.17272)
		(layer "F.Cu")
		(net "PWRGD_P52V_HS1_PG")
	)
	(segment
		(start 286.154622 -35.306)
		(end 286.02305 -35.174428)
		(width 0.17272)
		(layer "F.Cu")
		(net "PWRGD_P52V_HS1_PG")
	)
	(segment
		(start 286.02305 -35.174428)
		(end 286.02305 -35.168078)
		(width 0.17272)
		(layer "F.Cu")
		(net "PWRGD_P52V_HS1_PG")
	)
	(via
		(at 286.295592 -37.481764)
		(size 0.762)
		(drill 0.381)
		(layers "F.Cu" "B.Cu")
		(net "PWRGD_P52V_HS1_PG")
	)
	(via
		(at 178.9176 -91.0844)
		(size 0.508)
		(drill 0.254)
		(layers "F.Cu" "B.Cu")
		(net "PWRGD_P52V_HS1_PG")
	)
	(via
		(at 286.02305 -34.537142)
		(size 0.508)
		(drill 0.254)
		(layers "F.Cu" "B.Cu")
		(net "PWRGD_P52V_HS1_PG")
	)
	(segment
		(start 156.692346 -91.0844)
		(end 178.9176 -91.0844)
		(width 0.17272)
		(layer "B.Cu")
		(net "PWRGD_P52V_HS1_PG")
	)
	(segment
		(start 149.733 -114.82705)
		(end 150.057104 -114.82705)
		(width 0.17272)
		(layer "B.Cu")
		(net "PWRGD_P52V_HS1_PG")
	)
	(segment
		(start 150.057104 -114.82705)
		(end 151.003 -113.881154)
		(width 0.17272)
		(layer "B.Cu")
		(net "PWRGD_P52V_HS1_PG")
	)
	(segment
		(start 148.405088 -114.82705)
		(end 148.319998 -114.74196)
		(width 0.17272)
		(layer "B.Cu")
		(net "PWRGD_P52V_HS1_PG")
	)
	(segment
		(start 151.003 -96.773746)
		(end 156.692346 -91.0844)
		(width 0.17272)
		(layer "B.Cu")
		(net "PWRGD_P52V_HS1_PG")
	)
	(segment
		(start 149.733 -114.82705)
		(end 148.405088 -114.82705)
		(width 0.17272)
		(layer "B.Cu")
		(net "PWRGD_P52V_HS1_PG")
	)
	(segment
		(start 151.003 -113.881154)
		(end 151.003 -96.773746)
		(width 0.17272)
		(layer "B.Cu")
		(net "PWRGD_P52V_HS1_PG")
	)
	(segment
		(start 219.983812 -71.89724)
		(end 219.06865 -70.982078)
		(width 0.12954)
		(layer "In7.Cu")
		(net "PWRGD_P52V_HS1_PG")
	)
	(segment
		(start 220.70822 -53.249322)
		(end 225.986086 -47.971456)
		(width 0.12954)
		(layer "In7.Cu")
		(net "PWRGD_P52V_HS1_PG")
	)
	(segment
		(start 220.70822 -63.22187)
		(end 220.70822 -53.249322)
		(width 0.12954)
		(layer "In7.Cu")
		(net "PWRGD_P52V_HS1_PG")
	)
	(segment
		(start 219.06865 -64.86144)
		(end 220.70822 -63.22187)
		(width 0.12954)
		(layer "In7.Cu")
		(net "PWRGD_P52V_HS1_PG")
	)
	(segment
		(start 274.28571 -38.455854)
		(end 266.954 -45.787564)
		(width 0.12954)
		(layer "In7.Cu")
		(net "PWRGD_P52V_HS1_PG")
	)
	(segment
		(start 276.78126 -32.414464)
		(end 276.78126 -33.47974)
		(width 0.12954)
		(layer "In7.Cu")
		(net "PWRGD_P52V_HS1_PG")
	)
	(segment
		(start 220.74124 -71.89724)
		(end 219.983812 -71.89724)
		(width 0.12954)
		(layer "In7.Cu")
		(net "PWRGD_P52V_HS1_PG")
	)
	(segment
		(start 181.172866 -88.829134)
		(end 190.232538 -88.829134)
		(width 0.12954)
		(layer "In7.Cu")
		(net "PWRGD_P52V_HS1_PG")
	)
	(segment
		(start 266.954 -45.787564)
		(end 266.954 -49.149)
		(width 0.12954)
		(layer "In7.Cu")
		(net "PWRGD_P52V_HS1_PG")
	)
	(segment
		(start 266.954 -49.149)
		(end 267.25626 -49.45126)
		(width 0.12954)
		(layer "In7.Cu")
		(net "PWRGD_P52V_HS1_PG")
	)
	(segment
		(start 274.066 -46.101)
		(end 276.918674 -46.101)
		(width 0.12954)
		(layer "In7.Cu")
		(net "PWRGD_P52V_HS1_PG")
	)
	(segment
		(start 283.23794 -34.537142)
		(end 286.02305 -34.537142)
		(width 0.12954)
		(layer "In7.Cu")
		(net "PWRGD_P52V_HS1_PG")
	)
	(segment
		(start 273.431 -48.80864)
		(end 273.431 -46.736)
		(width 0.12954)
		(layer "In7.Cu")
		(net "PWRGD_P52V_HS1_PG")
	)
	(segment
		(start 204.69479 -81.24952)
		(end 207.04048 -81.24952)
		(width 0.12954)
		(layer "In7.Cu")
		(net "PWRGD_P52V_HS1_PG")
	)
	(segment
		(start 225.986086 -47.971456)
		(end 248.183654 -47.971456)
		(width 0.12954)
		(layer "In7.Cu")
		(net "PWRGD_P52V_HS1_PG")
	)
	(segment
		(start 272.78838 -49.45126)
		(end 273.431 -48.80864)
		(width 0.12954)
		(layer "In7.Cu")
		(net "PWRGD_P52V_HS1_PG")
	)
	(segment
		(start 196.689472 -82.3722)
		(end 198.628 -82.3722)
		(width 0.12954)
		(layer "In7.Cu")
		(net "PWRGD_P52V_HS1_PG")
	)
	(segment
		(start 207.94726 -80.34274)
		(end 224.262442 -80.34274)
		(width 0.12954)
		(layer "In7.Cu")
		(net "PWRGD_P52V_HS1_PG")
	)
	(segment
		(start 273.546316 -29.17952)
		(end 276.78126 -32.414464)
		(width 0.12954)
		(layer "In7.Cu")
		(net "PWRGD_P52V_HS1_PG")
	)
	(segment
		(start 219.06865 -70.982078)
		(end 219.06865 -64.86144)
		(width 0.12954)
		(layer "In7.Cu")
		(net "PWRGD_P52V_HS1_PG")
	)
	(segment
		(start 278.003 -47.185326)
		(end 280.914856 -47.185326)
		(width 0.12954)
		(layer "In7.Cu")
		(net "PWRGD_P52V_HS1_PG")
	)
	(segment
		(start 276.918674 -46.101)
		(end 278.003 -47.185326)
		(width 0.12954)
		(layer "In7.Cu")
		(net "PWRGD_P52V_HS1_PG")
	)
	(segment
		(start 264.224008 -29.17952)
		(end 273.546316 -29.17952)
		(width 0.12954)
		(layer "In7.Cu")
		(net "PWRGD_P52V_HS1_PG")
	)
	(segment
		(start 283.38526 -44.714922)
		(end 283.38526 -36.62426)
		(width 0.12954)
		(layer "In7.Cu")
		(net "PWRGD_P52V_HS1_PG")
	)
	(segment
		(start 282.702 -35.941)
		(end 282.702 -35.073082)
		(width 0.12954)
		(layer "In7.Cu")
		(net "PWRGD_P52V_HS1_PG")
	)
	(segment
		(start 256.63652 -36.767008)
		(end 264.224008 -29.17952)
		(width 0.12954)
		(layer "In7.Cu")
		(net "PWRGD_P52V_HS1_PG")
	)
	(segment
		(start 273.431 -46.736)
		(end 274.066 -46.101)
		(width 0.12954)
		(layer "In7.Cu")
		(net "PWRGD_P52V_HS1_PG")
	)
	(segment
		(start 224.262442 -80.34274)
		(end 224.96526 -79.639922)
		(width 0.12954)
		(layer "In7.Cu")
		(net "PWRGD_P52V_HS1_PG")
	)
	(segment
		(start 190.232538 -88.829134)
		(end 196.689472 -82.3722)
		(width 0.12954)
		(layer "In7.Cu")
		(net "PWRGD_P52V_HS1_PG")
	)
	(segment
		(start 256.63652 -39.51859)
		(end 256.63652 -36.767008)
		(width 0.12954)
		(layer "In7.Cu")
		(net "PWRGD_P52V_HS1_PG")
	)
	(segment
		(start 198.999856 -82.744056)
		(end 203.200254 -82.744056)
		(width 0.12954)
		(layer "In7.Cu")
		(net "PWRGD_P52V_HS1_PG")
	)
	(segment
		(start 198.628 -82.3722)
		(end 198.999856 -82.744056)
		(width 0.12954)
		(layer "In7.Cu")
		(net "PWRGD_P52V_HS1_PG")
	)
	(segment
		(start 224.96526 -79.639922)
		(end 224.96526 -76.12126)
		(width 0.12954)
		(layer "In7.Cu")
		(net "PWRGD_P52V_HS1_PG")
	)
	(segment
		(start 283.38526 -36.62426)
		(end 282.702 -35.941)
		(width 0.12954)
		(layer "In7.Cu")
		(net "PWRGD_P52V_HS1_PG")
	)
	(segment
		(start 224.96526 -76.12126)
		(end 220.74124 -71.89724)
		(width 0.12954)
		(layer "In7.Cu")
		(net "PWRGD_P52V_HS1_PG")
	)
	(segment
		(start 267.25626 -49.45126)
		(end 272.78838 -49.45126)
		(width 0.12954)
		(layer "In7.Cu")
		(net "PWRGD_P52V_HS1_PG")
	)
	(segment
		(start 207.04048 -81.24952)
		(end 207.94726 -80.34274)
		(width 0.12954)
		(layer "In7.Cu")
		(net "PWRGD_P52V_HS1_PG")
	)
	(segment
		(start 248.183654 -47.971456)
		(end 256.63652 -39.51859)
		(width 0.12954)
		(layer "In7.Cu")
		(net "PWRGD_P52V_HS1_PG")
	)
	(segment
		(start 276.78126 -33.47974)
		(end 274.28571 -35.97529)
		(width 0.12954)
		(layer "In7.Cu")
		(net "PWRGD_P52V_HS1_PG")
	)
	(segment
		(start 280.914856 -47.185326)
		(end 283.38526 -44.714922)
		(width 0.12954)
		(layer "In7.Cu")
		(net "PWRGD_P52V_HS1_PG")
	)
	(segment
		(start 203.200254 -82.744056)
		(end 204.69479 -81.24952)
		(width 0.12954)
		(layer "In7.Cu")
		(net "PWRGD_P52V_HS1_PG")
	)
	(segment
		(start 282.702 -35.073082)
		(end 283.23794 -34.537142)
		(width 0.12954)
		(layer "In7.Cu")
		(net "PWRGD_P52V_HS1_PG")
	)
	(segment
		(start 274.28571 -35.97529)
		(end 274.28571 -38.455854)
		(width 0.12954)
		(layer "In7.Cu")
		(net "PWRGD_P52V_HS1_PG")
	)
	(segment
		(start 178.9176 -91.0844)
		(end 181.172866 -88.829134)
		(width 0.12954)
		(layer "In7.Cu")
		(net "PWRGD_P52V_HS1_PG")
	)
	(segment
		(start 256.794 -24.892)
		(end 258.93395 -24.892)
		(width 0.17272)
		(layer "F.Cu")
		(net "SMB_P52V_VPDB_DEBUG_SDA")
	)
	(segment
		(start 56.850026 -76.134976)
		(end 56.850026 -67.869816)
		(width 0.17272)
		(layer "B.Cu")
		(net "SMB_BRICK3_ALERT")
	)
	(segment
		(start 57.04205 -76.327)
		(end 56.850026 -76.134976)
		(width 0.17272)
		(layer "B.Cu")
		(net "SMB_BRICK3_ALERT")
	)
	(segment
		(start 58.850022 -74.735436)
		(end 58.850022 -75.360276)
		(width 0.17272)
		(layer "B.Cu")
		(net "SMB_BRICK3_SCL")
	)
	(segment
		(start 60.071508 -73.174606)
		(end 59.049412 -73.174606)
		(width 0.17272)
		(layer "B.Cu")
		(net "SMB_BRICK3_SCL")
	)
	(segment
		(start 59.049412 -73.174606)
		(end 58.850022 -73.373996)
		(width 0.17272)
		(layer "B.Cu")
		(net "SMB_BRICK3_SCL")
	)
	(segment
		(start 58.850022 -67.869816)
		(end 58.850022 -70.933056)
		(width 0.17272)
		(layer "B.Cu")
		(net "SMB_BRICK3_SCL")
	)
	(segment
		(start 59.049412 -74.536046)
		(end 58.850022 -74.735436)
		(width 0.17272)
		(layer "B.Cu")
		(net "SMB_BRICK3_SCL")
	)
	(segment
		(start 58.850022 -73.373996)
		(end 58.850022 -73.655936)
		(width 0.17272)
		(layer "B.Cu")
		(net "SMB_BRICK3_SCL")
	)
	(segment
		(start 58.850022 -70.933056)
		(end 59.049412 -71.132446)
		(width 0.17272)
		(layer "B.Cu")
		(net "SMB_BRICK3_SCL")
	)
	(segment
		(start 60.071508 -74.536046)
		(end 59.049412 -74.536046)
		(width 0.17272)
		(layer "B.Cu")
		(net "SMB_BRICK3_SCL")
	)
	(segment
		(start 60.270898 -71.613776)
		(end 60.071508 -71.813166)
		(width 0.17272)
		(layer "B.Cu")
		(net "SMB_BRICK3_SCL")
	)
	(segment
		(start 60.270898 -74.336656)
		(end 60.071508 -74.536046)
		(width 0.17272)
		(layer "B.Cu")
		(net "SMB_BRICK3_SCL")
	)
	(segment
		(start 58.850022 -73.655936)
		(end 59.049412 -73.855326)
		(width 0.17272)
		(layer "B.Cu")
		(net "SMB_BRICK3_SCL")
	)
	(segment
		(start 58.850022 -75.360276)
		(end 59.32805 -75.838304)
		(width 0.17272)
		(layer "B.Cu")
		(net "SMB_BRICK3_SCL")
	)
	(segment
		(start 60.071508 -71.813166)
		(end 59.049412 -71.813166)
		(width 0.17272)
		(layer "B.Cu")
		(net "SMB_BRICK3_SCL")
	)
	(segment
		(start 59.32805 -75.838304)
		(end 59.32805 -76.327)
		(width 0.17272)
		(layer "B.Cu")
		(net "SMB_BRICK3_SCL")
	)
	(segment
		(start 58.850022 -72.012556)
		(end 58.850022 -72.294496)
		(width 0.17272)
		(layer "B.Cu")
		(net "SMB_BRICK3_SCL")
	)
	(segment
		(start 59.049412 -72.493886)
		(end 60.071508 -72.493886)
		(width 0.17272)
		(layer "B.Cu")
		(net "SMB_BRICK3_SCL")
	)
	(segment
		(start 60.071508 -72.493886)
		(end 60.270898 -72.693276)
		(width 0.17272)
		(layer "B.Cu")
		(net "SMB_BRICK3_SCL")
	)
	(segment
		(start 60.270898 -74.054716)
		(end 60.270898 -74.336656)
		(width 0.17272)
		(layer "B.Cu")
		(net "SMB_BRICK3_SCL")
	)
	(segment
		(start 60.270898 -72.693276)
		(end 60.270898 -72.975216)
		(width 0.17272)
		(layer "B.Cu")
		(net "SMB_BRICK3_SCL")
	)
	(segment
		(start 60.270898 -72.975216)
		(end 60.071508 -73.174606)
		(width 0.17272)
		(layer "B.Cu")
		(net "SMB_BRICK3_SCL")
	)
	(segment
		(start 59.049412 -71.813166)
		(end 58.850022 -72.012556)
		(width 0.17272)
		(layer "B.Cu")
		(net "SMB_BRICK3_SCL")
	)
	(segment
		(start 59.049412 -73.855326)
		(end 60.071508 -73.855326)
		(width 0.17272)
		(layer "B.Cu")
		(net "SMB_BRICK3_SCL")
	)
	(segment
		(start 59.049412 -71.132446)
		(end 60.071508 -71.132446)
		(width 0.17272)
		(layer "B.Cu")
		(net "SMB_BRICK3_SCL")
	)
	(segment
		(start 60.071508 -73.855326)
		(end 60.270898 -74.054716)
		(width 0.17272)
		(layer "B.Cu")
		(net "SMB_BRICK3_SCL")
	)
	(segment
		(start 60.270898 -71.331836)
		(end 60.270898 -71.613776)
		(width 0.17272)
		(layer "B.Cu")
		(net "SMB_BRICK3_SCL")
	)
	(segment
		(start 58.850022 -72.294496)
		(end 59.049412 -72.493886)
		(width 0.17272)
		(layer "B.Cu")
		(net "SMB_BRICK3_SCL")
	)
	(segment
		(start 60.071508 -71.132446)
		(end 60.270898 -71.331836)
		(width 0.17272)
		(layer "B.Cu")
		(net "SMB_BRICK3_SCL")
	)
	(segment
		(start 258.93395 -29.972)
		(end 256.794 -29.972)
		(width 0.17272)
		(layer "F.Cu")
		(net "SMB_P52V_VPDB_DEBUG_SCL")
	)
	(via
		(at 135.89 -75.1586)
		(size 0.6604)
		(drill 0.3302)
		(layers "F.Cu" "B.Cu")
		(net "P12V_BRICK0_ALERT_N")
	)
	(segment
		(start 136.21766 -66.98234)
		(end 135.89 -67.31)
		(width 0.17272)
		(layer "B.Cu")
		(net "P12V_BRICK0_ALERT_N")
	)
	(segment
		(start 202.16876 -72.50176)
		(end 202.16876 -70.58406)
		(width 0.17272)
		(layer "B.Cu")
		(net "P12V_BRICK0_ALERT_N")
	)
	(segment
		(start 198.849996 -68.56984)
		(end 197.262496 -66.98234)
		(width 0.17272)
		(layer "B.Cu")
		(net "P12V_BRICK0_ALERT_N")
	)
	(segment
		(start 135.89 -75.1586)
		(end 135.89 -75.83805)
		(width 0.17272)
		(layer "B.Cu")
		(net "P12V_BRICK0_ALERT_N")
	)
	(segment
		(start 135.89 -67.31)
		(end 135.89 -75.1586)
		(width 0.17272)
		(layer "B.Cu")
		(net "P12V_BRICK0_ALERT_N")
	)
	(segment
		(start 202.16876 -70.58406)
		(end 200.15454 -68.56984)
		(width 0.17272)
		(layer "B.Cu")
		(net "P12V_BRICK0_ALERT_N")
	)
	(segment
		(start 197.262496 -66.98234)
		(end 136.21766 -66.98234)
		(width 0.17272)
		(layer "B.Cu")
		(net "P12V_BRICK0_ALERT_N")
	)
	(segment
		(start 136.37895 -77.597)
		(end 136.37895 -76.327)
		(width 0.17272)
		(layer "B.Cu")
		(net "P12V_BRICK0_ALERT_N")
	)
	(segment
		(start 200.15454 -68.56984)
		(end 198.849996 -68.56984)
		(width 0.17272)
		(layer "B.Cu")
		(net "P12V_BRICK0_ALERT_N")
	)
	(segment
		(start 210.29676 -77.484986)
		(end 207.151986 -77.484986)
		(width 0.17272)
		(layer "B.Cu")
		(net "P12V_BRICK0_ALERT_N")
	)
	(segment
		(start 135.89 -75.83805)
		(end 136.37895 -76.327)
		(width 0.17272)
		(layer "B.Cu")
		(net "P12V_BRICK0_ALERT_N")
	)
	(segment
		(start 207.151986 -77.484986)
		(end 202.16876 -72.50176)
		(width 0.17272)
		(layer "B.Cu")
		(net "P12V_BRICK0_ALERT_N")
	)
	(segment
		(start 210.860894 -78.04912)
		(end 210.29676 -77.484986)
		(width 0.17272)
		(layer "B.Cu")
		(net "P12V_BRICK0_ALERT_N")
	)
	(segment
		(start 136.37895 -78.867)
		(end 136.37895 -77.597)
		(width 0.17272)
		(layer "B.Cu")
		(net "P12V_BRICK0_ALERT_N")
	)
	(segment
		(start 210.860894 -78.994)
		(end 210.860894 -78.04912)
		(width 0.17272)
		(layer "B.Cu")
		(net "P12V_BRICK0_ALERT_N")
	)
	(via
		(at 271.152874 -104.887268)
		(size 0.508)
		(drill 0.254)
		(layers "F.Cu" "B.Cu")
		(net "P52V_HS1_GATE3")
	)
	(segment
		(start 283.595572 -41.592246)
		(end 282.2194 -41.592246)
		(width 0.17272)
		(layer "F.Cu")
		(net "P52V_HS1_ADR1")
	)
	(segment
		(start 266.531852 -36.552632)
		(end 266.042648 -37.735002)
		(width 0.17272)
		(layer "F.Cu")
		(net "P52V_HS1_ADR1")
	)
	(segment
		(start 266.536424 -36.5506)
		(end 266.531852 -36.552632)
		(width 0.17272)
		(layer "F.Cu")
		(net "P52V_HS1_ADR1")
	)
	(segment
		(start 266.042648 -37.735002)
		(end 266.042648 -37.942774)
		(width 0.17272)
		(layer "F.Cu")
		(net "P52V_HS1_ADR1")
	)
	(via
		(at 266.536424 -36.5506)
		(size 0.508)
		(drill 0.254)
		(layers "F.Cu" "B.Cu")
		(net "P52V_HS1_ADR1")
	)
	(via
		(at 282.2194 -41.592246)
		(size 0.508)
		(drill 0.254)
		(layers "F.Cu" "B.Cu")
		(net "P52V_HS1_ADR1")
	)
	(segment
		(start 271.78 -47.22495)
		(end 271.17675 -47.22495)
		(width 0.17272)
		(layer "B.Cu")
		(net "P52V_HS1_ADR1")
	)
	(segment
		(start 265.44905 -38.354)
		(end 266.536424 -37.266626)
		(width 0.17272)
		(layer "B.Cu")
		(net "P52V_HS1_ADR1")
	)
	(segment
		(start 280.30805 -46.609)
		(end 281.559 -46.609)
		(width 0.17272)
		(layer "B.Cu")
		(net "P52V_HS1_ADR1")
	)
	(segment
		(start 282.9052 -41.3512)
		(end 282.460446 -41.3512)
		(width 0.17272)
		(layer "B.Cu")
		(net "P52V_HS1_ADR1")
	)
	(segment
		(start 279.907746 -47.4726)
		(end 273.278346 -47.4726)
		(width 0.17272)
		(layer "B.Cu")
		(net "P52V_HS1_ADR1")
	)
	(segment
		(start 281.559 -46.609)
		(end 283.972 -44.196)
		(width 0.17272)
		(layer "B.Cu")
		(net "P52V_HS1_ADR1")
	)
	(segment
		(start 280.30805 -47.072296)
		(end 279.907746 -47.4726)
		(width 0.17272)
		(layer "B.Cu")
		(net "P52V_HS1_ADR1")
	)
	(segment
		(start 273.030696 -47.22495)
		(end 272.669 -47.22495)
		(width 0.17272)
		(layer "B.Cu")
		(net "P52V_HS1_ADR1")
	)
	(segment
		(start 265.44905 -41.49725)
		(end 265.44905 -38.354)
		(width 0.17272)
		(layer "B.Cu")
		(net "P52V_HS1_ADR1")
	)
	(segment
		(start 283.972 -42.418)
		(end 282.9052 -41.3512)
		(width 0.17272)
		(layer "B.Cu")
		(net "P52V_HS1_ADR1")
	)
	(segment
		(start 266.536424 -37.266626)
		(end 266.536424 -36.5506)
		(width 0.17272)
		(layer "B.Cu")
		(net "P52V_HS1_ADR1")
	)
	(segment
		(start 271.78 -47.22495)
		(end 272.669 -47.22495)
		(width 0.17272)
		(layer "B.Cu")
		(net "P52V_HS1_ADR1")
	)
	(segment
		(start 282.460446 -41.3512)
		(end 282.2194 -41.592246)
		(width 0.17272)
		(layer "B.Cu")
		(net "P52V_HS1_ADR1")
	)
	(segment
		(start 280.30805 -46.609)
		(end 280.30805 -47.072296)
		(width 0.17272)
		(layer "B.Cu")
		(net "P52V_HS1_ADR1")
	)
	(segment
		(start 273.278346 -47.4726)
		(end 273.030696 -47.22495)
		(width 0.17272)
		(layer "B.Cu")
		(net "P52V_HS1_ADR1")
	)
	(segment
		(start 271.17675 -47.22495)
		(end 265.44905 -41.49725)
		(width 0.17272)
		(layer "B.Cu")
		(net "P52V_HS1_ADR1")
	)
	(segment
		(start 283.972 -44.196)
		(end 283.972 -42.418)
		(width 0.17272)
		(layer "B.Cu")
		(net "P52V_HS1_ADR1")
	)
	(via
		(at 236.241844 -69.338444)
		(size 0.6604)
		(drill 0.3302)
		(layers "F.Cu" "B.Cu")
		(net "RST_SMB_PDB_R_N")
	)
	(segment
		(start 236.347 -71.22795)
		(end 236.347 -72.49795)
		(width 0.17272)
		(layer "B.Cu")
		(net "RST_SMB_PDB_R_N")
	)
	(segment
		(start 215.011 -41.402)
		(end 220.218 -46.609)
		(width 0.17272)
		(layer "B.Cu")
		(net "RST_SMB_PDB_R_N")
	)
	(segment
		(start 220.218 -46.609)
		(end 220.218 -61.488066)
		(width 0.17272)
		(layer "B.Cu")
		(net "RST_SMB_PDB_R_N")
	)
	(segment
		(start 210.185 -36.694618)
		(end 210.185 -38.989)
		(width 0.17272)
		(layer "B.Cu")
		(net "RST_SMB_PDB_R_N")
	)
	(segment
		(start 211.469986 -35.409632)
		(end 210.185 -36.694618)
		(width 0.17272)
		(layer "B.Cu")
		(net "RST_SMB_PDB_R_N")
	)
	(segment
		(start 212.598 -41.402)
		(end 215.011 -41.402)
		(width 0.17272)
		(layer "B.Cu")
		(net "RST_SMB_PDB_R_N")
	)
	(segment
		(start 220.218 -61.488066)
		(end 225.674174 -66.94424)
		(width 0.17272)
		(layer "B.Cu")
		(net "RST_SMB_PDB_R_N")
	)
	(segment
		(start 225.674174 -66.94424)
		(end 233.84764 -66.94424)
		(width 0.17272)
		(layer "B.Cu")
		(net "RST_SMB_PDB_R_N")
	)
	(segment
		(start 236.982 -70.59295)
		(end 236.347 -71.22795)
		(width 0.17272)
		(layer "B.Cu")
		(net "RST_SMB_PDB_R_N")
	)
	(segment
		(start 233.84764 -66.94424)
		(end 236.241844 -69.338444)
		(width 0.17272)
		(layer "B.Cu")
		(net "RST_SMB_PDB_R_N")
	)
	(segment
		(start 236.241844 -69.338444)
		(end 236.982 -70.0786)
		(width 0.17272)
		(layer "B.Cu")
		(net "RST_SMB_PDB_R_N")
	)
	(segment
		(start 210.185 -38.989)
		(end 212.598 -41.402)
		(width 0.17272)
		(layer "B.Cu")
		(net "RST_SMB_PDB_R_N")
	)
	(segment
		(start 236.982 -70.0786)
		(end 236.982 -70.59295)
		(width 0.17272)
		(layer "B.Cu")
		(net "RST_SMB_PDB_R_N")
	)
	(segment
		(start 236.347 -72.49795)
		(end 236.982 -73.13295)
		(width 0.17272)
		(layer "B.Cu")
		(net "RST_SMB_PDB_R_N")
	)
	(segment
		(start 294.1828 -34.871914)
		(end 292.757098 -33.446212)
		(width 0.17272)
		(layer "F.Cu")
		(net "P52V_HS1_DV_DT_R")
	)
	(segment
		(start 294.1828 -34.9758)
		(end 294.1828 -34.871914)
		(width 0.17272)
		(layer "F.Cu")
		(net "P52V_HS1_DV_DT_R")
	)
	(segment
		(start 291.494972 -42.092626)
		(end 292.806374 -42.092626)
		(width 0.17272)
		(layer "F.Cu")
		(net "P52V_HS1_DV_DT_R")
	)
	(via
		(at 294.1828 -34.9758)
		(size 0.508)
		(drill 0.254)
		(layers "F.Cu" "B.Cu")
		(net "P52V_HS1_DV_DT_R")
	)
	(via
		(at 292.806374 -42.092626)
		(size 0.508)
		(drill 0.254)
		(layers "F.Cu" "B.Cu")
		(net "P52V_HS1_DV_DT_R")
	)
	(segment
		(start 294.1828 -34.9758)
		(end 294.320976 -35.113976)
		(width 0.254)
		(layer "B.Cu")
		(net "P52V_HS1_DV_DT_R")
	)
	(segment
		(start 294.320976 -35.113976)
		(end 294.320976 -40.578024)
		(width 0.254)
		(layer "B.Cu")
		(net "P52V_HS1_DV_DT_R")
	)
	(segment
		(start 294.320976 -40.578024)
		(end 292.806374 -42.092626)
		(width 0.254)
		(layer "B.Cu")
		(net "P52V_HS1_DV_DT_R")
	)
	(segment
		(start 287.767014 -33.526984)
		(end 287.05175 -34.242248)
		(width 0.17272)
		(layer "F.Cu")
		(net "P52V_HS1_PWRGIN")
	)
	(segment
		(start 286.954722 -36.209224)
		(end 286.954722 -37.90315)
		(width 0.17272)
		(layer "F.Cu")
		(net "P52V_HS1_PWRGIN")
	)
	(segment
		(start 286.954722 -37.90315)
		(end 286.795972 -38.0619)
		(width 0.17272)
		(layer "F.Cu")
		(net "P52V_HS1_PWRGIN")
	)
	(segment
		(start 286.954722 -35.265106)
		(end 287.05175 -35.168078)
		(width 0.17272)
		(layer "F.Cu")
		(net "P52V_HS1_PWRGIN")
	)
	(segment
		(start 286.954722 -36.209224)
		(end 286.954722 -35.265106)
		(width 0.17272)
		(layer "F.Cu")
		(net "P52V_HS1_PWRGIN")
	)
	(segment
		(start 286.795972 -38.0619)
		(end 286.795972 -38.892226)
		(width 0.17272)
		(layer "F.Cu")
		(net "P52V_HS1_PWRGIN")
	)
	(segment
		(start 287.05175 -34.52876)
		(end 287.05175 -35.168078)
		(width 0.17272)
		(layer "F.Cu")
		(net "P52V_HS1_PWRGIN")
	)
	(segment
		(start 287.05175 -34.242248)
		(end 287.05175 -34.52876)
		(width 0.17272)
		(layer "F.Cu")
		(net "P52V_HS1_PWRGIN")
	)
	(via
		(at 287.05175 -34.52876)
		(size 0.508)
		(drill 0.254)
		(layers "F.Cu" "B.Cu")
		(net "P52V_HS1_PWRGIN")
	)
	(segment
		(start 262.763 -37.338)
		(end 263.042654 -37.617654)
		(width 0.17272)
		(layer "F.Cu")
		(net "P52V_HS1_UVLO_EN")
	)
	(segment
		(start 284.226 -47.498254)
		(end 285.294832 -46.429422)
		(width 0.17272)
		(layer "F.Cu")
		(net "P52V_HS1_UVLO_EN")
	)
	(segment
		(start 263.042654 -37.617654)
		(end 263.042654 -37.942774)
		(width 0.17272)
		(layer "F.Cu")
		(net "P52V_HS1_UVLO_EN")
	)
	(segment
		(start 284.226 -48.133)
		(end 284.226 -47.498254)
		(width 0.17272)
		(layer "F.Cu")
		(net "P52V_HS1_UVLO_EN")
	)
	(segment
		(start 262.763 -36.83)
		(end 262.763 -37.338)
		(width 0.17272)
		(layer "F.Cu")
		(net "P52V_HS1_UVLO_EN")
	)
	(segment
		(start 285.294832 -46.429422)
		(end 285.294832 -45.790866)
		(width 0.17272)
		(layer "F.Cu")
		(net "P52V_HS1_UVLO_EN")
	)
	(via
		(at 284.226 -48.133)
		(size 0.508)
		(drill 0.254)
		(layers "F.Cu" "B.Cu")
		(net "P52V_HS1_UVLO_EN")
	)
	(via
		(at 262.763 -36.83)
		(size 0.508)
		(drill 0.254)
		(layers "F.Cu" "B.Cu")
		(net "P52V_HS1_UVLO_EN")
	)
	(segment
		(start 275.133562 -48.93183)
		(end 272.909792 -51.1556)
		(width 0.17272)
		(layer "B.Cu")
		(net "P52V_HS1_UVLO_EN")
	)
	(segment
		(start 268.0716 -51.1556)
		(end 265.684 -48.768)
		(width 0.17272)
		(layer "B.Cu")
		(net "P52V_HS1_UVLO_EN")
	)
	(segment
		(start 289.70605 -50.927)
		(end 289.70605 -49.911)
		(width 0.17272)
		(layer "B.Cu")
		(net "P52V_HS1_UVLO_EN")
	)
	(segment
		(start 272.909792 -51.1556)
		(end 268.0716 -51.1556)
		(width 0.17272)
		(layer "B.Cu")
		(net "P52V_HS1_UVLO_EN")
	)
	(segment
		(start 289.18789 -48.914558)
		(end 289.70605 -49.432718)
		(width 0.17272)
		(layer "B.Cu")
		(net "P52V_HS1_UVLO_EN")
	)
	(segment
		(start 284.226 -48.133)
		(end 283.42717 -48.93183)
		(width 0.17272)
		(layer "B.Cu")
		(net "P52V_HS1_UVLO_EN")
	)
	(segment
		(start 265.684 -48.768)
		(end 265.684 -45.212)
		(width 0.17272)
		(layer "B.Cu")
		(net "P52V_HS1_UVLO_EN")
	)
	(segment
		(start 265.684 -45.212)
		(end 262.763 -42.291)
		(width 0.17272)
		(layer "B.Cu")
		(net "P52V_HS1_UVLO_EN")
	)
	(segment
		(start 284.226 -48.133)
		(end 285.007558 -48.914558)
		(width 0.17272)
		(layer "B.Cu")
		(net "P52V_HS1_UVLO_EN")
	)
	(segment
		(start 289.687 -50.94605)
		(end 289.70605 -50.927)
		(width 0.17272)
		(layer "B.Cu")
		(net "P52V_HS1_UVLO_EN")
	)
	(segment
		(start 289.687 -52.39004)
		(end 289.687 -50.94605)
		(width 0.17272)
		(layer "B.Cu")
		(net "P52V_HS1_UVLO_EN")
	)
	(segment
		(start 262.763 -42.291)
		(end 262.763 -36.83)
		(width 0.17272)
		(layer "B.Cu")
		(net "P52V_HS1_UVLO_EN")
	)
	(segment
		(start 283.42717 -48.93183)
		(end 275.133562 -48.93183)
		(width 0.17272)
		(layer "B.Cu")
		(net "P52V_HS1_UVLO_EN")
	)
	(segment
		(start 289.70605 -49.432718)
		(end 289.70605 -49.911)
		(width 0.17272)
		(layer "B.Cu")
		(net "P52V_HS1_UVLO_EN")
	)
	(segment
		(start 285.007558 -48.914558)
		(end 289.18789 -48.914558)
		(width 0.17272)
		(layer "B.Cu")
		(net "P52V_HS1_UVLO_EN")
	)
	(via
		(at 270.002 -123.571)
		(size 0.508)
		(drill 0.254)
		(layers "F.Cu" "B.Cu")
		(net "P52V_HS")
	)
	(via
		(at 270.002 -122.809)
		(size 0.508)
		(drill 0.254)
		(layers "F.Cu" "B.Cu")
		(net "P52V_HS")
	)
	(via
		(at 269.24 -85.852)
		(size 0.508)
		(drill 0.254)
		(layers "F.Cu" "B.Cu")
		(net "P52V_HS")
	)
	(via
		(at 41.656 -106.8324)
		(size 0.508)
		(drill 0.254)
		(layers "F.Cu" "B.Cu")
		(net "P52V_HS")
	)
	(via
		(at 218.272868 -105.134664)
		(size 0.508)
		(drill 0.254)
		(layers "F.Cu" "B.Cu")
		(net "P52V_HS")
	)
	(via
		(at 221.320868 -105.896664)
		(size 0.508)
		(drill 0.254)
		(layers "F.Cu" "B.Cu")
		(net "P52V_HS")
	)
	(via
		(at 287.401 -30.687264)
		(size 0.508)
		(drill 0.254)
		(layers "F.Cu" "B.Cu")
		(net "P52V_HS")
	)
	(via
		(at 233.817668 -129.586736)
		(size 0.508)
		(drill 0.254)
		(layers "F.Cu" "B.Cu")
		(net "P52V_HS")
	)
	(via
		(at 271.526 -74.549)
		(size 0.508)
		(drill 0.254)
		(layers "F.Cu" "B.Cu")
		(net "P52V_HS")
	)
	(via
		(at 219.796868 -103.6701)
		(size 0.508)
		(drill 0.254)
		(layers "F.Cu" "B.Cu")
		(net "P52V_HS")
	)
	(via
		(at 272.288 -122.809)
		(size 0.508)
		(drill 0.254)
		(layers "F.Cu" "B.Cu")
		(net "P52V_HS")
	)
	(via
		(at 239.076738 -98.012758)
		(size 0.508)
		(drill 0.254)
		(layers "F.Cu" "B.Cu")
		(net "P52V_HS")
	)
	(via
		(at 269.24 -100.965)
		(size 0.508)
		(drill 0.254)
		(layers "F.Cu" "B.Cu")
		(net "P52V_HS")
	)
	(via
		(at 270.002 -113.03)
		(size 0.508)
		(drill 0.254)
		(layers "F.Cu" "B.Cu")
		(net "P52V_HS")
	)
	(via
		(at 270.764 -97.917)
		(size 0.508)
		(drill 0.254)
		(layers "F.Cu" "B.Cu")
		(net "P52V_HS")
	)
	(via
		(at 271.526 -109.982)
		(size 0.508)
		(drill 0.254)
		(layers "F.Cu" "B.Cu")
		(net "P52V_HS")
	)
	(via
		(at 286.004 -30.687264)
		(size 0.508)
		(drill 0.254)
		(layers "F.Cu" "B.Cu")
		(net "P52V_HS")
	)
	(via
		(at 269.24 -113.03)
		(size 0.508)
		(drill 0.254)
		(layers "F.Cu" "B.Cu")
		(net "P52V_HS")
	)
	(via
		(at 206.076042 -105.134664)
		(size 0.508)
		(drill 0.254)
		(layers "F.Cu" "B.Cu")
		(net "P52V_HS")
	)
	(via
		(at 221.320868 -102.9081)
		(size 0.508)
		(drill 0.254)
		(layers "F.Cu" "B.Cu")
		(net "P52V_HS")
	)
	(via
		(at 142.748 -112.268)
		(size 0.508)
		(drill 0.254)
		(layers "F.Cu" "B.Cu")
		(net "P52V_HS")
	)
	(via
		(at 269.24 -76.073)
		(size 0.508)
		(drill 0.254)
		(layers "F.Cu" "B.Cu")
		(net "P52V_HS")
	)
	(via
		(at 269.24 -65.532)
		(size 0.508)
		(drill 0.254)
		(layers "F.Cu" "B.Cu")
		(net "P52V_HS")
	)
	(via
		(at 270.002 -64.008)
		(size 0.508)
		(drill 0.254)
		(layers "F.Cu" "B.Cu")
		(net "P52V_HS")
	)
	(via
		(at 231.591104 -128.824736)
		(size 0.508)
		(drill 0.254)
		(layers "F.Cu" "B.Cu")
		(net "P52V_HS")
	)
	(via
		(at 220.558868 -104.4321)
		(size 0.508)
		(drill 0.254)
		(layers "F.Cu" "B.Cu")
		(net "P52V_HS")
	)
	(via
		(at 272.288 -86.614)
		(size 0.508)
		(drill 0.254)
		(layers "F.Cu" "B.Cu")
		(net "P52V_HS")
	)
	(via
		(at 40.767 -105.283)
		(size 0.508)
		(drill 0.254)
		(layers "F.Cu" "B.Cu")
		(net "P52V_HS")
	)
	(via
		(at 218.272868 -105.896664)
		(size 0.508)
		(drill 0.254)
		(layers "F.Cu" "B.Cu")
		(net "P52V_HS")
	)
	(via
		(at 270.764 -85.852)
		(size 0.508)
		(drill 0.254)
		(layers "F.Cu" "B.Cu")
		(net "P52V_HS")
	)
	(via
		(at 219.034868 -104.4321)
		(size 0.508)
		(drill 0.254)
		(layers "F.Cu" "B.Cu")
		(net "P52V_HS")
	)
	(via
		(at 203.028042 -105.134664)
		(size 0.508)
		(drill 0.254)
		(layers "F.Cu" "B.Cu")
		(net "P52V_HS")
	)
	(via
		(at 219.034868 -105.896664)
		(size 0.508)
		(drill 0.254)
		(layers "F.Cu" "B.Cu")
		(net "P52V_HS")
	)
	(via
		(at 206.838042 -105.896664)
		(size 0.508)
		(drill 0.254)
		(layers "F.Cu" "B.Cu")
		(net "P52V_HS")
	)
	(via
		(at 41.6052 -107.6198)
		(size 0.508)
		(drill 0.254)
		(layers "F.Cu" "B.Cu")
		(net "P52V_HS")
	)
	(via
		(at 270.764 -62.484)
		(size 0.508)
		(drill 0.254)
		(layers "F.Cu" "B.Cu")
		(net "P52V_HS")
	)
	(via
		(at 270.002 -85.852)
		(size 0.508)
		(drill 0.254)
		(layers "F.Cu" "B.Cu")
		(net "P52V_HS")
	)
	(via
		(at 232.353104 -130.348736)
		(size 0.508)
		(drill 0.254)
		(layers "F.Cu" "B.Cu")
		(net "P52V_HS")
	)
	(via
		(at 233.055668 -130.348736)
		(size 0.508)
		(drill 0.254)
		(layers "F.Cu" "B.Cu")
		(net "P52V_HS")
	)
	(via
		(at 272.288 -125.857)
		(size 0.508)
		(drill 0.254)
		(layers "F.Cu" "B.Cu")
		(net "P52V_HS")
	)
	(via
		(at 207.556862 -105.120948)
		(size 0.508)
		(drill 0.254)
		(layers "F.Cu" "B.Cu")
		(net "P52V_HS")
	)
	(via
		(at 217.510868 -105.896664)
		(size 0.508)
		(drill 0.254)
		(layers "F.Cu" "B.Cu")
		(net "P52V_HS")
	)
	(via
		(at 231.60482 -131.829556)
		(size 0.508)
		(drill 0.254)
		(layers "F.Cu" "B.Cu")
		(net "P52V_HS")
	)
	(via
		(at 205.314042 -105.134664)
		(size 0.508)
		(drill 0.254)
		(layers "F.Cu" "B.Cu")
		(net "P52V_HS")
	)
	(via
		(at 272.288 -65.532)
		(size 0.508)
		(drill 0.254)
		(layers "F.Cu" "B.Cu")
		(net "P52V_HS")
	)
	(via
		(at 270.764 -110.744)
		(size 0.508)
		(drill 0.254)
		(layers "F.Cu" "B.Cu")
		(net "P52V_HS")
	)
	(via
		(at 220.609668 -97.985834)
		(size 0.508)
		(drill 0.254)
		(layers "F.Cu" "B.Cu")
		(net "P52V_HS")
	)
	(via
		(at 270.002 -109.982)
		(size 0.508)
		(drill 0.254)
		(layers "F.Cu" "B.Cu")
		(net "P52V_HS")
	)
	(via
		(at 269.24 -123.571)
		(size 0.508)
		(drill 0.254)
		(layers "F.Cu" "B.Cu")
		(net "P52V_HS")
	)
	(via
		(at 269.24 -62.484)
		(size 0.508)
		(drill 0.254)
		(layers "F.Cu" "B.Cu")
		(net "P52V_HS")
	)
	(via
		(at 269.24 -124.333)
		(size 0.508)
		(drill 0.254)
		(layers "F.Cu" "B.Cu")
		(net "P52V_HS")
	)
	(via
		(at 270.764 -125.095)
		(size 0.508)
		(drill 0.254)
		(layers "F.Cu" "B.Cu")
		(net "P52V_HS")
	)
	(via
		(at 271.526 -101.727)
		(size 0.508)
		(drill 0.254)
		(layers "F.Cu" "B.Cu")
		(net "P52V_HS")
	)
	(via
		(at 222.039688 -105.120948)
		(size 0.508)
		(drill 0.254)
		(layers "F.Cu" "B.Cu")
		(net "P52V_HS")
	)
	(via
		(at 271.526 -61.722)
		(size 0.508)
		(drill 0.254)
		(layers "F.Cu" "B.Cu")
		(net "P52V_HS")
	)
	(via
		(at 235.065316 -97.985834)
		(size 0.508)
		(drill 0.254)
		(layers "F.Cu" "B.Cu")
		(net "P52V_HS")
	)
	(via
		(at 270.002 -76.835)
		(size 0.508)
		(drill 0.254)
		(layers "F.Cu" "B.Cu")
		(net "P52V_HS")
	)
	(via
		(at 270.891 -138.176)
		(size 0.508)
		(drill 0.254)
		(layers "F.Cu" "B.Cu")
		(net "P52V_HS")
	)
	(via
		(at 234.59313 -126.609094)
		(size 0.508)
		(drill 0.254)
		(layers "F.Cu" "B.Cu")
		(net "P52V_HS")
	)
	(via
		(at 40.767 -106.807)
		(size 0.508)
		(drill 0.254)
		(layers "F.Cu" "B.Cu")
		(net "P52V_HS")
	)
	(via
		(at 219.796868 -105.896664)
		(size 0.508)
		(drill 0.254)
		(layers "F.Cu" "B.Cu")
		(net "P52V_HS")
	)
	(via
		(at 203.028042 -105.896664)
		(size 0.508)
		(drill 0.254)
		(layers "F.Cu" "B.Cu")
		(net "P52V_HS")
	)
	(via
		(at 216.819226 -102.894638)
		(size 0.508)
		(drill 0.254)
		(layers "F.Cu" "B.Cu")
		(net "P52V_HS")
	)
	(via
		(at 227.607114 -97.985834)
		(size 0.508)
		(drill 0.254)
		(layers "F.Cu" "B.Cu")
		(net "P52V_HS")
	)
	(via
		(at 229.530148 -98.012758)
		(size 0.508)
		(drill 0.254)
		(layers "F.Cu" "B.Cu")
		(net "P52V_HS")
	)
	(via
		(at 270.002 -89.662)
		(size 0.508)
		(drill 0.254)
		(layers "F.Cu" "B.Cu")
		(net "P52V_HS")
	)
	(via
		(at 272.288 -88.9)
		(size 0.508)
		(drill 0.254)
		(layers "F.Cu" "B.Cu")
		(net "P52V_HS")
	)
	(via
		(at 41.656 -105.3084)
		(size 0.508)
		(drill 0.254)
		(layers "F.Cu" "B.Cu")
		(net "P52V_HS")
	)
	(via
		(at 276.225 -50.292)
		(size 0.508)
		(drill 0.254)
		(layers "F.Cu" "B.Cu")
		(net "P52V_HS")
	)
	(via
		(at 270.764 -113.03)
		(size 0.508)
		(drill 0.254)
		(layers "F.Cu" "B.Cu")
		(net "P52V_HS")
	)
	(via
		(at 207.556862 -104.418384)
		(size 0.508)
		(drill 0.254)
		(layers "F.Cu" "B.Cu")
		(net "P52V_HS")
	)
	(via
		(at 270.891 -136.652)
		(size 0.508)
		(drill 0.254)
		(layers "F.Cu" "B.Cu")
		(net "P52V_HS")
	)
	(via
		(at 270.764 -63.246)
		(size 0.508)
		(drill 0.254)
		(layers "F.Cu" "B.Cu")
		(net "P52V_HS")
	)
	(via
		(at 221.320868 -105.134664)
		(size 0.508)
		(drill 0.254)
		(layers "F.Cu" "B.Cu")
		(net "P52V_HS")
	)
	(via
		(at 218.272868 -103.6701)
		(size 0.508)
		(drill 0.254)
		(layers "F.Cu" "B.Cu")
		(net "P52V_HS")
	)
	(via
		(at 233.817668 -128.062736)
		(size 0.508)
		(drill 0.254)
		(layers "F.Cu" "B.Cu")
		(net "P52V_HS")
	)
	(via
		(at 218.272868 -104.4321)
		(size 0.508)
		(drill 0.254)
		(layers "F.Cu" "B.Cu")
		(net "P52V_HS")
	)
	(via
		(at 270.002 -99.441)
		(size 0.508)
		(drill 0.254)
		(layers "F.Cu" "B.Cu")
		(net "P52V_HS")
	)
	(via
		(at 143.383 -112.268)
		(size 0.508)
		(drill 0.254)
		(layers "F.Cu" "B.Cu")
		(net "P52V_HS")
	)
	(via
		(at 270.002 -76.073)
		(size 0.508)
		(drill 0.254)
		(layers "F.Cu" "B.Cu")
		(net "P52V_HS")
	)
	(via
		(at 219.847668 -97.985834)
		(size 0.508)
		(drill 0.254)
		(layers "F.Cu" "B.Cu")
		(net "P52V_HS")
	)
	(via
		(at 202.3364 -104.418638)
		(size 0.508)
		(drill 0.254)
		(layers "F.Cu" "B.Cu")
		(net "P52V_HS")
	)
	(via
		(at 258.219956 -47.565818)
		(size 0.508)
		(drill 0.254)
		(layers "F.Cu" "B.Cu")
		(net "P52V_HS")
	)
	(via
		(at 270.764 -101.727)
		(size 0.508)
		(drill 0.254)
		(layers "F.Cu" "B.Cu")
		(net "P52V_HS")
	)
	(via
		(at 270.764 -76.073)
		(size 0.508)
		(drill 0.254)
		(layers "F.Cu" "B.Cu")
		(net "P52V_HS")
	)
	(via
		(at 271.653 -140.462)
		(size 0.508)
		(drill 0.254)
		(layers "F.Cu" "B.Cu")
		(net "P52V_HS")
	)
	(via
		(at 269.24 -99.441)
		(size 0.508)
		(drill 0.254)
		(layers "F.Cu" "B.Cu")
		(net "P52V_HS")
	)
	(via
		(at 270.002 -88.138)
		(size 0.508)
		(drill 0.254)
		(layers "F.Cu" "B.Cu")
		(net "P52V_HS")
	)
	(via
		(at 271.526 -122.047)
		(size 0.508)
		(drill 0.254)
		(layers "F.Cu" "B.Cu")
		(net "P52V_HS")
	)
	(via
		(at 270.764 -88.9)
		(size 0.508)
		(drill 0.254)
		(layers "F.Cu" "B.Cu")
		(net "P52V_HS")
	)
	(via
		(at 221.320868 -104.4321)
		(size 0.508)
		(drill 0.254)
		(layers "F.Cu" "B.Cu")
		(net "P52V_HS")
	)
	(via
		(at 270.002 -124.333)
		(size 0.508)
		(drill 0.254)
		(layers "F.Cu" "B.Cu")
		(net "P52V_HS")
	)
	(via
		(at 269.24 -122.047)
		(size 0.508)
		(drill 0.254)
		(layers "F.Cu" "B.Cu")
		(net "P52V_HS")
	)
	(via
		(at 269.24 -125.095)
		(size 0.508)
		(drill 0.254)
		(layers "F.Cu" "B.Cu")
		(net "P52V_HS")
	)
	(via
		(at 270.764 -65.532)
		(size 0.508)
		(drill 0.254)
		(layers "F.Cu" "B.Cu")
		(net "P52V_HS")
	)
	(via
		(at 204.552042 -104.4321)
		(size 0.508)
		(drill 0.254)
		(layers "F.Cu" "B.Cu")
		(net "P52V_HS")
	)
	(via
		(at 203.028042 -104.4321)
		(size 0.508)
		(drill 0.254)
		(layers "F.Cu" "B.Cu")
		(net "P52V_HS")
	)
	(via
		(at 39.878 -106.045)
		(size 0.508)
		(drill 0.254)
		(layers "F.Cu" "B.Cu")
		(net "P52V_HS")
	)
	(via
		(at 271.526 -113.792)
		(size 0.508)
		(drill 0.254)
		(layers "F.Cu" "B.Cu")
		(net "P52V_HS")
	)
	(via
		(at 270.002 -125.857)
		(size 0.508)
		(drill 0.254)
		(layers "F.Cu" "B.Cu")
		(net "P52V_HS")
	)
	(via
		(at 219.796868 -105.134664)
		(size 0.508)
		(drill 0.254)
		(layers "F.Cu" "B.Cu")
		(net "P52V_HS")
	)
	(via
		(at 270.764 -125.857)
		(size 0.508)
		(drill 0.254)
		(layers "F.Cu" "B.Cu")
		(net "P52V_HS")
	)
	(via
		(at 294.6908 -44.699428)
		(size 0.508)
		(drill 0.254)
		(layers "F.Cu" "B.Cu")
		(net "P52V_HS")
	)
	(via
		(at 285.242 -30.687264)
		(size 0.508)
		(drill 0.254)
		(layers "F.Cu" "B.Cu")
		(net "P52V_HS")
	)
	(via
		(at 270.764 -73.787)
		(size 0.508)
		(drill 0.254)
		(layers "F.Cu" "B.Cu")
		(net "P52V_HS")
	)
	(via
		(at 269.24 -89.662)
		(size 0.508)
		(drill 0.254)
		(layers "F.Cu" "B.Cu")
		(net "P52V_HS")
	)
	(via
		(at 231.591104 -127.300736)
		(size 0.508)
		(drill 0.254)
		(layers "F.Cu" "B.Cu")
		(net "P52V_HS")
	)
	(via
		(at 234.579668 -130.348736)
		(size 0.508)
		(drill 0.254)
		(layers "F.Cu" "B.Cu")
		(net "P52V_HS")
	)
	(via
		(at 203.790042 -104.4321)
		(size 0.508)
		(drill 0.254)
		(layers "F.Cu" "B.Cu")
		(net "P52V_HS")
	)
	(via
		(at 233.817668 -127.300736)
		(size 0.508)
		(drill 0.254)
		(layers "F.Cu" "B.Cu")
		(net "P52V_HS")
	)
	(via
		(at 230.292148 -98.012758)
		(size 0.508)
		(drill 0.254)
		(layers "F.Cu" "B.Cu")
		(net "P52V_HS")
	)
	(via
		(at 233.055668 -129.586736)
		(size 0.508)
		(drill 0.254)
		(layers "F.Cu" "B.Cu")
		(net "P52V_HS")
	)
	(via
		(at 204.552042 -103.6701)
		(size 0.508)
		(drill 0.254)
		(layers "F.Cu" "B.Cu")
		(net "P52V_HS")
	)
	(via
		(at 236.554518 -97.985834)
		(size 0.508)
		(drill 0.254)
		(layers "F.Cu" "B.Cu")
		(net "P52V_HS")
	)
	(via
		(at 270.764 -61.722)
		(size 0.508)
		(drill 0.254)
		(layers "F.Cu" "B.Cu")
		(net "P52V_HS")
	)
	(via
		(at 233.055668 -128.062736)
		(size 0.508)
		(drill 0.254)
		(layers "F.Cu" "B.Cu")
		(net "P52V_HS")
	)
	(via
		(at 205.314042 -102.9081)
		(size 0.508)
		(drill 0.254)
		(layers "F.Cu" "B.Cu")
		(net "P52V_HS")
	)
	(via
		(at 271.526 -100.965)
		(size 0.508)
		(drill 0.254)
		(layers "F.Cu" "B.Cu")
		(net "P52V_HS")
	)
	(via
		(at 232.36682 -131.829556)
		(size 0.508)
		(drill 0.254)
		(layers "F.Cu" "B.Cu")
		(net "P52V_HS")
	)
	(via
		(at 270.002 -98.679)
		(size 0.508)
		(drill 0.254)
		(layers "F.Cu" "B.Cu")
		(net "P52V_HS")
	)
	(via
		(at 272.288 -122.047)
		(size 0.508)
		(drill 0.254)
		(layers "F.Cu" "B.Cu")
		(net "P52V_HS")
	)
	(via
		(at 270.002 -110.744)
		(size 0.508)
		(drill 0.254)
		(layers "F.Cu" "B.Cu")
		(net "P52V_HS")
	)
	(via
		(at 233.831384 -131.829556)
		(size 0.508)
		(drill 0.254)
		(layers "F.Cu" "B.Cu")
		(net "P52V_HS")
	)
	(via
		(at 269.24 -64.008)
		(size 0.508)
		(drill 0.254)
		(layers "F.Cu" "B.Cu")
		(net "P52V_HS")
	)
	(via
		(at 215.646 -101.346)
		(size 0.762)
		(drill 0.254)
		(layers "F.Cu" "B.Cu")
		(net "P52V_HS")
	)
	(via
		(at 222.039688 -105.882948)
		(size 0.508)
		(drill 0.254)
		(layers "F.Cu" "B.Cu")
		(net "P52V_HS")
	)
	(via
		(at 220.558868 -105.134664)
		(size 0.508)
		(drill 0.254)
		(layers "F.Cu" "B.Cu")
		(net "P52V_HS")
	)
	(via
		(at 233.069384 -131.829556)
		(size 0.508)
		(drill 0.254)
		(layers "F.Cu" "B.Cu")
		(net "P52V_HS")
	)
	(via
		(at 269.24 -77.597)
		(size 0.508)
		(drill 0.254)
		(layers "F.Cu" "B.Cu")
		(net "P52V_HS")
	)
	(via
		(at 271.526 -89.662)
		(size 0.508)
		(drill 0.254)
		(layers "F.Cu" "B.Cu")
		(net "P52V_HS")
	)
	(via
		(at 270.764 -98.679)
		(size 0.508)
		(drill 0.254)
		(layers "F.Cu" "B.Cu")
		(net "P52V_HS")
	)
	(via
		(at 270.764 -74.549)
		(size 0.508)
		(drill 0.254)
		(layers "F.Cu" "B.Cu")
		(net "P52V_HS")
	)
	(via
		(at 270.764 -122.047)
		(size 0.508)
		(drill 0.254)
		(layers "F.Cu" "B.Cu")
		(net "P52V_HS")
	)
	(via
		(at 270.002 -77.597)
		(size 0.508)
		(drill 0.254)
		(layers "F.Cu" "B.Cu")
		(net "P52V_HS")
	)
	(via
		(at 270.891 -137.414)
		(size 0.508)
		(drill 0.254)
		(layers "F.Cu" "B.Cu")
		(net "P52V_HS")
	)
	(via
		(at 234.579668 -128.824736)
		(size 0.508)
		(drill 0.254)
		(layers "F.Cu" "B.Cu")
		(net "P52V_HS")
	)
	(via
		(at 269.24 -113.792)
		(size 0.508)
		(drill 0.254)
		(layers "F.Cu" "B.Cu")
		(net "P52V_HS")
	)
	(via
		(at 221.320868 -103.6701)
		(size 0.508)
		(drill 0.254)
		(layers "F.Cu" "B.Cu")
		(net "P52V_HS")
	)
	(via
		(at 204.552042 -105.134664)
		(size 0.508)
		(drill 0.254)
		(layers "F.Cu" "B.Cu")
		(net "P52V_HS")
	)
	(via
		(at 206.838042 -103.6701)
		(size 0.508)
		(drill 0.254)
		(layers "F.Cu" "B.Cu")
		(net "P52V_HS")
	)
	(via
		(at 270.764 -99.441)
		(size 0.508)
		(drill 0.254)
		(layers "F.Cu" "B.Cu")
		(net "P52V_HS")
	)
	(via
		(at 271.526 -85.852)
		(size 0.508)
		(drill 0.254)
		(layers "F.Cu" "B.Cu")
		(net "P52V_HS")
	)
	(via
		(at 269.24 -88.9)
		(size 0.508)
		(drill 0.254)
		(layers "F.Cu" "B.Cu")
		(net "P52V_HS")
	)
	(via
		(at 232.54335 -98.012758)
		(size 0.508)
		(drill 0.254)
		(layers "F.Cu" "B.Cu")
		(net "P52V_HS")
	)
	(via
		(at 271.526 -88.9)
		(size 0.508)
		(drill 0.254)
		(layers "F.Cu" "B.Cu")
		(net "P52V_HS")
	)
	(via
		(at 272.288 -125.095)
		(size 0.508)
		(drill 0.254)
		(layers "F.Cu" "B.Cu")
		(net "P52V_HS")
	)
	(via
		(at 206.076042 -104.4321)
		(size 0.508)
		(drill 0.254)
		(layers "F.Cu" "B.Cu")
		(net "P52V_HS")
	)
	(via
		(at 203.790042 -105.134664)
		(size 0.508)
		(drill 0.254)
		(layers "F.Cu" "B.Cu")
		(net "P52V_HS")
	)
	(via
		(at 270.891 -138.938)
		(size 0.508)
		(drill 0.254)
		(layers "F.Cu" "B.Cu")
		(net "P52V_HS")
	)
	(via
		(at 270.764 -88.138)
		(size 0.508)
		(drill 0.254)
		(layers "F.Cu" "B.Cu")
		(net "P52V_HS")
	)
	(via
		(at 202.3364 -103.656638)
		(size 0.508)
		(drill 0.254)
		(layers "F.Cu" "B.Cu")
		(net "P52V_HS")
	)
	(via
		(at 219.796868 -104.4321)
		(size 0.508)
		(drill 0.254)
		(layers "F.Cu" "B.Cu")
		(net "P52V_HS")
	)
	(via
		(at 272.288 -113.792)
		(size 0.508)
		(drill 0.254)
		(layers "F.Cu" "B.Cu")
		(net "P52V_HS")
	)
	(via
		(at 233.817668 -131.110736)
		(size 0.508)
		(drill 0.254)
		(layers "F.Cu" "B.Cu")
		(net "P52V_HS")
	)
	(via
		(at 270.002 -100.203)
		(size 0.508)
		(drill 0.254)
		(layers "F.Cu" "B.Cu")
		(net "P52V_HS")
	)
	(via
		(at 270.002 -125.095)
		(size 0.508)
		(drill 0.254)
		(layers "F.Cu" "B.Cu")
		(net "P52V_HS")
	)
	(via
		(at 272.288 -64.77)
		(size 0.508)
		(drill 0.254)
		(layers "F.Cu" "B.Cu")
		(net "P52V_HS")
	)
	(via
		(at 270.002 -73.787)
		(size 0.508)
		(drill 0.254)
		(layers "F.Cu" "B.Cu")
		(net "P52V_HS")
	)
	(via
		(at 40.767 -106.045)
		(size 0.508)
		(drill 0.254)
		(layers "F.Cu" "B.Cu")
		(net "P52V_HS")
	)
	(via
		(at 270.002 -62.484)
		(size 0.508)
		(drill 0.254)
		(layers "F.Cu" "B.Cu")
		(net "P52V_HS")
	)
	(via
		(at 41.656 -104.5464)
		(size 0.508)
		(drill 0.254)
		(layers "F.Cu" "B.Cu")
		(net "P52V_HS")
	)
	(via
		(at 222.86087 -97.985834)
		(size 0.508)
		(drill 0.254)
		(layers "F.Cu" "B.Cu")
		(net "P52V_HS")
	)
	(via
		(at 239.838738 -98.012758)
		(size 0.508)
		(drill 0.254)
		(layers "F.Cu" "B.Cu")
		(net "P52V_HS")
	)
	(via
		(at 217.510868 -103.6701)
		(size 0.508)
		(drill 0.254)
		(layers "F.Cu" "B.Cu")
		(net "P52V_HS")
	)
	(via
		(at 39.8272 -107.5944)
		(size 0.508)
		(drill 0.254)
		(layers "F.Cu" "B.Cu")
		(net "P52V_HS")
	)
	(via
		(at 231.604566 -126.609094)
		(size 0.508)
		(drill 0.254)
		(layers "F.Cu" "B.Cu")
		(net "P52V_HS")
	)
	(via
		(at 271.653 -137.414)
		(size 0.508)
		(drill 0.254)
		(layers "F.Cu" "B.Cu")
		(net "P52V_HS")
	)
	(via
		(at 270.764 -76.835)
		(size 0.508)
		(drill 0.254)
		(layers "F.Cu" "B.Cu")
		(net "P52V_HS")
	)
	(via
		(at 224.593912 -97.985834)
		(size 0.508)
		(drill 0.254)
		(layers "F.Cu" "B.Cu")
		(net "P52V_HS")
	)
	(via
		(at 234.579668 -131.110736)
		(size 0.508)
		(drill 0.254)
		(layers "F.Cu" "B.Cu")
		(net "P52V_HS")
	)
	(via
		(at 272.288 -110.744)
		(size 0.508)
		(drill 0.254)
		(layers "F.Cu" "B.Cu")
		(net "P52V_HS")
	)
	(via
		(at 206.076042 -103.6701)
		(size 0.508)
		(drill 0.254)
		(layers "F.Cu" "B.Cu")
		(net "P52V_HS")
	)
	(via
		(at 270.764 -111.506)
		(size 0.508)
		(drill 0.254)
		(layers "F.Cu" "B.Cu")
		(net "P52V_HS")
	)
	(via
		(at 217.510868 -104.4321)
		(size 0.508)
		(drill 0.254)
		(layers "F.Cu" "B.Cu")
		(net "P52V_HS")
	)
	(via
		(at 269.24 -87.376)
		(size 0.508)
		(drill 0.254)
		(layers "F.Cu" "B.Cu")
		(net "P52V_HS")
	)
	(via
		(at 242.08994 -98.012758)
		(size 0.508)
		(drill 0.254)
		(layers "F.Cu" "B.Cu")
		(net "P52V_HS")
	)
	(via
		(at 271.526 -62.484)
		(size 0.508)
		(drill 0.254)
		(layers "F.Cu" "B.Cu")
		(net "P52V_HS")
	)
	(via
		(at 233.055668 -128.824736)
		(size 0.508)
		(drill 0.254)
		(layers "F.Cu" "B.Cu")
		(net "P52V_HS")
	)
	(via
		(at 258.219956 -48.327818)
		(size 0.508)
		(drill 0.254)
		(layers "F.Cu" "B.Cu")
		(net "P52V_HS")
	)
	(via
		(at 270.764 -89.662)
		(size 0.508)
		(drill 0.254)
		(layers "F.Cu" "B.Cu")
		(net "P52V_HS")
	)
	(via
		(at 270.764 -77.597)
		(size 0.508)
		(drill 0.254)
		(layers "F.Cu" "B.Cu")
		(net "P52V_HS")
	)
	(via
		(at 271.526 -73.787)
		(size 0.508)
		(drill 0.254)
		(layers "F.Cu" "B.Cu")
		(net "P52V_HS")
	)
	(via
		(at 233.83113 -126.609094)
		(size 0.508)
		(drill 0.254)
		(layers "F.Cu" "B.Cu")
		(net "P52V_HS")
	)
	(via
		(at 218.250262 -98.013012)
		(size 0.508)
		(drill 0.254)
		(layers "F.Cu" "B.Cu")
		(net "P52V_HS")
	)
	(via
		(at 269.24 -64.77)
		(size 0.508)
		(drill 0.254)
		(layers "F.Cu" "B.Cu")
		(net "P52V_HS")
	)
	(via
		(at 203.790042 -103.6701)
		(size 0.508)
		(drill 0.254)
		(layers "F.Cu" "B.Cu")
		(net "P52V_HS")
	)
	(via
		(at 234.593384 -131.829556)
		(size 0.508)
		(drill 0.254)
		(layers "F.Cu" "B.Cu")
		(net "P52V_HS")
	)
	(via
		(at 203.028042 -102.9081)
		(size 0.508)
		(drill 0.254)
		(layers "F.Cu" "B.Cu")
		(net "P52V_HS")
	)
	(via
		(at 272.288 -98.679)
		(size 0.508)
		(drill 0.254)
		(layers "F.Cu" "B.Cu")
		(net "P52V_HS")
	)
	(via
		(at 219.796868 -102.9081)
		(size 0.508)
		(drill 0.254)
		(layers "F.Cu" "B.Cu")
		(net "P52V_HS")
	)
	(via
		(at 271.526 -122.809)
		(size 0.508)
		(drill 0.254)
		(layers "F.Cu" "B.Cu")
		(net "P52V_HS")
	)
	(via
		(at 269.24 -100.203)
		(size 0.508)
		(drill 0.254)
		(layers "F.Cu" "B.Cu")
		(net "P52V_HS")
	)
	(via
		(at 271.526 -65.532)
		(size 0.508)
		(drill 0.254)
		(layers "F.Cu" "B.Cu")
		(net "P52V_HS")
	)
	(via
		(at 215.23706 -98.013012)
		(size 0.508)
		(drill 0.254)
		(layers "F.Cu" "B.Cu")
		(net "P52V_HS")
	)
	(via
		(at 216.819226 -105.121202)
		(size 0.508)
		(drill 0.254)
		(layers "F.Cu" "B.Cu")
		(net "P52V_HS")
	)
	(via
		(at 272.288 -85.852)
		(size 0.508)
		(drill 0.254)
		(layers "F.Cu" "B.Cu")
		(net "P52V_HS")
	)
	(via
		(at 269.24 -125.857)
		(size 0.508)
		(drill 0.254)
		(layers "F.Cu" "B.Cu")
		(net "P52V_HS")
	)
	(via
		(at 270.891 -139.7)
		(size 0.508)
		(drill 0.254)
		(layers "F.Cu" "B.Cu")
		(net "P52V_HS")
	)
	(via
		(at 222.039688 -104.418384)
		(size 0.508)
		(drill 0.254)
		(layers "F.Cu" "B.Cu")
		(net "P52V_HS")
	)
	(via
		(at 241.32794 -98.012758)
		(size 0.508)
		(drill 0.254)
		(layers "F.Cu" "B.Cu")
		(net "P52V_HS")
	)
	(via
		(at 271.526 -98.679)
		(size 0.508)
		(drill 0.254)
		(layers "F.Cu" "B.Cu")
		(net "P52V_HS")
	)
	(via
		(at 234.579668 -129.586736)
		(size 0.508)
		(drill 0.254)
		(layers "F.Cu" "B.Cu")
		(net "P52V_HS")
	)
	(via
		(at 231.78135 -98.012758)
		(size 0.508)
		(drill 0.254)
		(layers "F.Cu" "B.Cu")
		(net "P52V_HS")
	)
	(via
		(at 269.24 -111.506)
		(size 0.508)
		(drill 0.254)
		(layers "F.Cu" "B.Cu")
		(net "P52V_HS")
	)
	(via
		(at 272.288 -73.787)
		(size 0.508)
		(drill 0.254)
		(layers "F.Cu" "B.Cu")
		(net "P52V_HS")
	)
	(via
		(at 270.002 -64.77)
		(size 0.508)
		(drill 0.254)
		(layers "F.Cu" "B.Cu")
		(net "P52V_HS")
	)
	(via
		(at 270.764 -87.376)
		(size 0.508)
		(drill 0.254)
		(layers "F.Cu" "B.Cu")
		(net "P52V_HS")
	)
	(via
		(at 41.656 -103.7844)
		(size 0.508)
		(drill 0.254)
		(layers "F.Cu" "B.Cu")
		(net "P52V_HS")
	)
	(via
		(at 222.09887 -97.985834)
		(size 0.508)
		(drill 0.254)
		(layers "F.Cu" "B.Cu")
		(net "P52V_HS")
	)
	(via
		(at 270.002 -100.965)
		(size 0.508)
		(drill 0.254)
		(layers "F.Cu" "B.Cu")
		(net "P52V_HS")
	)
	(via
		(at 40.767 -104.521)
		(size 0.508)
		(drill 0.254)
		(layers "F.Cu" "B.Cu")
		(net "P52V_HS")
	)
	(via
		(at 41.6052 -108.3818)
		(size 0.508)
		(drill 0.254)
		(layers "F.Cu" "B.Cu")
		(net "P52V_HS")
	)
	(via
		(at 269.24 -63.246)
		(size 0.508)
		(drill 0.254)
		(layers "F.Cu" "B.Cu")
		(net "P52V_HS")
	)
	(via
		(at 207.556862 -105.882948)
		(size 0.508)
		(drill 0.254)
		(layers "F.Cu" "B.Cu")
		(net "P52V_HS")
	)
	(via
		(at 219.034868 -105.134664)
		(size 0.508)
		(drill 0.254)
		(layers "F.Cu" "B.Cu")
		(net "P52V_HS")
	)
	(via
		(at 269.24 -110.744)
		(size 0.508)
		(drill 0.254)
		(layers "F.Cu" "B.Cu")
		(net "P52V_HS")
	)
	(via
		(at 271.526 -86.614)
		(size 0.508)
		(drill 0.254)
		(layers "F.Cu" "B.Cu")
		(net "P52V_HS")
	)
	(via
		(at 269.24 -74.549)
		(size 0.508)
		(drill 0.254)
		(layers "F.Cu" "B.Cu")
		(net "P52V_HS")
	)
	(via
		(at 232.353104 -131.110736)
		(size 0.508)
		(drill 0.254)
		(layers "F.Cu" "B.Cu")
		(net "P52V_HS")
	)
	(via
		(at 270.002 -111.506)
		(size 0.508)
		(drill 0.254)
		(layers "F.Cu" "B.Cu")
		(net "P52V_HS")
	)
	(via
		(at 270.002 -86.614)
		(size 0.508)
		(drill 0.254)
		(layers "F.Cu" "B.Cu")
		(net "P52V_HS")
	)
	(via
		(at 269.24 -73.787)
		(size 0.508)
		(drill 0.254)
		(layers "F.Cu" "B.Cu")
		(net "P52V_HS")
	)
	(via
		(at 39.878 -106.807)
		(size 0.508)
		(drill 0.254)
		(layers "F.Cu" "B.Cu")
		(net "P52V_HS")
	)
	(via
		(at 237.316518 -97.985834)
		(size 0.508)
		(drill 0.254)
		(layers "F.Cu" "B.Cu")
		(net "P52V_HS")
	)
	(via
		(at 215.99906 -98.013012)
		(size 0.508)
		(drill 0.254)
		(layers "F.Cu" "B.Cu")
		(net "P52V_HS")
	)
	(via
		(at 270.764 -100.203)
		(size 0.508)
		(drill 0.254)
		(layers "F.Cu" "B.Cu")
		(net "P52V_HS")
	)
	(via
		(at 269.24 -98.679)
		(size 0.508)
		(drill 0.254)
		(layers "F.Cu" "B.Cu")
		(net "P52V_HS")
	)
	(via
		(at 39.878 -104.521)
		(size 0.508)
		(drill 0.254)
		(layers "F.Cu" "B.Cu")
		(net "P52V_HS")
	)
	(via
		(at 270.002 -88.9)
		(size 0.508)
		(drill 0.254)
		(layers "F.Cu" "B.Cu")
		(net "P52V_HS")
	)
	(via
		(at 269.24 -86.614)
		(size 0.508)
		(drill 0.254)
		(layers "F.Cu" "B.Cu")
		(net "P52V_HS")
	)
	(via
		(at 234.579668 -128.062736)
		(size 0.508)
		(drill 0.254)
		(layers "F.Cu" "B.Cu")
		(net "P52V_HS")
	)
	(via
		(at 272.288 -61.722)
		(size 0.508)
		(drill 0.254)
		(layers "F.Cu" "B.Cu")
		(net "P52V_HS")
	)
	(via
		(at 272.288 -89.662)
		(size 0.508)
		(drill 0.254)
		(layers "F.Cu" "B.Cu")
		(net "P52V_HS")
	)
	(via
		(at 40.767 -103.759)
		(size 0.508)
		(drill 0.254)
		(layers "F.Cu" "B.Cu")
		(net "P52V_HS")
	)
	(via
		(at 272.288 -77.597)
		(size 0.508)
		(drill 0.254)
		(layers "F.Cu" "B.Cu")
		(net "P52V_HS")
	)
	(via
		(at 270.764 -100.965)
		(size 0.508)
		(drill 0.254)
		(layers "F.Cu" "B.Cu")
		(net "P52V_HS")
	)
	(via
		(at 270.002 -113.792)
		(size 0.508)
		(drill 0.254)
		(layers "F.Cu" "B.Cu")
		(net "P52V_HS")
	)
	(via
		(at 220.558868 -102.9081)
		(size 0.508)
		(drill 0.254)
		(layers "F.Cu" "B.Cu")
		(net "P52V_HS")
	)
	(via
		(at 270.002 -74.549)
		(size 0.508)
		(drill 0.254)
		(layers "F.Cu" "B.Cu")
		(net "P52V_HS")
	)
	(via
		(at 233.817668 -128.824736)
		(size 0.508)
		(drill 0.254)
		(layers "F.Cu" "B.Cu")
		(net "P52V_HS")
	)
	(via
		(at 203.028042 -103.6701)
		(size 0.508)
		(drill 0.254)
		(layers "F.Cu" "B.Cu")
		(net "P52V_HS")
	)
	(via
		(at 222.039688 -102.894384)
		(size 0.508)
		(drill 0.254)
		(layers "F.Cu" "B.Cu")
		(net "P52V_HS")
	)
	(via
		(at 270.764 -86.614)
		(size 0.508)
		(drill 0.254)
		(layers "F.Cu" "B.Cu")
		(net "P52V_HS")
	)
	(via
		(at 272.288 -101.727)
		(size 0.508)
		(drill 0.254)
		(layers "F.Cu" "B.Cu")
		(net "P52V_HS")
	)
	(via
		(at 204.552042 -105.896664)
		(size 0.508)
		(drill 0.254)
		(layers "F.Cu" "B.Cu")
		(net "P52V_HS")
	)
	(via
		(at 202.3364 -102.894638)
		(size 0.508)
		(drill 0.254)
		(layers "F.Cu" "B.Cu")
		(net "P52V_HS")
	)
	(via
		(at 202.3364 -105.883202)
		(size 0.508)
		(drill 0.254)
		(layers "F.Cu" "B.Cu")
		(net "P52V_HS")
	)
	(via
		(at 218.272868 -102.9081)
		(size 0.508)
		(drill 0.254)
		(layers "F.Cu" "B.Cu")
		(net "P52V_HS")
	)
	(via
		(at 39.878 -105.283)
		(size 0.508)
		(drill 0.254)
		(layers "F.Cu" "B.Cu")
		(net "P52V_HS")
	)
	(via
		(at 272.288 -76.835)
		(size 0.508)
		(drill 0.254)
		(layers "F.Cu" "B.Cu")
		(net "P52V_HS")
	)
	(via
		(at 270.764 -122.809)
		(size 0.508)
		(drill 0.254)
		(layers "F.Cu" "B.Cu")
		(net "P52V_HS")
	)
	(via
		(at 231.591104 -131.110736)
		(size 0.508)
		(drill 0.254)
		(layers "F.Cu" "B.Cu")
		(net "P52V_HS")
	)
	(via
		(at 203.790042 -102.9081)
		(size 0.508)
		(drill 0.254)
		(layers "F.Cu" "B.Cu")
		(net "P52V_HS")
	)
	(via
		(at 270.002 -112.268)
		(size 0.508)
		(drill 0.254)
		(layers "F.Cu" "B.Cu")
		(net "P52V_HS")
	)
	(via
		(at 219.034868 -103.6701)
		(size 0.508)
		(drill 0.254)
		(layers "F.Cu" "B.Cu")
		(net "P52V_HS")
	)
	(via
		(at 270.764 -112.268)
		(size 0.508)
		(drill 0.254)
		(layers "F.Cu" "B.Cu")
		(net "P52V_HS")
	)
	(via
		(at 234.579668 -127.300736)
		(size 0.508)
		(drill 0.254)
		(layers "F.Cu" "B.Cu")
		(net "P52V_HS")
	)
	(via
		(at 232.353104 -128.824736)
		(size 0.508)
		(drill 0.254)
		(layers "F.Cu" "B.Cu")
		(net "P52V_HS")
	)
	(via
		(at 272.288 -113.03)
		(size 0.508)
		(drill 0.254)
		(layers "F.Cu" "B.Cu")
		(net "P52V_HS")
	)
	(via
		(at 207.556862 -102.894384)
		(size 0.508)
		(drill 0.254)
		(layers "F.Cu" "B.Cu")
		(net "P52V_HS")
	)
	(via
		(at 270.764 -75.311)
		(size 0.508)
		(drill 0.254)
		(layers "F.Cu" "B.Cu")
		(net "P52V_HS")
	)
	(via
		(at 288.163 -30.687264)
		(size 0.508)
		(drill 0.254)
		(layers "F.Cu" "B.Cu")
		(net "P52V_HS")
	)
	(via
		(at 203.790042 -105.896664)
		(size 0.508)
		(drill 0.254)
		(layers "F.Cu" "B.Cu")
		(net "P52V_HS")
	)
	(via
		(at 271.653 -136.652)
		(size 0.508)
		(drill 0.254)
		(layers "F.Cu" "B.Cu")
		(net "P52V_HS")
	)
	(via
		(at 269.24 -88.138)
		(size 0.508)
		(drill 0.254)
		(layers "F.Cu" "B.Cu")
		(net "P52V_HS")
	)
	(via
		(at 271.526 -110.744)
		(size 0.508)
		(drill 0.254)
		(layers "F.Cu" "B.Cu")
		(net "P52V_HS")
	)
	(via
		(at 233.06913 -126.609094)
		(size 0.508)
		(drill 0.254)
		(layers "F.Cu" "B.Cu")
		(net "P52V_HS")
	)
	(via
		(at 269.24 -76.835)
		(size 0.508)
		(drill 0.254)
		(layers "F.Cu" "B.Cu")
		(net "P52V_HS")
	)
	(via
		(at 270.002 -101.727)
		(size 0.508)
		(drill 0.254)
		(layers "F.Cu" "B.Cu")
		(net "P52V_HS")
	)
	(via
		(at 220.558868 -103.6701)
		(size 0.508)
		(drill 0.254)
		(layers "F.Cu" "B.Cu")
		(net "P52V_HS")
	)
	(via
		(at 271.526 -125.095)
		(size 0.508)
		(drill 0.254)
		(layers "F.Cu" "B.Cu")
		(net "P52V_HS")
	)
	(via
		(at 269.24 -112.268)
		(size 0.508)
		(drill 0.254)
		(layers "F.Cu" "B.Cu")
		(net "P52V_HS")
	)
	(via
		(at 271.526 -125.857)
		(size 0.508)
		(drill 0.254)
		(layers "F.Cu" "B.Cu")
		(net "P52V_HS")
	)
	(via
		(at 269.24 -109.982)
		(size 0.508)
		(drill 0.254)
		(layers "F.Cu" "B.Cu")
		(net "P52V_HS")
	)
	(via
		(at 225.355912 -97.985834)
		(size 0.508)
		(drill 0.254)
		(layers "F.Cu" "B.Cu")
		(net "P52V_HS")
	)
	(via
		(at 232.366566 -126.609094)
		(size 0.508)
		(drill 0.254)
		(layers "F.Cu" "B.Cu")
		(net "P52V_HS")
	)
	(via
		(at 206.838042 -102.9081)
		(size 0.508)
		(drill 0.254)
		(layers "F.Cu" "B.Cu")
		(net "P52V_HS")
	)
	(via
		(at 217.510868 -102.9081)
		(size 0.508)
		(drill 0.254)
		(layers "F.Cu" "B.Cu")
		(net "P52V_HS")
	)
	(via
		(at 295.3258 -44.693586)
		(size 0.508)
		(drill 0.254)
		(layers "F.Cu" "B.Cu")
		(net "P52V_HS")
	)
	(via
		(at 271.653 -138.176)
		(size 0.508)
		(drill 0.254)
		(layers "F.Cu" "B.Cu")
		(net "P52V_HS")
	)
	(via
		(at 231.591104 -129.586736)
		(size 0.508)
		(drill 0.254)
		(layers "F.Cu" "B.Cu")
		(net "P52V_HS")
	)
	(via
		(at 234.303316 -97.985834)
		(size 0.508)
		(drill 0.254)
		(layers "F.Cu" "B.Cu")
		(net "P52V_HS")
	)
	(via
		(at 219.034868 -102.9081)
		(size 0.508)
		(drill 0.254)
		(layers "F.Cu" "B.Cu")
		(net "P52V_HS")
	)
	(via
		(at 270.002 -61.722)
		(size 0.508)
		(drill 0.254)
		(layers "F.Cu" "B.Cu")
		(net "P52V_HS")
	)
	(via
		(at 222.039688 -103.656384)
		(size 0.508)
		(drill 0.254)
		(layers "F.Cu" "B.Cu")
		(net "P52V_HS")
	)
	(via
		(at 269.24 -61.722)
		(size 0.508)
		(drill 0.254)
		(layers "F.Cu" "B.Cu")
		(net "P52V_HS")
	)
	(via
		(at 271.653 -138.938)
		(size 0.508)
		(drill 0.254)
		(layers "F.Cu" "B.Cu")
		(net "P52V_HS")
	)
	(via
		(at 217.510868 -105.134664)
		(size 0.508)
		(drill 0.254)
		(layers "F.Cu" "B.Cu")
		(net "P52V_HS")
	)
	(via
		(at 206.838042 -105.134664)
		(size 0.508)
		(drill 0.254)
		(layers "F.Cu" "B.Cu")
		(net "P52V_HS")
	)
	(via
		(at 233.817668 -130.348736)
		(size 0.508)
		(drill 0.254)
		(layers "F.Cu" "B.Cu")
		(net "P52V_HS")
	)
	(via
		(at 270.764 -109.982)
		(size 0.508)
		(drill 0.254)
		(layers "F.Cu" "B.Cu")
		(net "P52V_HS")
	)
	(via
		(at 271.526 -77.597)
		(size 0.508)
		(drill 0.254)
		(layers "F.Cu" "B.Cu")
		(net "P52V_HS")
	)
	(via
		(at 232.353104 -127.300736)
		(size 0.508)
		(drill 0.254)
		(layers "F.Cu" "B.Cu")
		(net "P52V_HS")
	)
	(via
		(at 270.002 -122.047)
		(size 0.508)
		(drill 0.254)
		(layers "F.Cu" "B.Cu")
		(net "P52V_HS")
	)
	(via
		(at 272.288 -62.484)
		(size 0.508)
		(drill 0.254)
		(layers "F.Cu" "B.Cu")
		(net "P52V_HS")
	)
	(via
		(at 216.819226 -103.656638)
		(size 0.508)
		(drill 0.254)
		(layers "F.Cu" "B.Cu")
		(net "P52V_HS")
	)
	(via
		(at 216.819226 -104.418638)
		(size 0.508)
		(drill 0.254)
		(layers "F.Cu" "B.Cu")
		(net "P52V_HS")
	)
	(via
		(at 202.3364 -105.121202)
		(size 0.508)
		(drill 0.254)
		(layers "F.Cu" "B.Cu")
		(net "P52V_HS")
	)
	(via
		(at 231.591104 -128.062736)
		(size 0.508)
		(drill 0.254)
		(layers "F.Cu" "B.Cu")
		(net "P52V_HS")
	)
	(via
		(at 207.556862 -103.656384)
		(size 0.508)
		(drill 0.254)
		(layers "F.Cu" "B.Cu")
		(net "P52V_HS")
	)
	(via
		(at 272.288 -97.917)
		(size 0.508)
		(drill 0.254)
		(layers "F.Cu" "B.Cu")
		(net "P52V_HS")
	)
	(via
		(at 269.24 -122.809)
		(size 0.508)
		(drill 0.254)
		(layers "F.Cu" "B.Cu")
		(net "P52V_HS")
	)
	(via
		(at 269.24 -97.917)
		(size 0.508)
		(drill 0.254)
		(layers "F.Cu" "B.Cu")
		(net "P52V_HS")
	)
	(via
		(at 204.552042 -102.9081)
		(size 0.508)
		(drill 0.254)
		(layers "F.Cu" "B.Cu")
		(net "P52V_HS")
	)
	(via
		(at 226.845114 -97.985834)
		(size 0.508)
		(drill 0.254)
		(layers "F.Cu" "B.Cu")
		(net "P52V_HS")
	)
	(via
		(at 39.8272 -108.3564)
		(size 0.508)
		(drill 0.254)
		(layers "F.Cu" "B.Cu")
		(net "P52V_HS")
	)
	(via
		(at 272.288 -109.982)
		(size 0.508)
		(drill 0.254)
		(layers "F.Cu" "B.Cu")
		(net "P52V_HS")
	)
	(via
		(at 205.314042 -104.4321)
		(size 0.508)
		(drill 0.254)
		(layers "F.Cu" "B.Cu")
		(net "P52V_HS")
	)
	(via
		(at 271.526 -97.917)
		(size 0.508)
		(drill 0.254)
		(layers "F.Cu" "B.Cu")
		(net "P52V_HS")
	)
	(via
		(at 270.764 -64.008)
		(size 0.508)
		(drill 0.254)
		(layers "F.Cu" "B.Cu")
		(net "P52V_HS")
	)
	(via
		(at 270.002 -97.917)
		(size 0.508)
		(drill 0.254)
		(layers "F.Cu" "B.Cu")
		(net "P52V_HS")
	)
	(via
		(at 206.076042 -102.9081)
		(size 0.508)
		(drill 0.254)
		(layers "F.Cu" "B.Cu")
		(net "P52V_HS")
	)
	(via
		(at 272.288 -100.965)
		(size 0.508)
		(drill 0.254)
		(layers "F.Cu" "B.Cu")
		(net "P52V_HS")
	)
	(via
		(at 270.891 -140.462)
		(size 0.508)
		(drill 0.254)
		(layers "F.Cu" "B.Cu")
		(net "P52V_HS")
	)
	(via
		(at 269.24 -75.311)
		(size 0.508)
		(drill 0.254)
		(layers "F.Cu" "B.Cu")
		(net "P52V_HS")
	)
	(via
		(at 269.24 -101.727)
		(size 0.508)
		(drill 0.254)
		(layers "F.Cu" "B.Cu")
		(net "P52V_HS")
	)
	(via
		(at 270.002 -87.376)
		(size 0.508)
		(drill 0.254)
		(layers "F.Cu" "B.Cu")
		(net "P52V_HS")
	)
	(via
		(at 270.764 -123.571)
		(size 0.508)
		(drill 0.254)
		(layers "F.Cu" "B.Cu")
		(net "P52V_HS")
	)
	(via
		(at 270.002 -65.532)
		(size 0.508)
		(drill 0.254)
		(layers "F.Cu" "B.Cu")
		(net "P52V_HS")
	)
	(via
		(at 206.838042 -104.4321)
		(size 0.508)
		(drill 0.254)
		(layers "F.Cu" "B.Cu")
		(net "P52V_HS")
	)
	(via
		(at 272.288 -74.549)
		(size 0.508)
		(drill 0.254)
		(layers "F.Cu" "B.Cu")
		(net "P52V_HS")
	)
	(via
		(at 205.314042 -105.896664)
		(size 0.508)
		(drill 0.254)
		(layers "F.Cu" "B.Cu")
		(net "P52V_HS")
	)
	(via
		(at 270.002 -63.246)
		(size 0.508)
		(drill 0.254)
		(layers "F.Cu" "B.Cu")
		(net "P52V_HS")
	)
	(via
		(at 40.7162 -107.5944)
		(size 0.508)
		(drill 0.254)
		(layers "F.Cu" "B.Cu")
		(net "P52V_HS")
	)
	(via
		(at 216.819226 -105.883202)
		(size 0.508)
		(drill 0.254)
		(layers "F.Cu" "B.Cu")
		(net "P52V_HS")
	)
	(via
		(at 233.055668 -131.110736)
		(size 0.508)
		(drill 0.254)
		(layers "F.Cu" "B.Cu")
		(net "P52V_HS")
	)
	(via
		(at 270.002 -75.311)
		(size 0.508)
		(drill 0.254)
		(layers "F.Cu" "B.Cu")
		(net "P52V_HS")
	)
	(via
		(at 41.656 -106.0704)
		(size 0.508)
		(drill 0.254)
		(layers "F.Cu" "B.Cu")
		(net "P52V_HS")
	)
	(via
		(at 270.764 -124.333)
		(size 0.508)
		(drill 0.254)
		(layers "F.Cu" "B.Cu")
		(net "P52V_HS")
	)
	(via
		(at 39.878 -103.759)
		(size 0.508)
		(drill 0.254)
		(layers "F.Cu" "B.Cu")
		(net "P52V_HS")
	)
	(via
		(at 40.7162 -108.3564)
		(size 0.508)
		(drill 0.254)
		(layers "F.Cu" "B.Cu")
		(net "P52V_HS")
	)
	(via
		(at 206.076042 -105.896664)
		(size 0.508)
		(drill 0.254)
		(layers "F.Cu" "B.Cu")
		(net "P52V_HS")
	)
	(via
		(at 271.526 -113.03)
		(size 0.508)
		(drill 0.254)
		(layers "F.Cu" "B.Cu")
		(net "P52V_HS")
	)
	(via
		(at 276.225 -51.054)
		(size 0.508)
		(drill 0.254)
		(layers "F.Cu" "B.Cu")
		(net "P52V_HS")
	)
	(via
		(at 271.526 -64.77)
		(size 0.508)
		(drill 0.254)
		(layers "F.Cu" "B.Cu")
		(net "P52V_HS")
	)
	(via
		(at 205.314042 -103.6701)
		(size 0.508)
		(drill 0.254)
		(layers "F.Cu" "B.Cu")
		(net "P52V_HS")
	)
	(via
		(at 271.526 -76.835)
		(size 0.508)
		(drill 0.254)
		(layers "F.Cu" "B.Cu")
		(net "P52V_HS")
	)
	(via
		(at 233.055668 -127.300736)
		(size 0.508)
		(drill 0.254)
		(layers "F.Cu" "B.Cu")
		(net "P52V_HS")
	)
	(via
		(at 270.764 -113.792)
		(size 0.508)
		(drill 0.254)
		(layers "F.Cu" "B.Cu")
		(net "P52V_HS")
	)
	(via
		(at 231.591104 -130.348736)
		(size 0.508)
		(drill 0.254)
		(layers "F.Cu" "B.Cu")
		(net "P52V_HS")
	)
	(via
		(at 270.764 -64.77)
		(size 0.508)
		(drill 0.254)
		(layers "F.Cu" "B.Cu")
		(net "P52V_HS")
	)
	(via
		(at 232.353104 -129.586736)
		(size 0.508)
		(drill 0.254)
		(layers "F.Cu" "B.Cu")
		(net "P52V_HS")
	)
	(via
		(at 220.558868 -105.896664)
		(size 0.508)
		(drill 0.254)
		(layers "F.Cu" "B.Cu")
		(net "P52V_HS")
	)
	(via
		(at 217.488262 -98.013012)
		(size 0.508)
		(drill 0.254)
		(layers "F.Cu" "B.Cu")
		(net "P52V_HS")
	)
	(via
		(at 232.353104 -128.062736)
		(size 0.508)
		(drill 0.254)
		(layers "F.Cu" "B.Cu")
		(net "P52V_HS")
	)
	(via
		(at 271.653 -139.7)
		(size 0.508)
		(drill 0.254)
		(layers "F.Cu" "B.Cu")
		(net "P52V_HS")
	)
	(via
		(at 258.219956 -50.232818)
		(size 0.508)
		(drill 0.254)
		(layers "F.Cu" "B.Cu")
		(net "P52V_HS")
	)
	(segment
		(start 46.07941 -55.07482)
		(end 46.7106 -55.07482)
		(width 0.17272)
		(layer "F.Cu")
		(net "P12V_BRICK_PWRGD")
	)
	(via
		(at 171.72305 -76.0984)
		(size 0.508)
		(drill 0.254)
		(layers "F.Cu" "B.Cu")
		(net "P12V_BRICK_PWRGD")
	)
	(via
		(at 46.7106 -55.07482)
		(size 0.508)
		(drill 0.254)
		(layers "F.Cu" "B.Cu")
		(net "P12V_BRICK_PWRGD")
	)
	(via
		(at 51.70805 -75.565)
		(size 0.508)
		(drill 0.254)
		(layers "F.Cu" "B.Cu")
		(net "P12V_BRICK_PWRGD")
	)
	(via
		(at 220.218 -73.98004)
		(size 0.508)
		(drill 0.254)
		(layers "F.Cu" "B.Cu")
		(net "P12V_BRICK_PWRGD")
	)
	(segment
		(start 91.694 -68.713858)
		(end 90.849958 -67.869816)
		(width 0.17272)
		(layer "B.Cu")
		(net "P12V_BRICK_PWRGD")
	)
	(segment
		(start 84.901786 -82.86496)
		(end 54.84876 -82.86496)
		(width 0.17272)
		(layer "B.Cu")
		(net "P12V_BRICK_PWRGD")
	)
	(segment
		(start 91.694 -76.30795)
		(end 91.458796 -76.30795)
		(width 0.17272)
		(layer "B.Cu")
		(net "P12V_BRICK_PWRGD")
	)
	(segment
		(start 50.850038 -67.869816)
		(end 51.70805 -68.727828)
		(width 0.17272)
		(layer "B.Cu")
		(net "P12V_BRICK_PWRGD")
	)
	(segment
		(start 54.84876 -82.86496)
		(end 51.70805 -79.72425)
		(width 0.17272)
		(layer "B.Cu")
		(net "P12V_BRICK_PWRGD")
	)
	(segment
		(start 51.70805 -79.72425)
		(end 51.70805 -75.565)
		(width 0.17272)
		(layer "B.Cu")
		(net "P12V_BRICK_PWRGD")
	)
	(segment
		(start 51.70805 -68.727828)
		(end 51.70805 -75.565)
		(width 0.17272)
		(layer "B.Cu")
		(net "P12V_BRICK_PWRGD")
	)
	(segment
		(start 171.72305 -76.0984)
		(end 171.72305 -68.74256)
		(width 0.17272)
		(layer "B.Cu")
		(net "P12V_BRICK_PWRGD")
	)
	(segment
		(start 91.694 -76.30795)
		(end 91.694 -68.713858)
		(width 0.17272)
		(layer "B.Cu")
		(net "P12V_BRICK_PWRGD")
	)
	(segment
		(start 220.218 -73.98004)
		(end 226.076002 -73.98004)
		(width 0.17272)
		(layer "B.Cu")
		(net "P12V_BRICK_PWRGD")
	)
	(segment
		(start 91.458796 -76.30795)
		(end 84.901786 -82.86496)
		(width 0.17272)
		(layer "B.Cu")
		(net "P12V_BRICK_PWRGD")
	)
	(segment
		(start 171.72305 -68.74256)
		(end 170.850306 -67.869816)
		(width 0.17272)
		(layer "B.Cu")
		(net "P12V_BRICK_PWRGD")
	)
	(segment
		(start 219.9386 -73.70064)
		(end 210.7946 -73.70064)
		(width 0.12954)
		(layer "In7.Cu")
		(net "P12V_BRICK_PWRGD")
	)
	(segment
		(start 171.976034 -76.351384)
		(end 171.72305 -76.0984)
		(width 0.12954)
		(layer "In7.Cu")
		(net "P12V_BRICK_PWRGD")
	)
	(segment
		(start 43.7134 -60.0456)
		(end 45.5422 -58.2168)
		(width 0.12954)
		(layer "In7.Cu")
		(net "P12V_BRICK_PWRGD")
	)
	(segment
		(start 220.218 -73.98004)
		(end 219.9386 -73.70064)
		(width 0.12954)
		(layer "In7.Cu")
		(net "P12V_BRICK_PWRGD")
	)
	(segment
		(start 52.21605 -76.073)
		(end 171.69765 -76.073)
		(width 0.12954)
		(layer "In7.Cu")
		(net "P12V_BRICK_PWRGD")
	)
	(segment
		(start 39.38397 -72.239632)
		(end 39.38397 -67.727576)
		(width 0.12954)
		(layer "In7.Cu")
		(net "P12V_BRICK_PWRGD")
	)
	(segment
		(start 50.56505 -74.422)
		(end 41.566338 -74.422)
		(width 0.12954)
		(layer "In7.Cu")
		(net "P12V_BRICK_PWRGD")
	)
	(segment
		(start 195.318634 -76.351384)
		(end 171.976034 -76.351384)
		(width 0.12954)
		(layer "In7.Cu")
		(net "P12V_BRICK_PWRGD")
	)
	(segment
		(start 51.70805 -75.565)
		(end 52.21605 -76.073)
		(width 0.12954)
		(layer "In7.Cu")
		(net "P12V_BRICK_PWRGD")
	)
	(segment
		(start 45.5422 -56.24322)
		(end 46.7106 -55.07482)
		(width 0.12954)
		(layer "In7.Cu")
		(net "P12V_BRICK_PWRGD")
	)
	(segment
		(start 41.566338 -74.422)
		(end 39.38397 -72.239632)
		(width 0.12954)
		(layer "In7.Cu")
		(net "P12V_BRICK_PWRGD")
	)
	(segment
		(start 51.70805 -75.565)
		(end 50.56505 -74.422)
		(width 0.12954)
		(layer "In7.Cu")
		(net "P12V_BRICK_PWRGD")
	)
	(segment
		(start 45.5422 -58.2168)
		(end 45.5422 -56.24322)
		(width 0.12954)
		(layer "In7.Cu")
		(net "P12V_BRICK_PWRGD")
	)
	(segment
		(start 210.7946 -73.70064)
		(end 210.09356 -72.9996)
		(width 0.12954)
		(layer "In7.Cu")
		(net "P12V_BRICK_PWRGD")
	)
	(segment
		(start 210.09356 -72.9996)
		(end 198.670418 -72.9996)
		(width 0.12954)
		(layer "In7.Cu")
		(net "P12V_BRICK_PWRGD")
	)
	(segment
		(start 198.670418 -72.9996)
		(end 195.318634 -76.351384)
		(width 0.12954)
		(layer "In7.Cu")
		(net "P12V_BRICK_PWRGD")
	)
	(segment
		(start 171.69765 -76.073)
		(end 171.72305 -76.0984)
		(width 0.12954)
		(layer "In7.Cu")
		(net "P12V_BRICK_PWRGD")
	)
	(segment
		(start 43.7134 -63.398146)
		(end 43.7134 -60.0456)
		(width 0.12954)
		(layer "In7.Cu")
		(net "P12V_BRICK_PWRGD")
	)
	(segment
		(start 39.38397 -67.727576)
		(end 43.7134 -63.398146)
		(width 0.12954)
		(layer "In7.Cu")
		(net "P12V_BRICK_PWRGD")
	)
	(via
		(at 138.303 -114.44605)
		(size 0.6604)
		(drill 0.3302)
		(layers "F.Cu" "B.Cu")
		(net "BRICK_P12V0_EN_N")
	)
	(segment
		(start 139.596368 -114.422682)
		(end 139.573 -114.44605)
		(width 0.17272)
		(layer "B.Cu")
		(net "BRICK_P12V0_EN_N")
	)
	(segment
		(start 139.086336 -114.44605)
		(end 139.109704 -114.422682)
		(width 0.17272)
		(layer "B.Cu")
		(net "BRICK_P12V0_EN_N")
	)
	(segment
		(start 136.85012 -114.44605)
		(end 136.85012 -115.67795)
		(width 0.17272)
		(layer "B.Cu")
		(net "BRICK_P12V0_EN_N")
	)
	(segment
		(start 143.002 -115.12296)
		(end 143.97609 -115.12296)
		(width 0.17272)
		(layer "B.Cu")
		(net "BRICK_P12V0_EN_N")
	)
	(segment
		(start 139.109704 -114.422682)
		(end 139.549632 -114.422682)
		(width 0.17272)
		(layer "B.Cu")
		(net "BRICK_P12V0_EN_N")
	)
	(segment
		(start 146.15795 -114.681)
		(end 146.15795 -116.205)
		(width 0.17272)
		(layer "B.Cu")
		(net "BRICK_P12V0_EN_N")
	)
	(segment
		(start 138.303 -114.44605)
		(end 139.086336 -114.44605)
		(width 0.17272)
		(layer "B.Cu")
		(net "BRICK_P12V0_EN_N")
	)
	(segment
		(start 143.002 -115.12296)
		(end 140.777214 -115.12296)
		(width 0.17272)
		(layer "B.Cu")
		(net "BRICK_P12V0_EN_N")
	)
	(segment
		(start 145.923 -114.44605)
		(end 146.15795 -114.681)
		(width 0.17272)
		(layer "B.Cu")
		(net "BRICK_P12V0_EN_N")
	)
	(segment
		(start 139.549632 -114.422682)
		(end 139.573 -114.44605)
		(width 0.17272)
		(layer "B.Cu")
		(net "BRICK_P12V0_EN_N")
	)
	(segment
		(start 140.076936 -114.422682)
		(end 139.596368 -114.422682)
		(width 0.17272)
		(layer "B.Cu")
		(net "BRICK_P12V0_EN_N")
	)
	(segment
		(start 140.777214 -115.12296)
		(end 140.076936 -114.422682)
		(width 0.17272)
		(layer "B.Cu")
		(net "BRICK_P12V0_EN_N")
	)
	(segment
		(start 144.653 -114.44605)
		(end 145.923 -114.44605)
		(width 0.17272)
		(layer "B.Cu")
		(net "BRICK_P12V0_EN_N")
	)
	(segment
		(start 143.97609 -115.12296)
		(end 144.653 -114.44605)
		(width 0.17272)
		(layer "B.Cu")
		(net "BRICK_P12V0_EN_N")
	)
	(segment
		(start 138.303 -114.44605)
		(end 136.85012 -114.44605)
		(width 0.17272)
		(layer "B.Cu")
		(net "BRICK_P12V0_EN_N")
	)
	(segment
		(start 136.85012 -67.869816)
		(end 136.85012 -74.493374)
		(width 0.17272)
		(layer "B.Cu")
		(net "SMB_BRICK0_ALERT")
	)
	(segment
		(start 137.17905 -74.822304)
		(end 137.17905 -76.327)
		(width 0.17272)
		(layer "B.Cu")
		(net "SMB_BRICK0_ALERT")
	)
	(segment
		(start 136.85012 -74.493374)
		(end 137.17905 -74.822304)
		(width 0.17272)
		(layer "B.Cu")
		(net "SMB_BRICK0_ALERT")
	)
	(segment
		(start 139.049506 -72.117712)
		(end 139.62761 -72.117712)
		(width 0.17272)
		(layer "B.Cu")
		(net "SMB_BRICK0_SCL")
	)
	(segment
		(start 138.850116 -72.997822)
		(end 138.850116 -74.33437)
		(width 0.17272)
		(layer "B.Cu")
		(net "SMB_BRICK0_SCL")
	)
	(segment
		(start 138.850116 -71.636382)
		(end 138.850116 -71.918322)
		(width 0.17272)
		(layer "B.Cu")
		(net "SMB_BRICK0_SCL")
	)
	(segment
		(start 139.827 -72.317102)
		(end 139.827 -72.599042)
		(width 0.17272)
		(layer "B.Cu")
		(net "SMB_BRICK0_SCL")
	)
	(segment
		(start 139.049506 -70.756272)
		(end 139.62761 -70.756272)
		(width 0.17272)
		(layer "B.Cu")
		(net "SMB_BRICK0_SCL")
	)
	(segment
		(start 139.827 -72.599042)
		(end 139.62761 -72.798432)
		(width 0.17272)
		(layer "B.Cu")
		(net "SMB_BRICK0_SCL")
	)
	(segment
		(start 138.850116 -74.33437)
		(end 139.46505 -74.949304)
		(width 0.17272)
		(layer "B.Cu")
		(net "SMB_BRICK0_SCL")
	)
	(segment
		(start 138.850116 -71.918322)
		(end 139.049506 -72.117712)
		(width 0.17272)
		(layer "B.Cu")
		(net "SMB_BRICK0_SCL")
	)
	(segment
		(start 139.62761 -70.756272)
		(end 139.827 -70.955662)
		(width 0.17272)
		(layer "B.Cu")
		(net "SMB_BRICK0_SCL")
	)
	(segment
		(start 139.62761 -71.436992)
		(end 139.049506 -71.436992)
		(width 0.17272)
		(layer "B.Cu")
		(net "SMB_BRICK0_SCL")
	)
	(segment
		(start 139.049506 -72.798432)
		(end 138.850116 -72.997822)
		(width 0.17272)
		(layer "B.Cu")
		(net "SMB_BRICK0_SCL")
	)
	(segment
		(start 139.827 -70.955662)
		(end 139.827 -71.237602)
		(width 0.17272)
		(layer "B.Cu")
		(net "SMB_BRICK0_SCL")
	)
	(segment
		(start 138.850116 -67.869816)
		(end 138.850116 -70.556882)
		(width 0.17272)
		(layer "B.Cu")
		(net "SMB_BRICK0_SCL")
	)
	(segment
		(start 139.46505 -74.949304)
		(end 139.46505 -76.327)
		(width 0.17272)
		(layer "B.Cu")
		(net "SMB_BRICK0_SCL")
	)
	(segment
		(start 139.62761 -72.798432)
		(end 139.049506 -72.798432)
		(width 0.17272)
		(layer "B.Cu")
		(net "SMB_BRICK0_SCL")
	)
	(segment
		(start 139.62761 -72.117712)
		(end 139.827 -72.317102)
		(width 0.17272)
		(layer "B.Cu")
		(net "SMB_BRICK0_SCL")
	)
	(segment
		(start 139.827 -71.237602)
		(end 139.62761 -71.436992)
		(width 0.17272)
		(layer "B.Cu")
		(net "SMB_BRICK0_SCL")
	)
	(segment
		(start 138.850116 -70.556882)
		(end 139.049506 -70.756272)
		(width 0.17272)
		(layer "B.Cu")
		(net "SMB_BRICK0_SCL")
	)
	(segment
		(start 139.049506 -71.436992)
		(end 138.850116 -71.636382)
		(width 0.17272)
		(layer "B.Cu")
		(net "SMB_BRICK0_SCL")
	)
	(segment
		(start 134.89305 -67.912742)
		(end 134.850124 -67.869816)
		(width 0.17272)
		(layer "B.Cu")
		(net "SMB_BRICK0_SDA")
	)
	(segment
		(start 134.89305 -76.327)
		(end 134.89305 -67.912742)
		(width 0.17272)
		(layer "B.Cu")
		(net "SMB_BRICK0_SDA")
	)
	(segment
		(start 132.59816 -81.63814)
		(end 141.11986 -81.63814)
		(width 0.4572)
		(layer "B.Cu")
		(net "P12V_MB0_SENSE+")
	)
	(segment
		(start 103.886 -76.30795)
		(end 127.26797 -76.30795)
		(width 0.4572)
		(layer "B.Cu")
		(net "P12V_MB0_SENSE+")
	)
	(segment
		(start 142.850108 -76.30795)
		(end 142.850108 -75.285854)
		(width 0.4572)
		(layer "B.Cu")
		(net "P12V_MB0_SENSE+")
	)
	(segment
		(start 141.7066 -77.0636)
		(end 142.46225 -76.30795)
		(width 0.4572)
		(layer "B.Cu")
		(net "P12V_MB0_SENSE+")
	)
	(segment
		(start 142.46225 -76.30795)
		(end 142.850108 -76.30795)
		(width 0.4572)
		(layer "B.Cu")
		(net "P12V_MB0_SENSE+")
	)
	(segment
		(start 141.11986 -81.63814)
		(end 141.7066 -81.0514)
		(width 0.4572)
		(layer "B.Cu")
		(net "P12V_MB0_SENSE+")
	)
	(segment
		(start 141.859 -68.860924)
		(end 142.850108 -67.869816)
		(width 0.4572)
		(layer "B.Cu")
		(net "P12V_MB0_SENSE+")
	)
	(segment
		(start 127.26797 -76.30795)
		(end 132.59816 -81.63814)
		(width 0.4572)
		(layer "B.Cu")
		(net "P12V_MB0_SENSE+")
	)
	(segment
		(start 141.7066 -81.0514)
		(end 141.7066 -77.0636)
		(width 0.4572)
		(layer "B.Cu")
		(net "P12V_MB0_SENSE+")
	)
	(segment
		(start 142.850108 -75.285854)
		(end 141.859 -74.294746)
		(width 0.4572)
		(layer "B.Cu")
		(net "P12V_MB0_SENSE+")
	)
	(segment
		(start 141.859 -74.294746)
		(end 141.859 -68.860924)
		(width 0.4572)
		(layer "B.Cu")
		(net "P12V_MB0_SENSE+")
	)
	(via
		(at 231.391968 -91.71305)
		(size 0.508)
		(drill 0.254)
		(layers "F.Cu" "B.Cu")
		(net "RST_SMB_PDB_BUF_N")
	)
	(via
		(at 198.501 -92.1258)
		(size 0.508)
		(drill 0.254)
		(layers "F.Cu" "B.Cu")
		(net "RST_SMB_PDB_BUF_N")
	)
	(via
		(at 16.112744 -89.906348)
		(size 0.508)
		(drill 0.254)
		(layers "F.Cu" "B.Cu")
		(net "RST_SMB_PDB_BUF_N")
	)
	(segment
		(start 179.197 -86.3854)
		(end 187.624212 -94.812612)
		(width 0.17272)
		(layer "B.Cu")
		(net "RST_SMB_PDB_BUF_N")
	)
	(segment
		(start 231.391968 -91.71305)
		(end 232.537 -91.71305)
		(width 0.17272)
		(layer "B.Cu")
		(net "RST_SMB_PDB_BUF_N")
	)
	(segment
		(start 152.575514 -86.3854)
		(end 179.197 -86.3854)
		(width 0.17272)
		(layer "B.Cu")
		(net "RST_SMB_PDB_BUF_N")
	)
	(segment
		(start 149.054566 -89.906348)
		(end 152.575514 -86.3854)
		(width 0.17272)
		(layer "B.Cu")
		(net "RST_SMB_PDB_BUF_N")
	)
	(segment
		(start 197.53707 -94.09303)
		(end 197.53707 -94.07398)
		(width 0.17272)
		(layer "B.Cu")
		(net "RST_SMB_PDB_BUF_N")
	)
	(segment
		(start 195.398644 -94.812612)
		(end 195.798948 -94.412308)
		(width 0.17272)
		(layer "B.Cu")
		(net "RST_SMB_PDB_BUF_N")
	)
	(segment
		(start 232.537 -91.71305)
		(end 233.68 -91.71305)
		(width 0.17272)
		(layer "B.Cu")
		(net "RST_SMB_PDB_BUF_N")
	)
	(segment
		(start 198.501 -93.11005)
		(end 198.501 -92.1258)
		(width 0.17272)
		(layer "B.Cu")
		(net "RST_SMB_PDB_BUF_N")
	)
	(segment
		(start 197.75805 -93.853)
		(end 198.501 -93.11005)
		(width 0.17272)
		(layer "B.Cu")
		(net "RST_SMB_PDB_BUF_N")
	)
	(segment
		(start 16.112744 -89.906348)
		(end 149.054566 -89.906348)
		(width 0.17272)
		(layer "B.Cu")
		(net "RST_SMB_PDB_BUF_N")
	)
	(segment
		(start 187.624212 -94.812612)
		(end 195.398644 -94.812612)
		(width 0.17272)
		(layer "B.Cu")
		(net "RST_SMB_PDB_BUF_N")
	)
	(segment
		(start 197.53707 -94.07398)
		(end 197.75805 -93.853)
		(width 0.17272)
		(layer "B.Cu")
		(net "RST_SMB_PDB_BUF_N")
	)
	(segment
		(start 195.798948 -94.412308)
		(end 197.217792 -94.412308)
		(width 0.17272)
		(layer "B.Cu")
		(net "RST_SMB_PDB_BUF_N")
	)
	(segment
		(start 197.217792 -94.412308)
		(end 197.53707 -94.09303)
		(width 0.17272)
		(layer "B.Cu")
		(net "RST_SMB_PDB_BUF_N")
	)
	(segment
		(start 198.501 -92.1258)
		(end 201.143616 -92.1258)
		(width 0.12954)
		(layer "In7.Cu")
		(net "RST_SMB_PDB_BUF_N")
	)
	(segment
		(start 14.605 -83.037426)
		(end 12.455652 -81.275428)
		(width 0.12954)
		(layer "In7.Cu")
		(net "RST_SMB_PDB_BUF_N")
	)
	(segment
		(start 203.480416 -89.789)
		(end 208.153 -89.789)
		(width 0.12954)
		(layer "In7.Cu")
		(net "RST_SMB_PDB_BUF_N")
	)
	(segment
		(start 12.455652 -81.275428)
		(end 12.39012 -81.209896)
		(width 0.12954)
		(layer "In7.Cu")
		(net "RST_SMB_PDB_BUF_N")
	)
	(segment
		(start 219.64777 -92.39377)
		(end 230.711248 -92.39377)
		(width 0.12954)
		(layer "In7.Cu")
		(net "RST_SMB_PDB_BUF_N")
	)
	(segment
		(start 209.23377 -88.70823)
		(end 215.96223 -88.70823)
		(width 0.12954)
		(layer "In7.Cu")
		(net "RST_SMB_PDB_BUF_N")
	)
	(segment
		(start 215.96223 -88.70823)
		(end 219.64777 -92.39377)
		(width 0.12954)
		(layer "In7.Cu")
		(net "RST_SMB_PDB_BUF_N")
	)
	(segment
		(start 14.605 -88.398604)
		(end 14.605 -83.037426)
		(width 0.12954)
		(layer "In7.Cu")
		(net "RST_SMB_PDB_BUF_N")
	)
	(segment
		(start 16.112744 -89.906348)
		(end 14.605 -88.398604)
		(width 0.12954)
		(layer "In7.Cu")
		(net "RST_SMB_PDB_BUF_N")
	)
	(segment
		(start 208.153 -89.789)
		(end 209.23377 -88.70823)
		(width 0.12954)
		(layer "In7.Cu")
		(net "RST_SMB_PDB_BUF_N")
	)
	(segment
		(start 201.143616 -92.1258)
		(end 203.480416 -89.789)
		(width 0.12954)
		(layer "In7.Cu")
		(net "RST_SMB_PDB_BUF_N")
	)
	(segment
		(start 230.711248 -92.39377)
		(end 231.391968 -91.71305)
		(width 0.12954)
		(layer "In7.Cu")
		(net "RST_SMB_PDB_BUF_N")
	)
	(via
		(at 147.061936 -111.252)
		(size 0.6604)
		(drill 0.3302)
		(layers "F.Cu" "B.Cu")
		(net "BRICK_P12V0_EN_R_N")
	)
	(segment
		(start 147.08505 -110.109)
		(end 147.061936 -110.132114)
		(width 0.17272)
		(layer "B.Cu")
		(net "BRICK_P12V0_EN_R_N")
	)
	(segment
		(start 146.173952 -113.64595)
		(end 144.653 -113.64595)
		(width 0.17272)
		(layer "B.Cu")
		(net "BRICK_P12V0_EN_R_N")
	)
	(segment
		(start 147.061936 -111.252)
		(end 147.061936 -113.050066)
		(width 0.17272)
		(layer "B.Cu")
		(net "BRICK_P12V0_EN_R_N")
	)
	(segment
		(start 147.061936 -110.132114)
		(end 147.061936 -111.252)
		(width 0.17272)
		(layer "B.Cu")
		(net "BRICK_P12V0_EN_R_N")
	)
	(segment
		(start 147.061936 -113.050066)
		(end 146.320002 -113.792)
		(width 0.17272)
		(layer "B.Cu")
		(net "BRICK_P12V0_EN_R_N")
	)
	(segment
		(start 146.320002 -113.792)
		(end 146.173952 -113.64595)
		(width 0.17272)
		(layer "B.Cu")
		(net "BRICK_P12V0_EN_R_N")
	)
	(segment
		(start 108.279946 -70.409816)
		(end 109.561376 -71.691246)
		(width 0.889)
		(layer "F.Cu")
		(net "P12V_BRICK")
	)
	(segment
		(start 146.99869 -69.128386)
		(end 148.28012 -70.409816)
		(width 0.889)
		(layer "F.Cu")
		(net "P12V_BRICK")
	)
	(segment
		(start 130.250692 -61.900308)
		(end 131.191 -60.96)
		(width 0.635)
		(layer "F.Cu")
		(net "P12V_BRICK")
	)
	(segment
		(start 144.47012 -70.409816)
		(end 145.75155 -71.691246)
		(width 0.889)
		(layer "F.Cu")
		(net "P12V_BRICK")
	)
	(segment
		(start 90.678 -60.96)
		(end 91.618308 -60.019692)
		(width 0.635)
		(layer "F.Cu")
		(net "P12V_BRICK")
	)
	(segment
		(start 79.375 -60.96)
		(end 80.315308 -60.019692)
		(width 0.635)
		(layer "F.Cu")
		(net "P12V_BRICK")
	)
	(segment
		(start 146.99869 -71.691246)
		(end 148.28012 -70.409816)
		(width 0.889)
		(layer "F.Cu")
		(net "P12V_BRICK")
	)
	(segment
		(start 143.18869 -71.691246)
		(end 144.47012 -70.409816)
		(width 0.889)
		(layer "F.Cu")
		(net "P12V_BRICK")
	)
	(segment
		(start 143.18869 -69.128386)
		(end 144.47012 -70.409816)
		(width 0.889)
		(layer "F.Cu")
		(net "P12V_BRICK")
	)
	(segment
		(start 169.291 -60.96)
		(end 170.231308 -61.900308)
		(width 0.635)
		(layer "F.Cu")
		(net "P12V_BRICK")
	)
	(segment
		(start 67.131692 -60.019692)
		(end 68.072 -60.96)
		(width 0.635)
		(layer "F.Cu")
		(net "P12V_BRICK")
	)
	(segment
		(start 145.998692 -61.900308)
		(end 146.939 -60.96)
		(width 0.635)
		(layer "F.Cu")
		(net "P12V_BRICK")
	)
	(segment
		(start 145.998692 -60.019692)
		(end 146.939 -60.96)
		(width 0.635)
		(layer "F.Cu")
		(net "P12V_BRICK")
	)
	(segment
		(start 197.174866 -61.900308)
		(end 198.115174 -60.96)
		(width 0.635)
		(layer "F.Cu")
		(net "P12V_BRICK")
	)
	(segment
		(start 66.998596 -71.691246)
		(end 68.280026 -70.409816)
		(width 0.889)
		(layer "F.Cu")
		(net "P12V_BRICK")
	)
	(segment
		(start 119.074692 -60.019692)
		(end 120.015 -60.96)
		(width 0.635)
		(layer "F.Cu")
		(net "P12V_BRICK")
	)
	(segment
		(start 67.131692 -61.900308)
		(end 68.072 -60.96)
		(width 0.635)
		(layer "F.Cu")
		(net "P12V_BRICK")
	)
	(segment
		(start 209.291174 -60.96)
		(end 210.231482 -60.019692)
		(width 0.635)
		(layer "F.Cu")
		(net "P12V_BRICK")
	)
	(segment
		(start 209.291174 -60.96)
		(end 210.231482 -61.900308)
		(width 0.635)
		(layer "F.Cu")
		(net "P12V_BRICK")
	)
	(segment
		(start 186.998864 -71.691246)
		(end 188.280294 -70.409816)
		(width 0.889)
		(layer "F.Cu")
		(net "P12V_BRICK")
	)
	(segment
		(start 184.470294 -70.409816)
		(end 185.751724 -69.128386)
		(width 0.889)
		(layer "F.Cu")
		(net "P12V_BRICK")
	)
	(segment
		(start 148.28012 -70.409816)
		(end 149.56155 -71.691246)
		(width 0.889)
		(layer "F.Cu")
		(net "P12V_BRICK")
	)
	(segment
		(start 183.188864 -69.128386)
		(end 184.470294 -70.409816)
		(width 0.889)
		(layer "F.Cu")
		(net "P12V_BRICK")
	)
	(segment
		(start 63.188596 -69.128386)
		(end 64.470026 -70.409816)
		(width 0.889)
		(layer "F.Cu")
		(net "P12V_BRICK")
	)
	(segment
		(start 208.350866 -61.900308)
		(end 209.291174 -60.96)
		(width 0.635)
		(layer "F.Cu")
		(net "P12V_BRICK")
	)
	(segment
		(start 108.839 -60.96)
		(end 109.779308 -61.900308)
		(width 0.635)
		(layer "F.Cu")
		(net "P12V_BRICK")
	)
	(segment
		(start 168.350692 -61.900308)
		(end 169.291 -60.96)
		(width 0.635)
		(layer "F.Cu")
		(net "P12V_BRICK")
	)
	(segment
		(start 186.939174 -60.96)
		(end 187.879482 -61.900308)
		(width 0.635)
		(layer "F.Cu")
		(net "P12V_BRICK")
	)
	(segment
		(start 131.191 -60.96)
		(end 132.131308 -60.019692)
		(width 0.635)
		(layer "F.Cu")
		(net "P12V_BRICK")
	)
	(segment
		(start 104.469946 -70.409816)
		(end 105.751376 -69.128386)
		(width 0.889)
		(layer "F.Cu")
		(net "P12V_BRICK")
	)
	(segment
		(start 89.737692 -60.019692)
		(end 90.678 -60.96)
		(width 0.635)
		(layer "F.Cu")
		(net "P12V_BRICK")
	)
	(segment
		(start 146.939 -60.96)
		(end 147.879308 -61.900308)
		(width 0.635)
		(layer "F.Cu")
		(net "P12V_BRICK")
	)
	(segment
		(start 158.115 -60.96)
		(end 159.055308 -60.019692)
		(width 0.635)
		(layer "F.Cu")
		(net "P12V_BRICK")
	)
	(segment
		(start 198.115174 -60.96)
		(end 199.055482 -61.900308)
		(width 0.635)
		(layer "F.Cu")
		(net "P12V_BRICK")
	)
	(segment
		(start 119.074692 -61.900308)
		(end 120.015 -60.96)
		(width 0.635)
		(layer "F.Cu")
		(net "P12V_BRICK")
	)
	(segment
		(start 106.998516 -71.691246)
		(end 108.279946 -70.409816)
		(width 0.889)
		(layer "F.Cu")
		(net "P12V_BRICK")
	)
	(segment
		(start 68.072 -60.96)
		(end 69.012308 -60.019692)
		(width 0.635)
		(layer "F.Cu")
		(net "P12V_BRICK")
	)
	(segment
		(start 79.375 -60.96)
		(end 80.315308 -61.900308)
		(width 0.635)
		(layer "F.Cu")
		(net "P12V_BRICK")
	)
	(segment
		(start 120.015 -60.96)
		(end 120.955308 -61.900308)
		(width 0.635)
		(layer "F.Cu")
		(net "P12V_BRICK")
	)
	(segment
		(start 103.188516 -69.128386)
		(end 104.469946 -70.409816)
		(width 0.889)
		(layer "F.Cu")
		(net "P12V_BRICK")
	)
	(segment
		(start 197.174866 -60.019692)
		(end 198.115174 -60.96)
		(width 0.635)
		(layer "F.Cu")
		(net "P12V_BRICK")
	)
	(segment
		(start 107.898692 -60.019692)
		(end 108.839 -60.96)
		(width 0.635)
		(layer "F.Cu")
		(net "P12V_BRICK")
	)
	(segment
		(start 188.280294 -70.409816)
		(end 189.561724 -69.128386)
		(width 0.889)
		(layer "F.Cu")
		(net "P12V_BRICK")
	)
	(segment
		(start 146.939 -60.96)
		(end 147.879308 -60.019692)
		(width 0.635)
		(layer "F.Cu")
		(net "P12V_BRICK")
	)
	(segment
		(start 68.280026 -70.409816)
		(end 69.561456 -71.691246)
		(width 0.889)
		(layer "F.Cu")
		(net "P12V_BRICK")
	)
	(segment
		(start 104.469946 -70.409816)
		(end 105.751376 -71.691246)
		(width 0.889)
		(layer "F.Cu")
		(net "P12V_BRICK")
	)
	(segment
		(start 90.678 -60.96)
		(end 91.618308 -61.900308)
		(width 0.635)
		(layer "F.Cu")
		(net "P12V_BRICK")
	)
	(segment
		(start 208.350866 -60.019692)
		(end 209.291174 -60.96)
		(width 0.635)
		(layer "F.Cu")
		(net "P12V_BRICK")
	)
	(segment
		(start 89.737692 -61.900308)
		(end 90.678 -60.96)
		(width 0.635)
		(layer "F.Cu")
		(net "P12V_BRICK")
	)
	(segment
		(start 168.350692 -60.019692)
		(end 169.291 -60.96)
		(width 0.635)
		(layer "F.Cu")
		(net "P12V_BRICK")
	)
	(segment
		(start 106.998516 -69.128386)
		(end 108.279946 -70.409816)
		(width 0.889)
		(layer "F.Cu")
		(net "P12V_BRICK")
	)
	(segment
		(start 64.470026 -70.409816)
		(end 65.751456 -71.691246)
		(width 0.889)
		(layer "F.Cu")
		(net "P12V_BRICK")
	)
	(segment
		(start 107.898692 -61.900308)
		(end 108.839 -60.96)
		(width 0.635)
		(layer "F.Cu")
		(net "P12V_BRICK")
	)
	(segment
		(start 185.998866 -60.019692)
		(end 186.939174 -60.96)
		(width 0.635)
		(layer "F.Cu")
		(net "P12V_BRICK")
	)
	(segment
		(start 186.939174 -60.96)
		(end 187.879482 -60.019692)
		(width 0.635)
		(layer "F.Cu")
		(net "P12V_BRICK")
	)
	(segment
		(start 66.998596 -69.128386)
		(end 68.280026 -70.409816)
		(width 0.889)
		(layer "F.Cu")
		(net "P12V_BRICK")
	)
	(segment
		(start 184.470294 -70.409816)
		(end 185.751724 -71.691246)
		(width 0.889)
		(layer "F.Cu")
		(net "P12V_BRICK")
	)
	(segment
		(start 157.174692 -60.019692)
		(end 158.115 -60.96)
		(width 0.635)
		(layer "F.Cu")
		(net "P12V_BRICK")
	)
	(segment
		(start 64.470026 -70.409816)
		(end 65.751456 -69.128386)
		(width 0.889)
		(layer "F.Cu")
		(net "P12V_BRICK")
	)
	(segment
		(start 188.280294 -70.409816)
		(end 189.561724 -71.691246)
		(width 0.889)
		(layer "F.Cu")
		(net "P12V_BRICK")
	)
	(segment
		(start 144.47012 -70.409816)
		(end 145.75155 -69.128386)
		(width 0.889)
		(layer "F.Cu")
		(net "P12V_BRICK")
	)
	(segment
		(start 131.191 -60.96)
		(end 132.131308 -61.900308)
		(width 0.635)
		(layer "F.Cu")
		(net "P12V_BRICK")
	)
	(segment
		(start 68.072 -60.96)
		(end 69.012308 -61.900308)
		(width 0.635)
		(layer "F.Cu")
		(net "P12V_BRICK")
	)
	(segment
		(start 78.434692 -61.900308)
		(end 79.375 -60.96)
		(width 0.635)
		(layer "F.Cu")
		(net "P12V_BRICK")
	)
	(segment
		(start 63.188596 -71.691246)
		(end 64.470026 -70.409816)
		(width 0.889)
		(layer "F.Cu")
		(net "P12V_BRICK")
	)
	(segment
		(start 185.998866 -61.900308)
		(end 186.939174 -60.96)
		(width 0.635)
		(layer "F.Cu")
		(net "P12V_BRICK")
	)
	(segment
		(start 186.998864 -69.128386)
		(end 188.280294 -70.409816)
		(width 0.889)
		(layer "F.Cu")
		(net "P12V_BRICK")
	)
	(segment
		(start 157.174692 -61.900308)
		(end 158.115 -60.96)
		(width 0.635)
		(layer "F.Cu")
		(net "P12V_BRICK")
	)
	(segment
		(start 78.434692 -60.019692)
		(end 79.375 -60.96)
		(width 0.635)
		(layer "F.Cu")
		(net "P12V_BRICK")
	)
	(segment
		(start 169.291 -60.96)
		(end 170.231308 -60.019692)
		(width 0.635)
		(layer "F.Cu")
		(net "P12V_BRICK")
	)
	(segment
		(start 158.115 -60.96)
		(end 159.055308 -61.900308)
		(width 0.635)
		(layer "F.Cu")
		(net "P12V_BRICK")
	)
	(segment
		(start 183.188864 -71.691246)
		(end 184.470294 -70.409816)
		(width 0.889)
		(layer "F.Cu")
		(net "P12V_BRICK")
	)
	(segment
		(start 68.280026 -70.409816)
		(end 69.561456 -69.128386)
		(width 0.889)
		(layer "F.Cu")
		(net "P12V_BRICK")
	)
	(segment
		(start 148.28012 -70.409816)
		(end 149.56155 -69.128386)
		(width 0.889)
		(layer "F.Cu")
		(net "P12V_BRICK")
	)
	(segment
		(start 108.279946 -70.409816)
		(end 109.561376 -69.128386)
		(width 0.889)
		(layer "F.Cu")
		(net "P12V_BRICK")
	)
	(segment
		(start 108.839 -60.96)
		(end 109.779308 -60.019692)
		(width 0.635)
		(layer "F.Cu")
		(net "P12V_BRICK")
	)
	(segment
		(start 130.250692 -60.019692)
		(end 131.191 -60.96)
		(width 0.635)
		(layer "F.Cu")
		(net "P12V_BRICK")
	)
	(segment
		(start 198.115174 -60.96)
		(end 199.055482 -60.019692)
		(width 0.635)
		(layer "F.Cu")
		(net "P12V_BRICK")
	)
	(segment
		(start 103.188516 -71.691246)
		(end 104.469946 -70.409816)
		(width 0.889)
		(layer "F.Cu")
		(net "P12V_BRICK")
	)
	(segment
		(start 120.015 -60.96)
		(end 120.955308 -60.019692)
		(width 0.635)
		(layer "F.Cu")
		(net "P12V_BRICK")
	)
	(via
		(at 104.648 -50.419)
		(size 0.508)
		(drill 0.254)
		(layers "F.Cu" "B.Cu")
		(net "P12V_BRICK")
	)
	(via
		(at 70.413626 -70.885812)
		(size 0.508)
		(drill 0.254)
		(layers "F.Cu" "B.Cu")
		(net "P12V_BRICK")
	)
	(via
		(at 70.413626 -69.869812)
		(size 0.508)
		(drill 0.254)
		(layers "F.Cu" "B.Cu")
		(net "P12V_BRICK")
	)
	(via
		(at 72.445626 -71.901812)
		(size 0.508)
		(drill 0.254)
		(layers "F.Cu" "B.Cu")
		(net "P12V_BRICK")
	)
	(via
		(at 162.8394 -12.2174)
		(size 0.508)
		(drill 0.254)
		(layers "F.Cu" "B.Cu")
		(net "P12V_BRICK")
	)
	(via
		(at 182.75046 -49.657)
		(size 0.508)
		(drill 0.254)
		(layers "F.Cu" "B.Cu")
		(net "P12V_BRICK")
	)
	(via
		(at 166.37 -50.292)
		(size 0.508)
		(drill 0.254)
		(layers "F.Cu" "B.Cu")
		(net "P12V_BRICK")
	)
	(via
		(at 88.265 -52.324)
		(size 0.508)
		(drill 0.254)
		(layers "F.Cu" "B.Cu")
		(net "P12V_BRICK")
	)
	(via
		(at 42.58564 -54.1147)
		(size 0.508)
		(drill 0.254)
		(layers "F.Cu" "B.Cu")
		(net "P12V_BRICK")
	)
	(via
		(at 104.648 -51.689)
		(size 0.508)
		(drill 0.254)
		(layers "F.Cu" "B.Cu")
		(net "P12V_BRICK")
	)
	(via
		(at 49.31664 -52.1208)
		(size 0.508)
		(drill 0.254)
		(layers "F.Cu" "B.Cu")
		(net "P12V_BRICK")
	)
	(via
		(at 160.909 -49.657)
		(size 0.508)
		(drill 0.254)
		(layers "F.Cu" "B.Cu")
		(net "P12V_BRICK")
	)
	(via
		(at 39.32936 -62.16142)
		(size 0.508)
		(drill 0.254)
		(layers "F.Cu" "B.Cu")
		(net "P12V_BRICK")
	)
	(via
		(at 171.831 -51.562)
		(size 0.508)
		(drill 0.254)
		(layers "F.Cu" "B.Cu")
		(net "P12V_BRICK")
	)
	(via
		(at 41.9989 -58.604912)
		(size 0.4572)
		(drill 0.254)
		(layers "F.Cu" "B.Cu")
		(net "P12V_BRICK")
	)
	(via
		(at 45.58284 -50.0507)
		(size 0.508)
		(drill 0.254)
		(layers "F.Cu" "B.Cu")
		(net "P12V_BRICK")
	)
	(via
		(at 155.448 -51.562)
		(size 0.508)
		(drill 0.254)
		(layers "F.Cu" "B.Cu")
		(net "P12V_BRICK")
	)
	(via
		(at 71.882 -50.419)
		(size 0.508)
		(drill 0.254)
		(layers "F.Cu" "B.Cu")
		(net "P12V_BRICK")
	)
	(via
		(at 71.882 -49.784)
		(size 0.508)
		(drill 0.254)
		(layers "F.Cu" "B.Cu")
		(net "P12V_BRICK")
	)
	(via
		(at 166.37 -52.197)
		(size 0.508)
		(drill 0.254)
		(layers "F.Cu" "B.Cu")
		(net "P12V_BRICK")
	)
	(via
		(at 142.850108 -77.71765)
		(size 0.508)
		(drill 0.254)
		(layers "F.Cu" "B.Cu")
		(net "P12V_BRICK")
	)
	(via
		(at 112.394746 -69.897244)
		(size 0.508)
		(drill 0.254)
		(layers "F.Cu" "B.Cu")
		(net "P12V_BRICK")
	)
	(via
		(at 112.394746 -71.929244)
		(size 0.508)
		(drill 0.254)
		(layers "F.Cu" "B.Cu")
		(net "P12V_BRICK")
	)
	(via
		(at 182.75046 -51.562)
		(size 0.508)
		(drill 0.254)
		(layers "F.Cu" "B.Cu")
		(net "P12V_BRICK")
	)
	(via
		(at 82.804 -52.324)
		(size 0.508)
		(drill 0.254)
		(layers "F.Cu" "B.Cu")
		(net "P12V_BRICK")
	)
	(via
		(at 93.726 -52.324)
		(size 0.508)
		(drill 0.254)
		(layers "F.Cu" "B.Cu")
		(net "P12V_BRICK")
	)
	(via
		(at 110.362746 -71.929244)
		(size 0.508)
		(drill 0.254)
		(layers "F.Cu" "B.Cu")
		(net "P12V_BRICK")
	)
	(via
		(at 110.362746 -69.897244)
		(size 0.508)
		(drill 0.254)
		(layers "F.Cu" "B.Cu")
		(net "P12V_BRICK")
	)
	(via
		(at 41.3639 -57.70499)
		(size 0.4572)
		(drill 0.254)
		(layers "F.Cu" "B.Cu")
		(net "P12V_BRICK")
	)
	(via
		(at 41.9989 -55.904892)
		(size 0.4572)
		(drill 0.254)
		(layers "F.Cu" "B.Cu")
		(net "P12V_BRICK")
	)
	(via
		(at 149.987 -50.292)
		(size 0.508)
		(drill 0.254)
		(layers "F.Cu" "B.Cu")
		(net "P12V_BRICK")
	)
	(via
		(at 111.378746 -70.913244)
		(size 0.508)
		(drill 0.254)
		(layers "F.Cu" "B.Cu")
		(net "P12V_BRICK")
	)
	(via
		(at 41.84904 -53.3019)
		(size 0.508)
		(drill 0.254)
		(layers "F.Cu" "B.Cu")
		(net "P12V_BRICK")
	)
	(via
		(at 171.831 -49.657)
		(size 0.508)
		(drill 0.254)
		(layers "F.Cu" "B.Cu")
		(net "P12V_BRICK")
	)
	(via
		(at 47.05604 -52.9209)
		(size 0.508)
		(drill 0.254)
		(layers "F.Cu" "B.Cu")
		(net "P12V_BRICK")
	)
	(via
		(at 112.394746 -70.913244)
		(size 0.508)
		(drill 0.254)
		(layers "F.Cu" "B.Cu")
		(net "P12V_BRICK")
	)
	(via
		(at 50.84064 -52.1208)
		(size 0.508)
		(drill 0.254)
		(layers "F.Cu" "B.Cu")
		(net "P12V_BRICK")
	)
	(via
		(at 77.343 -50.419)
		(size 0.508)
		(drill 0.254)
		(layers "F.Cu" "B.Cu")
		(net "P12V_BRICK")
	)
	(via
		(at 102.849934 -77.71765)
		(size 0.508)
		(drill 0.254)
		(layers "F.Cu" "B.Cu")
		(net "P12V_BRICK")
	)
	(via
		(at 82.804 -51.689)
		(size 0.508)
		(drill 0.254)
		(layers "F.Cu" "B.Cu")
		(net "P12V_BRICK")
	)
	(via
		(at 72.445626 -69.869812)
		(size 0.508)
		(drill 0.254)
		(layers "F.Cu" "B.Cu")
		(net "P12V_BRICK")
	)
	(via
		(at 177.28946 -49.657)
		(size 0.508)
		(drill 0.254)
		(layers "F.Cu" "B.Cu")
		(net "P12V_BRICK")
	)
	(via
		(at 99.187 -50.419)
		(size 0.508)
		(drill 0.254)
		(layers "F.Cu" "B.Cu")
		(net "P12V_BRICK")
	)
	(via
		(at 46.29404 -50.0507)
		(size 0.508)
		(drill 0.254)
		(layers "F.Cu" "B.Cu")
		(net "P12V_BRICK")
	)
	(via
		(at 44.84624 -50.0507)
		(size 0.508)
		(drill 0.254)
		(layers "F.Cu" "B.Cu")
		(net "P12V_BRICK")
	)
	(via
		(at 160.909 -50.292)
		(size 0.508)
		(drill 0.254)
		(layers "F.Cu" "B.Cu")
		(net "P12V_BRICK")
	)
	(via
		(at 71.429626 -71.901812)
		(size 0.508)
		(drill 0.254)
		(layers "F.Cu" "B.Cu")
		(net "P12V_BRICK")
	)
	(via
		(at 93.726 -51.689)
		(size 0.508)
		(drill 0.254)
		(layers "F.Cu" "B.Cu")
		(net "P12V_BRICK")
	)
	(via
		(at 99.187 -52.324)
		(size 0.508)
		(drill 0.254)
		(layers "F.Cu" "B.Cu")
		(net "P12V_BRICK")
	)
	(via
		(at 71.882 -51.689)
		(size 0.508)
		(drill 0.254)
		(layers "F.Cu" "B.Cu")
		(net "P12V_BRICK")
	)
	(via
		(at 177.28946 -52.197)
		(size 0.508)
		(drill 0.254)
		(layers "F.Cu" "B.Cu")
		(net "P12V_BRICK")
	)
	(via
		(at 44.36364 -52.2859)
		(size 0.508)
		(drill 0.254)
		(layers "F.Cu" "B.Cu")
		(net "P12V_BRICK")
	)
	(via
		(at 182.850282 -77.71765)
		(size 0.508)
		(drill 0.254)
		(layers "F.Cu" "B.Cu")
		(net "P12V_BRICK")
	)
	(via
		(at 41.3639 -58.604912)
		(size 0.4572)
		(drill 0.254)
		(layers "F.Cu" "B.Cu")
		(net "P12V_BRICK")
	)
	(via
		(at 41.9989 -57.70499)
		(size 0.4572)
		(drill 0.254)
		(layers "F.Cu" "B.Cu")
		(net "P12V_BRICK")
	)
	(via
		(at 93.726 -50.419)
		(size 0.508)
		(drill 0.254)
		(layers "F.Cu" "B.Cu")
		(net "P12V_BRICK")
	)
	(via
		(at 177.28946 -51.562)
		(size 0.508)
		(drill 0.254)
		(layers "F.Cu" "B.Cu")
		(net "P12V_BRICK")
	)
	(via
		(at 44.36364 -51.4731)
		(size 0.508)
		(drill 0.254)
		(layers "F.Cu" "B.Cu")
		(net "P12V_BRICK")
	)
	(via
		(at 88.265 -51.689)
		(size 0.508)
		(drill 0.254)
		(layers "F.Cu" "B.Cu")
		(net "P12V_BRICK")
	)
	(via
		(at 160.909 -52.197)
		(size 0.508)
		(drill 0.254)
		(layers "F.Cu" "B.Cu")
		(net "P12V_BRICK")
	)
	(via
		(at 88.265 -50.419)
		(size 0.508)
		(drill 0.254)
		(layers "F.Cu" "B.Cu")
		(net "P12V_BRICK")
	)
	(via
		(at 72.445626 -68.853812)
		(size 0.508)
		(drill 0.254)
		(layers "F.Cu" "B.Cu")
		(net "P12V_BRICK")
	)
	(via
		(at 71.882 -52.324)
		(size 0.508)
		(drill 0.254)
		(layers "F.Cu" "B.Cu")
		(net "P12V_BRICK")
	)
	(via
		(at 182.75046 -52.197)
		(size 0.508)
		(drill 0.254)
		(layers "F.Cu" "B.Cu")
		(net "P12V_BRICK")
	)
	(via
		(at 162.1028 -11.176)
		(size 0.508)
		(drill 0.254)
		(layers "F.Cu" "B.Cu")
		(net "P12V_BRICK")
	)
	(via
		(at 111.378746 -68.881244)
		(size 0.508)
		(drill 0.254)
		(layers "F.Cu" "B.Cu")
		(net "P12V_BRICK")
	)
	(via
		(at 71.429626 -68.853812)
		(size 0.508)
		(drill 0.254)
		(layers "F.Cu" "B.Cu")
		(net "P12V_BRICK")
	)
	(via
		(at 149.987 -49.657)
		(size 0.508)
		(drill 0.254)
		(layers "F.Cu" "B.Cu")
		(net "P12V_BRICK")
	)
	(via
		(at 71.429626 -69.869812)
		(size 0.508)
		(drill 0.254)
		(layers "F.Cu" "B.Cu")
		(net "P12V_BRICK")
	)
	(via
		(at 110.362746 -70.913244)
		(size 0.508)
		(drill 0.254)
		(layers "F.Cu" "B.Cu")
		(net "P12V_BRICK")
	)
	(via
		(at 77.343 -49.784)
		(size 0.508)
		(drill 0.254)
		(layers "F.Cu" "B.Cu")
		(net "P12V_BRICK")
	)
	(via
		(at 77.343 -52.324)
		(size 0.508)
		(drill 0.254)
		(layers "F.Cu" "B.Cu")
		(net "P12V_BRICK")
	)
	(via
		(at 82.804 -49.784)
		(size 0.508)
		(drill 0.254)
		(layers "F.Cu" "B.Cu")
		(net "P12V_BRICK")
	)
	(via
		(at 99.187 -51.689)
		(size 0.508)
		(drill 0.254)
		(layers "F.Cu" "B.Cu")
		(net "P12V_BRICK")
	)
	(via
		(at 41.9989 -56.805068)
		(size 0.4572)
		(drill 0.254)
		(layers "F.Cu" "B.Cu")
		(net "P12V_BRICK")
	)
	(via
		(at 82.804 -50.419)
		(size 0.508)
		(drill 0.254)
		(layers "F.Cu" "B.Cu")
		(net "P12V_BRICK")
	)
	(via
		(at 104.648 -49.784)
		(size 0.508)
		(drill 0.254)
		(layers "F.Cu" "B.Cu")
		(net "P12V_BRICK")
	)
	(via
		(at 149.987 -51.562)
		(size 0.508)
		(drill 0.254)
		(layers "F.Cu" "B.Cu")
		(net "P12V_BRICK")
	)
	(via
		(at 112.394746 -68.881244)
		(size 0.508)
		(drill 0.254)
		(layers "F.Cu" "B.Cu")
		(net "P12V_BRICK")
	)
	(via
		(at 70.413626 -71.901812)
		(size 0.508)
		(drill 0.254)
		(layers "F.Cu" "B.Cu")
		(net "P12V_BRICK")
	)
	(via
		(at 50.84064 -52.8828)
		(size 0.508)
		(drill 0.254)
		(layers "F.Cu" "B.Cu")
		(net "P12V_BRICK")
	)
	(via
		(at 41.3639 -55.904892)
		(size 0.4572)
		(drill 0.254)
		(layers "F.Cu" "B.Cu")
		(net "P12V_BRICK")
	)
	(via
		(at 41.3639 -56.805068)
		(size 0.4572)
		(drill 0.254)
		(layers "F.Cu" "B.Cu")
		(net "P12V_BRICK")
	)
	(via
		(at 166.37 -51.562)
		(size 0.508)
		(drill 0.254)
		(layers "F.Cu" "B.Cu")
		(net "P12V_BRICK")
	)
	(via
		(at 62.850014 -77.71765)
		(size 0.508)
		(drill 0.254)
		(layers "F.Cu" "B.Cu")
		(net "P12V_BRICK")
	)
	(via
		(at 99.187 -49.784)
		(size 0.508)
		(drill 0.254)
		(layers "F.Cu" "B.Cu")
		(net "P12V_BRICK")
	)
	(via
		(at 162.7886 -10.7442)
		(size 0.508)
		(drill 0.254)
		(layers "F.Cu" "B.Cu")
		(net "P12V_BRICK")
	)
	(via
		(at 182.75046 -50.292)
		(size 0.508)
		(drill 0.254)
		(layers "F.Cu" "B.Cu")
		(net "P12V_BRICK")
	)
	(via
		(at 155.448 -52.197)
		(size 0.508)
		(drill 0.254)
		(layers "F.Cu" "B.Cu")
		(net "P12V_BRICK")
	)
	(via
		(at 171.831 -50.292)
		(size 0.508)
		(drill 0.254)
		(layers "F.Cu" "B.Cu")
		(net "P12V_BRICK")
	)
	(via
		(at 72.445626 -70.885812)
		(size 0.508)
		(drill 0.254)
		(layers "F.Cu" "B.Cu")
		(net "P12V_BRICK")
	)
	(via
		(at 155.448 -50.292)
		(size 0.508)
		(drill 0.254)
		(layers "F.Cu" "B.Cu")
		(net "P12V_BRICK")
	)
	(via
		(at 77.343 -51.689)
		(size 0.508)
		(drill 0.254)
		(layers "F.Cu" "B.Cu")
		(net "P12V_BRICK")
	)
	(via
		(at 155.448 -49.657)
		(size 0.508)
		(drill 0.254)
		(layers "F.Cu" "B.Cu")
		(net "P12V_BRICK")
	)
	(via
		(at 149.987 -52.197)
		(size 0.508)
		(drill 0.254)
		(layers "F.Cu" "B.Cu")
		(net "P12V_BRICK")
	)
	(via
		(at 49.31664 -52.8828)
		(size 0.508)
		(drill 0.254)
		(layers "F.Cu" "B.Cu")
		(net "P12V_BRICK")
	)
	(via
		(at 70.413626 -68.853812)
		(size 0.508)
		(drill 0.254)
		(layers "F.Cu" "B.Cu")
		(net "P12V_BRICK")
	)
	(via
		(at 104.648 -52.324)
		(size 0.508)
		(drill 0.254)
		(layers "F.Cu" "B.Cu")
		(net "P12V_BRICK")
	)
	(via
		(at 93.726 -49.784)
		(size 0.508)
		(drill 0.254)
		(layers "F.Cu" "B.Cu")
		(net "P12V_BRICK")
	)
	(via
		(at 42.58564 -53.3019)
		(size 0.508)
		(drill 0.254)
		(layers "F.Cu" "B.Cu")
		(net "P12V_BRICK")
	)
	(via
		(at 111.378746 -69.897244)
		(size 0.508)
		(drill 0.254)
		(layers "F.Cu" "B.Cu")
		(net "P12V_BRICK")
	)
	(via
		(at 162.1028 -11.811)
		(size 0.508)
		(drill 0.254)
		(layers "F.Cu" "B.Cu")
		(net "P12V_BRICK")
	)
	(via
		(at 166.37 -49.657)
		(size 0.508)
		(drill 0.254)
		(layers "F.Cu" "B.Cu")
		(net "P12V_BRICK")
	)
	(via
		(at 88.265 -49.784)
		(size 0.508)
		(drill 0.254)
		(layers "F.Cu" "B.Cu")
		(net "P12V_BRICK")
	)
	(via
		(at 71.429626 -70.885812)
		(size 0.508)
		(drill 0.254)
		(layers "F.Cu" "B.Cu")
		(net "P12V_BRICK")
	)
	(via
		(at 177.28946 -50.292)
		(size 0.508)
		(drill 0.254)
		(layers "F.Cu" "B.Cu")
		(net "P12V_BRICK")
	)
	(via
		(at 47.05604 -52.1589)
		(size 0.508)
		(drill 0.254)
		(layers "F.Cu" "B.Cu")
		(net "P12V_BRICK")
	)
	(via
		(at 111.378746 -71.929244)
		(size 0.508)
		(drill 0.254)
		(layers "F.Cu" "B.Cu")
		(net "P12V_BRICK")
	)
	(via
		(at 171.831 -52.197)
		(size 0.508)
		(drill 0.254)
		(layers "F.Cu" "B.Cu")
		(net "P12V_BRICK")
	)
	(via
		(at 160.909 -51.562)
		(size 0.508)
		(drill 0.254)
		(layers "F.Cu" "B.Cu")
		(net "P12V_BRICK")
	)
	(via
		(at 41.84904 -54.1147)
		(size 0.508)
		(drill 0.254)
		(layers "F.Cu" "B.Cu")
		(net "P12V_BRICK")
	)
	(via
		(at 110.362746 -68.881244)
		(size 0.508)
		(drill 0.254)
		(layers "F.Cu" "B.Cu")
		(net "P12V_BRICK")
	)
	(via
		(at 50.07864 -52.1208)
		(size 0.508)
		(drill 0.254)
		(layers "F.Cu" "B.Cu")
		(net "P12V_BRICK")
	)
	(via
		(at 50.07864 -52.8828)
		(size 0.508)
		(drill 0.254)
		(layers "F.Cu" "B.Cu")
		(net "P12V_BRICK")
	)
	(segment
		(start 119.074692 -61.900308)
		(end 120.015 -60.96)
		(width 0.635)
		(layer "B.Cu")
		(net "P12V_BRICK")
	)
	(segment
		(start 130.250692 -61.900308)
		(end 131.191 -60.96)
		(width 0.635)
		(layer "B.Cu")
		(net "P12V_BRICK")
	)
	(segment
		(start 198.115174 -60.96)
		(end 199.055482 -61.900308)
		(width 0.635)
		(layer "B.Cu")
		(net "P12V_BRICK")
	)
	(segment
		(start 120.015 -60.96)
		(end 120.955308 -61.900308)
		(width 0.635)
		(layer "B.Cu")
		(net "P12V_BRICK")
	)
	(segment
		(start 145.998692 -60.019692)
		(end 146.939 -60.96)
		(width 0.635)
		(layer "B.Cu")
		(net "P12V_BRICK")
	)
	(segment
		(start 208.350866 -60.019692)
		(end 209.291174 -60.96)
		(width 0.635)
		(layer "B.Cu")
		(net "P12V_BRICK")
	)
	(segment
		(start 63.691262 -72.828658)
		(end 63.194692 -72.332088)
		(width 0.889)
		(layer "B.Cu")
		(net "P12V_BRICK")
	)
	(segment
		(start 64.470026 -70.409816)
		(end 63.188596 -69.128386)
		(width 0.889)
		(layer "B.Cu")
		(net "P12V_BRICK")
	)
	(segment
		(start 89.737692 -61.900308)
		(end 90.678 -60.96)
		(width 0.635)
		(layer "B.Cu")
		(net "P12V_BRICK")
	)
	(segment
		(start 64.470026 -70.409816)
		(end 65.751456 -71.691246)
		(width 0.889)
		(layer "B.Cu")
		(net "P12V_BRICK")
	)
	(segment
		(start 209.291174 -60.96)
		(end 210.231482 -61.900308)
		(width 0.635)
		(layer "B.Cu")
		(net "P12V_BRICK")
	)
	(segment
		(start 79.375 -60.96)
		(end 80.315308 -61.900308)
		(width 0.635)
		(layer "B.Cu")
		(net "P12V_BRICK")
	)
	(segment
		(start 68.280026 -70.409816)
		(end 66.998596 -69.128386)
		(width 0.889)
		(layer "B.Cu")
		(net "P12V_BRICK")
	)
	(segment
		(start 185.998866 -61.900308)
		(end 186.939174 -60.96)
		(width 0.635)
		(layer "B.Cu")
		(net "P12V_BRICK")
	)
	(segment
		(start 78.434692 -61.900308)
		(end 79.375 -60.96)
		(width 0.635)
		(layer "B.Cu")
		(net "P12V_BRICK")
	)
	(segment
		(start 119.074692 -60.019692)
		(end 120.015 -60.96)
		(width 0.635)
		(layer "B.Cu")
		(net "P12V_BRICK")
	)
	(segment
		(start 108.839 -60.96)
		(end 109.779308 -61.900308)
		(width 0.635)
		(layer "B.Cu")
		(net "P12V_BRICK")
	)
	(segment
		(start 130.250692 -60.019692)
		(end 131.191 -60.96)
		(width 0.635)
		(layer "B.Cu")
		(net "P12V_BRICK")
	)
	(segment
		(start 169.291 -60.96)
		(end 170.231308 -61.900308)
		(width 0.635)
		(layer "B.Cu")
		(net "P12V_BRICK")
	)
	(segment
		(start 157.174692 -60.019692)
		(end 158.115 -60.96)
		(width 0.635)
		(layer "B.Cu")
		(net "P12V_BRICK")
	)
	(segment
		(start 186.939174 -60.96)
		(end 187.879482 -61.900308)
		(width 0.635)
		(layer "B.Cu")
		(net "P12V_BRICK")
	)
	(segment
		(start 63.194692 -72.332088)
		(end 63.194692 -71.68515)
		(width 0.889)
		(layer "B.Cu")
		(net "P12V_BRICK")
	)
	(segment
		(start 64.470026 -70.409816)
		(end 65.751456 -69.128386)
		(width 0.889)
		(layer "B.Cu")
		(net "P12V_BRICK")
	)
	(segment
		(start 67.131692 -60.019692)
		(end 68.072 -60.96)
		(width 0.635)
		(layer "B.Cu")
		(net "P12V_BRICK")
	)
	(segment
		(start 79.375 -60.96)
		(end 80.315308 -60.019692)
		(width 0.635)
		(layer "B.Cu")
		(net "P12V_BRICK")
	)
	(segment
		(start 145.998692 -61.900308)
		(end 146.939 -60.96)
		(width 0.635)
		(layer "B.Cu")
		(net "P12V_BRICK")
	)
	(segment
		(start 120.015 -60.96)
		(end 120.955308 -60.019692)
		(width 0.635)
		(layer "B.Cu")
		(net "P12V_BRICK")
	)
	(segment
		(start 197.174866 -60.019692)
		(end 198.115174 -60.96)
		(width 0.635)
		(layer "B.Cu")
		(net "P12V_BRICK")
	)
	(segment
		(start 62.850014 -77.10805)
		(end 62.850014 -77.71765)
		(width 0.508)
		(layer "B.Cu")
		(net "P12V_BRICK")
	)
	(segment
		(start 102.824534 -77.69225)
		(end 102.849934 -77.71765)
		(width 0.4572)
		(layer "B.Cu")
		(net "P12V_BRICK")
	)
	(segment
		(start 67.131692 -61.900308)
		(end 68.072 -60.96)
		(width 0.635)
		(layer "B.Cu")
		(net "P12V_BRICK")
	)
	(segment
		(start 158.115 -60.96)
		(end 159.055308 -60.019692)
		(width 0.635)
		(layer "B.Cu")
		(net "P12V_BRICK")
	)
	(segment
		(start 157.174692 -61.900308)
		(end 158.115 -60.96)
		(width 0.635)
		(layer "B.Cu")
		(net "P12V_BRICK")
	)
	(segment
		(start 63.194692 -71.68515)
		(end 64.470026 -70.409816)
		(width 0.889)
		(layer "B.Cu")
		(net "P12V_BRICK")
	)
	(segment
		(start 209.291174 -60.96)
		(end 210.231482 -60.019692)
		(width 0.635)
		(layer "B.Cu")
		(net "P12V_BRICK")
	)
	(segment
		(start 169.291 -60.96)
		(end 170.231308 -60.019692)
		(width 0.635)
		(layer "B.Cu")
		(net "P12V_BRICK")
	)
	(segment
		(start 68.280026 -70.409816)
		(end 69.561456 -69.128386)
		(width 0.889)
		(layer "B.Cu")
		(net "P12V_BRICK")
	)
	(segment
		(start 185.998866 -60.019692)
		(end 186.939174 -60.96)
		(width 0.635)
		(layer "B.Cu")
		(net "P12V_BRICK")
	)
	(segment
		(start 182.850282 -77.10805)
		(end 182.850282 -77.71765)
		(width 0.508)
		(layer "B.Cu")
		(net "P12V_BRICK")
	)
	(segment
		(start 78.434692 -60.019692)
		(end 79.375 -60.96)
		(width 0.635)
		(layer "B.Cu")
		(net "P12V_BRICK")
	)
	(segment
		(start 68.280026 -70.409816)
		(end 66.998596 -71.691246)
		(width 0.889)
		(layer "B.Cu")
		(net "P12V_BRICK")
	)
	(segment
		(start 90.678 -60.96)
		(end 91.618308 -60.019692)
		(width 0.635)
		(layer "B.Cu")
		(net "P12V_BRICK")
	)
	(segment
		(start 146.939 -60.96)
		(end 147.879308 -61.900308)
		(width 0.635)
		(layer "B.Cu")
		(net "P12V_BRICK")
	)
	(segment
		(start 68.280026 -70.409816)
		(end 69.561456 -71.691246)
		(width 0.889)
		(layer "B.Cu")
		(net "P12V_BRICK")
	)
	(segment
		(start 186.939174 -60.96)
		(end 187.879482 -60.019692)
		(width 0.635)
		(layer "B.Cu")
		(net "P12V_BRICK")
	)
	(segment
		(start 90.678 -60.96)
		(end 91.618308 -61.900308)
		(width 0.635)
		(layer "B.Cu")
		(net "P12V_BRICK")
	)
	(segment
		(start 131.191 -60.96)
		(end 132.131308 -61.900308)
		(width 0.635)
		(layer "B.Cu")
		(net "P12V_BRICK")
	)
	(segment
		(start 158.115 -60.96)
		(end 159.055308 -61.900308)
		(width 0.635)
		(layer "B.Cu")
		(net "P12V_BRICK")
	)
	(segment
		(start 131.191 -60.96)
		(end 132.131308 -60.019692)
		(width 0.635)
		(layer "B.Cu")
		(net "P12V_BRICK")
	)
	(segment
		(start 107.898692 -60.019692)
		(end 108.839 -60.96)
		(width 0.635)
		(layer "B.Cu")
		(net "P12V_BRICK")
	)
	(segment
		(start 68.072 -60.96)
		(end 69.012308 -60.019692)
		(width 0.635)
		(layer "B.Cu")
		(net "P12V_BRICK")
	)
	(segment
		(start 102.824534 -77.10805)
		(end 102.824534 -77.69225)
		(width 0.4572)
		(layer "B.Cu")
		(net "P12V_BRICK")
	)
	(segment
		(start 208.350866 -61.900308)
		(end 209.291174 -60.96)
		(width 0.635)
		(layer "B.Cu")
		(net "P12V_BRICK")
	)
	(segment
		(start 89.737692 -60.019692)
		(end 90.678 -60.96)
		(width 0.635)
		(layer "B.Cu")
		(net "P12V_BRICK")
	)
	(segment
		(start 107.898692 -61.900308)
		(end 108.839 -60.96)
		(width 0.635)
		(layer "B.Cu")
		(net "P12V_BRICK")
	)
	(segment
		(start 197.174866 -61.900308)
		(end 198.115174 -60.96)
		(width 0.635)
		(layer "B.Cu")
		(net "P12V_BRICK")
	)
	(segment
		(start 108.839 -60.96)
		(end 109.779308 -60.019692)
		(width 0.635)
		(layer "B.Cu")
		(net "P12V_BRICK")
	)
	(segment
		(start 146.939 -60.96)
		(end 147.879308 -60.019692)
		(width 0.635)
		(layer "B.Cu")
		(net "P12V_BRICK")
	)
	(segment
		(start 198.115174 -60.96)
		(end 199.055482 -60.019692)
		(width 0.635)
		(layer "B.Cu")
		(net "P12V_BRICK")
	)
	(segment
		(start 142.850108 -77.10805)
		(end 142.850108 -77.71765)
		(width 0.508)
		(layer "B.Cu")
		(net "P12V_BRICK")
	)
	(segment
		(start 168.350692 -60.019692)
		(end 169.291 -60.96)
		(width 0.635)
		(layer "B.Cu")
		(net "P12V_BRICK")
	)
	(segment
		(start 68.072 -60.96)
		(end 69.012308 -61.900308)
		(width 0.635)
		(layer "B.Cu")
		(net "P12V_BRICK")
	)
	(segment
		(start 168.350692 -61.900308)
		(end 169.291 -60.96)
		(width 0.635)
		(layer "B.Cu")
		(net "P12V_BRICK")
	)
	(segment
		(start 198.115174 -60.96)
		(end 198.830946 -60.244228)
		(width 0.635)
		(layer "In2.Cu")
		(net "P12V_BRICK")
	)
	(segment
		(start 120.015 -60.96)
		(end 120.730772 -61.675772)
		(width 0.635)
		(layer "In2.Cu")
		(net "P12V_BRICK")
	)
	(segment
		(start 119.299228 -60.244228)
		(end 120.015 -60.96)
		(width 0.635)
		(layer "In2.Cu")
		(net "P12V_BRICK")
	)
	(segment
		(start 108.123228 -61.675772)
		(end 108.839 -60.96)
		(width 0.635)
		(layer "In2.Cu")
		(net "P12V_BRICK")
	)
	(segment
		(start 186.223402 -60.244228)
		(end 186.939174 -60.96)
		(width 0.635)
		(layer "In2.Cu")
		(net "P12V_BRICK")
	)
	(segment
		(start 157.399228 -60.244228)
		(end 158.115 -60.96)
		(width 0.635)
		(layer "In2.Cu")
		(net "P12V_BRICK")
	)
	(segment
		(start 108.839 -60.96)
		(end 109.554772 -60.244228)
		(width 0.635)
		(layer "In2.Cu")
		(net "P12V_BRICK")
	)
	(segment
		(start 119.299228 -61.675772)
		(end 120.015 -60.96)
		(width 0.635)
		(layer "In2.Cu")
		(net "P12V_BRICK")
	)
	(segment
		(start 208.575402 -61.675772)
		(end 209.291174 -60.96)
		(width 0.635)
		(layer "In2.Cu")
		(net "P12V_BRICK")
	)
	(segment
		(start 68.280026 -70.409816)
		(end 69.561456 -71.691246)
		(width 0.889)
		(layer "In2.Cu")
		(net "P12V_BRICK")
	)
	(segment
		(start 68.072 -60.96)
		(end 68.787772 -60.244228)
		(width 0.635)
		(layer "In2.Cu")
		(net "P12V_BRICK")
	)
	(segment
		(start 89.962228 -60.244228)
		(end 90.678 -60.96)
		(width 0.635)
		(layer "In2.Cu")
		(net "P12V_BRICK")
	)
	(segment
		(start 108.839 -60.96)
		(end 109.554772 -61.675772)
		(width 0.635)
		(layer "In2.Cu")
		(net "P12V_BRICK")
	)
	(segment
		(start 169.291 -60.96)
		(end 170.006772 -61.675772)
		(width 0.635)
		(layer "In2.Cu")
		(net "P12V_BRICK")
	)
	(segment
		(start 108.123228 -60.244228)
		(end 108.839 -60.96)
		(width 0.635)
		(layer "In2.Cu")
		(net "P12V_BRICK")
	)
	(segment
		(start 208.575402 -60.244228)
		(end 209.291174 -60.96)
		(width 0.635)
		(layer "In2.Cu")
		(net "P12V_BRICK")
	)
	(segment
		(start 90.678 -60.96)
		(end 91.393772 -61.675772)
		(width 0.635)
		(layer "In2.Cu")
		(net "P12V_BRICK")
	)
	(segment
		(start 78.659228 -61.675772)
		(end 79.375 -60.96)
		(width 0.635)
		(layer "In2.Cu")
		(net "P12V_BRICK")
	)
	(segment
		(start 79.375 -60.96)
		(end 80.090772 -60.244228)
		(width 0.635)
		(layer "In2.Cu")
		(net "P12V_BRICK")
	)
	(segment
		(start 120.015 -60.96)
		(end 120.730772 -60.244228)
		(width 0.635)
		(layer "In2.Cu")
		(net "P12V_BRICK")
	)
	(segment
		(start 197.399402 -60.244228)
		(end 198.115174 -60.96)
		(width 0.635)
		(layer "In2.Cu")
		(net "P12V_BRICK")
	)
	(segment
		(start 186.223402 -61.675772)
		(end 186.939174 -60.96)
		(width 0.635)
		(layer "In2.Cu")
		(net "P12V_BRICK")
	)
	(segment
		(start 131.191 -60.96)
		(end 131.906772 -61.675772)
		(width 0.635)
		(layer "In2.Cu")
		(net "P12V_BRICK")
	)
	(segment
		(start 68.072 -60.96)
		(end 68.787772 -61.675772)
		(width 0.635)
		(layer "In2.Cu")
		(net "P12V_BRICK")
	)
	(segment
		(start 158.115 -60.96)
		(end 158.830772 -60.244228)
		(width 0.635)
		(layer "In2.Cu")
		(net "P12V_BRICK")
	)
	(segment
		(start 130.475228 -61.675772)
		(end 131.191 -60.96)
		(width 0.635)
		(layer "In2.Cu")
		(net "P12V_BRICK")
	)
	(segment
		(start 78.659228 -60.244228)
		(end 79.375 -60.96)
		(width 0.635)
		(layer "In2.Cu")
		(net "P12V_BRICK")
	)
	(segment
		(start 63.188596 -69.128386)
		(end 64.470026 -70.409816)
		(width 0.889)
		(layer "In2.Cu")
		(net "P12V_BRICK")
	)
	(segment
		(start 157.399228 -61.675772)
		(end 158.115 -60.96)
		(width 0.635)
		(layer "In2.Cu")
		(net "P12V_BRICK")
	)
	(segment
		(start 198.115174 -60.96)
		(end 198.830946 -61.675772)
		(width 0.635)
		(layer "In2.Cu")
		(net "P12V_BRICK")
	)
	(segment
		(start 90.678 -60.96)
		(end 91.393772 -60.244228)
		(width 0.635)
		(layer "In2.Cu")
		(net "P12V_BRICK")
	)
	(segment
		(start 146.223228 -61.675772)
		(end 146.939 -60.96)
		(width 0.635)
		(layer "In2.Cu")
		(net "P12V_BRICK")
	)
	(segment
		(start 64.470026 -70.409816)
		(end 65.751456 -69.128386)
		(width 0.889)
		(layer "In2.Cu")
		(net "P12V_BRICK")
	)
	(segment
		(start 209.291174 -60.96)
		(end 210.006946 -60.244228)
		(width 0.635)
		(layer "In2.Cu")
		(net "P12V_BRICK")
	)
	(segment
		(start 63.188596 -71.691246)
		(end 64.470026 -70.409816)
		(width 0.889)
		(layer "In2.Cu")
		(net "P12V_BRICK")
	)
	(segment
		(start 68.280026 -70.409816)
		(end 69.561456 -69.128386)
		(width 0.889)
		(layer "In2.Cu")
		(net "P12V_BRICK")
	)
	(segment
		(start 158.115 -60.96)
		(end 158.830772 -61.675772)
		(width 0.635)
		(layer "In2.Cu")
		(net "P12V_BRICK")
	)
	(segment
		(start 209.291174 -60.96)
		(end 210.006946 -61.675772)
		(width 0.635)
		(layer "In2.Cu")
		(net "P12V_BRICK")
	)
	(segment
		(start 168.575228 -60.244228)
		(end 169.291 -60.96)
		(width 0.635)
		(layer "In2.Cu")
		(net "P12V_BRICK")
	)
	(segment
		(start 130.475228 -60.244228)
		(end 131.191 -60.96)
		(width 0.635)
		(layer "In2.Cu")
		(net "P12V_BRICK")
	)
	(segment
		(start 131.191 -60.96)
		(end 131.906772 -60.244228)
		(width 0.635)
		(layer "In2.Cu")
		(net "P12V_BRICK")
	)
	(segment
		(start 186.939174 -60.96)
		(end 187.654946 -61.675772)
		(width 0.635)
		(layer "In2.Cu")
		(net "P12V_BRICK")
	)
	(segment
		(start 79.375 -60.96)
		(end 80.090772 -61.675772)
		(width 0.635)
		(layer "In2.Cu")
		(net "P12V_BRICK")
	)
	(segment
		(start 169.291 -60.96)
		(end 170.006772 -60.244228)
		(width 0.635)
		(layer "In2.Cu")
		(net "P12V_BRICK")
	)
	(segment
		(start 146.939 -60.96)
		(end 147.654772 -60.244228)
		(width 0.635)
		(layer "In2.Cu")
		(net "P12V_BRICK")
	)
	(segment
		(start 66.998596 -69.128386)
		(end 68.280026 -70.409816)
		(width 0.889)
		(layer "In2.Cu")
		(net "P12V_BRICK")
	)
	(segment
		(start 67.356228 -60.244228)
		(end 68.072 -60.96)
		(width 0.635)
		(layer "In2.Cu")
		(net "P12V_BRICK")
	)
	(segment
		(start 67.356228 -61.675772)
		(end 68.072 -60.96)
		(width 0.635)
		(layer "In2.Cu")
		(net "P12V_BRICK")
	)
	(segment
		(start 146.939 -60.96)
		(end 147.654772 -61.675772)
		(width 0.635)
		(layer "In2.Cu")
		(net "P12V_BRICK")
	)
	(segment
		(start 89.962228 -61.675772)
		(end 90.678 -60.96)
		(width 0.635)
		(layer "In2.Cu")
		(net "P12V_BRICK")
	)
	(segment
		(start 146.223228 -60.244228)
		(end 146.939 -60.96)
		(width 0.635)
		(layer "In2.Cu")
		(net "P12V_BRICK")
	)
	(segment
		(start 66.998596 -71.691246)
		(end 68.280026 -70.409816)
		(width 0.889)
		(layer "In2.Cu")
		(net "P12V_BRICK")
	)
	(segment
		(start 64.470026 -70.409816)
		(end 65.751456 -71.691246)
		(width 0.889)
		(layer "In2.Cu")
		(net "P12V_BRICK")
	)
	(segment
		(start 168.575228 -61.675772)
		(end 169.291 -60.96)
		(width 0.635)
		(layer "In2.Cu")
		(net "P12V_BRICK")
	)
	(segment
		(start 186.939174 -60.96)
		(end 187.654946 -60.244228)
		(width 0.635)
		(layer "In2.Cu")
		(net "P12V_BRICK")
	)
	(segment
		(start 197.399402 -61.675772)
		(end 198.115174 -60.96)
		(width 0.635)
		(layer "In2.Cu")
		(net "P12V_BRICK")
	)
	(segment
		(start 186.939174 -60.96)
		(end 187.654946 -60.244228)
		(width 0.635)
		(layer "In7.Cu")
		(net "P12V_BRICK")
	)
	(segment
		(start 143.18869 -69.128386)
		(end 144.47012 -70.409816)
		(width 0.889)
		(layer "In7.Cu")
		(net "P12V_BRICK")
	)
	(segment
		(start 146.939 -60.96)
		(end 147.654772 -61.675772)
		(width 0.635)
		(layer "In7.Cu")
		(net "P12V_BRICK")
	)
	(segment
		(start 157.399228 -60.244228)
		(end 158.115 -60.96)
		(width 0.635)
		(layer "In7.Cu")
		(net "P12V_BRICK")
	)
	(segment
		(start 63.188596 -71.691246)
		(end 64.470026 -70.409816)
		(width 0.889)
		(layer "In7.Cu")
		(net "P12V_BRICK")
	)
	(segment
		(start 119.299228 -60.244228)
		(end 120.015 -60.96)
		(width 0.635)
		(layer "In7.Cu")
		(net "P12V_BRICK")
	)
	(segment
		(start 144.47012 -70.409816)
		(end 145.75155 -69.128386)
		(width 0.889)
		(layer "In7.Cu")
		(net "P12V_BRICK")
	)
	(segment
		(start 144.47012 -70.409816)
		(end 145.75155 -71.691246)
		(width 0.889)
		(layer "In7.Cu")
		(net "P12V_BRICK")
	)
	(segment
		(start 186.223402 -61.675772)
		(end 186.939174 -60.96)
		(width 0.635)
		(layer "In7.Cu")
		(net "P12V_BRICK")
	)
	(segment
		(start 68.280026 -70.409816)
		(end 69.561456 -71.691246)
		(width 0.889)
		(layer "In7.Cu")
		(net "P12V_BRICK")
	)
	(segment
		(start 158.115 -60.96)
		(end 158.830772 -60.244228)
		(width 0.635)
		(layer "In7.Cu")
		(net "P12V_BRICK")
	)
	(segment
		(start 146.223228 -60.244228)
		(end 146.939 -60.96)
		(width 0.635)
		(layer "In7.Cu")
		(net "P12V_BRICK")
	)
	(segment
		(start 148.28012 -70.409816)
		(end 149.56155 -69.128386)
		(width 0.889)
		(layer "In7.Cu")
		(net "P12V_BRICK")
	)
	(segment
		(start 106.998516 -69.128386)
		(end 108.279946 -70.409816)
		(width 0.889)
		(layer "In7.Cu")
		(net "P12V_BRICK")
	)
	(segment
		(start 108.839 -60.96)
		(end 109.554772 -61.675772)
		(width 0.635)
		(layer "In7.Cu")
		(net "P12V_BRICK")
	)
	(segment
		(start 158.115 -60.96)
		(end 158.830772 -61.675772)
		(width 0.635)
		(layer "In7.Cu")
		(net "P12V_BRICK")
	)
	(segment
		(start 67.356228 -61.675772)
		(end 68.072 -60.96)
		(width 0.635)
		(layer "In7.Cu")
		(net "P12V_BRICK")
	)
	(segment
		(start 208.575402 -60.244228)
		(end 209.291174 -60.96)
		(width 0.635)
		(layer "In7.Cu")
		(net "P12V_BRICK")
	)
	(segment
		(start 104.469946 -70.409816)
		(end 105.751376 -71.691246)
		(width 0.889)
		(layer "In7.Cu")
		(net "P12V_BRICK")
	)
	(segment
		(start 169.291 -60.96)
		(end 170.006772 -61.675772)
		(width 0.635)
		(layer "In7.Cu")
		(net "P12V_BRICK")
	)
	(segment
		(start 119.299228 -61.675772)
		(end 120.015 -60.96)
		(width 0.635)
		(layer "In7.Cu")
		(net "P12V_BRICK")
	)
	(segment
		(start 89.962228 -61.675772)
		(end 90.678 -60.96)
		(width 0.635)
		(layer "In7.Cu")
		(net "P12V_BRICK")
	)
	(segment
		(start 68.280026 -70.409816)
		(end 69.561456 -69.128386)
		(width 0.889)
		(layer "In7.Cu")
		(net "P12V_BRICK")
	)
	(segment
		(start 197.399402 -60.244228)
		(end 198.115174 -60.96)
		(width 0.635)
		(layer "In7.Cu")
		(net "P12V_BRICK")
	)
	(segment
		(start 146.223228 -61.675772)
		(end 146.939 -60.96)
		(width 0.635)
		(layer "In7.Cu")
		(net "P12V_BRICK")
	)
	(segment
		(start 79.375 -60.96)
		(end 80.090772 -61.675772)
		(width 0.635)
		(layer "In7.Cu")
		(net "P12V_BRICK")
	)
	(segment
		(start 78.659228 -60.244228)
		(end 79.375 -60.96)
		(width 0.635)
		(layer "In7.Cu")
		(net "P12V_BRICK")
	)
	(segment
		(start 64.470026 -70.409816)
		(end 65.751456 -69.128386)
		(width 0.889)
		(layer "In7.Cu")
		(net "P12V_BRICK")
	)
	(segment
		(start 157.399228 -61.675772)
		(end 158.115 -60.96)
		(width 0.635)
		(layer "In7.Cu")
		(net "P12V_BRICK")
	)
	(segment
		(start 130.475228 -61.675772)
		(end 131.191 -60.96)
		(width 0.635)
		(layer "In7.Cu")
		(net "P12V_BRICK")
	)
	(segment
		(start 209.291174 -60.96)
		(end 210.006946 -60.244228)
		(width 0.635)
		(layer "In7.Cu")
		(net "P12V_BRICK")
	)
	(segment
		(start 186.223402 -60.244228)
		(end 186.939174 -60.96)
		(width 0.635)
		(layer "In7.Cu")
		(net "P12V_BRICK")
	)
	(segment
		(start 104.469946 -70.409816)
		(end 105.751376 -69.128386)
		(width 0.889)
		(layer "In7.Cu")
		(net "P12V_BRICK")
	)
	(segment
		(start 131.191 -60.96)
		(end 131.906772 -60.244228)
		(width 0.635)
		(layer "In7.Cu")
		(net "P12V_BRICK")
	)
	(segment
		(start 169.291 -60.96)
		(end 170.006772 -60.244228)
		(width 0.635)
		(layer "In7.Cu")
		(net "P12V_BRICK")
	)
	(segment
		(start 186.939174 -60.96)
		(end 187.654946 -61.675772)
		(width 0.635)
		(layer "In7.Cu")
		(net "P12V_BRICK")
	)
	(segment
		(start 66.998596 -69.128386)
		(end 68.280026 -70.409816)
		(width 0.889)
		(layer "In7.Cu")
		(net "P12V_BRICK")
	)
	(segment
		(start 146.99869 -69.128386)
		(end 148.28012 -70.409816)
		(width 0.889)
		(layer "In7.Cu")
		(net "P12V_BRICK")
	)
	(segment
		(start 108.279946 -70.409816)
		(end 109.561376 -69.128386)
		(width 0.889)
		(layer "In7.Cu")
		(net "P12V_BRICK")
	)
	(segment
		(start 103.188516 -69.128386)
		(end 104.469946 -70.409816)
		(width 0.889)
		(layer "In7.Cu")
		(net "P12V_BRICK")
	)
	(segment
		(start 148.28012 -70.409816)
		(end 149.56155 -71.691246)
		(width 0.889)
		(layer "In7.Cu")
		(net "P12V_BRICK")
	)
	(segment
		(start 197.399402 -61.675772)
		(end 198.115174 -60.96)
		(width 0.635)
		(layer "In7.Cu")
		(net "P12V_BRICK")
	)
	(segment
		(start 120.015 -60.96)
		(end 120.730772 -61.675772)
		(width 0.635)
		(layer "In7.Cu")
		(net "P12V_BRICK")
	)
	(segment
		(start 78.659228 -61.675772)
		(end 79.375 -60.96)
		(width 0.635)
		(layer "In7.Cu")
		(net "P12V_BRICK")
	)
	(segment
		(start 103.188516 -71.691246)
		(end 104.469946 -70.409816)
		(width 0.889)
		(layer "In7.Cu")
		(net "P12V_BRICK")
	)
	(segment
		(start 90.678 -60.96)
		(end 91.393772 -61.675772)
		(width 0.635)
		(layer "In7.Cu")
		(net "P12V_BRICK")
	)
	(segment
		(start 168.575228 -60.244228)
		(end 169.291 -60.96)
		(width 0.635)
		(layer "In7.Cu")
		(net "P12V_BRICK")
	)
	(segment
		(start 168.575228 -61.675772)
		(end 169.291 -60.96)
		(width 0.635)
		(layer "In7.Cu")
		(net "P12V_BRICK")
	)
	(segment
		(start 108.123228 -60.244228)
		(end 108.839 -60.96)
		(width 0.635)
		(layer "In7.Cu")
		(net "P12V_BRICK")
	)
	(segment
		(start 79.375 -60.96)
		(end 80.090772 -60.244228)
		(width 0.635)
		(layer "In7.Cu")
		(net "P12V_BRICK")
	)
	(segment
		(start 66.998596 -71.691246)
		(end 68.280026 -70.409816)
		(width 0.889)
		(layer "In7.Cu")
		(net "P12V_BRICK")
	)
	(segment
		(start 68.072 -60.96)
		(end 68.787772 -61.675772)
		(width 0.635)
		(layer "In7.Cu")
		(net "P12V_BRICK")
	)
	(segment
		(start 131.191 -60.96)
		(end 131.906772 -61.675772)
		(width 0.635)
		(layer "In7.Cu")
		(net "P12V_BRICK")
	)
	(segment
		(start 63.188596 -69.128386)
		(end 64.470026 -70.409816)
		(width 0.889)
		(layer "In7.Cu")
		(net "P12V_BRICK")
	)
	(segment
		(start 198.115174 -60.96)
		(end 198.830946 -61.675772)
		(width 0.635)
		(layer "In7.Cu")
		(net "P12V_BRICK")
	)
	(segment
		(start 143.18869 -71.691246)
		(end 144.47012 -70.409816)
		(width 0.889)
		(layer "In7.Cu")
		(net "P12V_BRICK")
	)
	(segment
		(start 146.939 -60.96)
		(end 147.654772 -60.244228)
		(width 0.635)
		(layer "In7.Cu")
		(net "P12V_BRICK")
	)
	(segment
		(start 120.015 -60.96)
		(end 120.730772 -60.244228)
		(width 0.635)
		(layer "In7.Cu")
		(net "P12V_BRICK")
	)
	(segment
		(start 106.998516 -71.691246)
		(end 108.279946 -70.409816)
		(width 0.889)
		(layer "In7.Cu")
		(net "P12V_BRICK")
	)
	(segment
		(start 209.291174 -60.96)
		(end 210.006946 -61.675772)
		(width 0.635)
		(layer "In7.Cu")
		(net "P12V_BRICK")
	)
	(segment
		(start 108.839 -60.96)
		(end 109.554772 -60.244228)
		(width 0.635)
		(layer "In7.Cu")
		(net "P12V_BRICK")
	)
	(segment
		(start 146.99869 -71.691246)
		(end 148.28012 -70.409816)
		(width 0.889)
		(layer "In7.Cu")
		(net "P12V_BRICK")
	)
	(segment
		(start 108.123228 -61.675772)
		(end 108.839 -60.96)
		(width 0.635)
		(layer "In7.Cu")
		(net "P12V_BRICK")
	)
	(segment
		(start 90.678 -60.96)
		(end 91.393772 -60.244228)
		(width 0.635)
		(layer "In7.Cu")
		(net "P12V_BRICK")
	)
	(segment
		(start 64.470026 -70.409816)
		(end 65.751456 -71.691246)
		(width 0.889)
		(layer "In7.Cu")
		(net "P12V_BRICK")
	)
	(segment
		(start 208.575402 -61.675772)
		(end 209.291174 -60.96)
		(width 0.635)
		(layer "In7.Cu")
		(net "P12V_BRICK")
	)
	(segment
		(start 68.072 -60.96)
		(end 68.787772 -60.244228)
		(width 0.635)
		(layer "In7.Cu")
		(net "P12V_BRICK")
	)
	(segment
		(start 198.115174 -60.96)
		(end 198.830946 -60.244228)
		(width 0.635)
		(layer "In7.Cu")
		(net "P12V_BRICK")
	)
	(segment
		(start 89.962228 -60.244228)
		(end 90.678 -60.96)
		(width 0.635)
		(layer "In7.Cu")
		(net "P12V_BRICK")
	)
	(segment
		(start 108.279946 -70.409816)
		(end 109.561376 -71.691246)
		(width 0.889)
		(layer "In7.Cu")
		(net "P12V_BRICK")
	)
	(segment
		(start 67.356228 -60.244228)
		(end 68.072 -60.96)
		(width 0.635)
		(layer "In7.Cu")
		(net "P12V_BRICK")
	)
	(segment
		(start 130.475228 -60.244228)
		(end 131.191 -60.96)
		(width 0.635)
		(layer "In7.Cu")
		(net "P12V_BRICK")
	)
	(via
		(at 232.73004 -90.17)
		(size 0.762)
		(drill 0.254)
		(layers "F.Cu" "B.Cu")
		(net "RST_SMB_PDB_BUF_R_N")
	)
	(segment
		(start 232.73004 -90.17)
		(end 232.73004 -89.109042)
		(width 0.17272)
		(layer "B.Cu")
		(net "RST_SMB_PDB_BUF_R_N")
	)
	(segment
		(start 232.537 -90.91295)
		(end 232.537 -90.36304)
		(width 0.17272)
		(layer "B.Cu")
		(net "RST_SMB_PDB_BUF_R_N")
	)
	(segment
		(start 232.537 -90.36304)
		(end 232.73004 -90.17)
		(width 0.17272)
		(layer "B.Cu")
		(net "RST_SMB_PDB_BUF_R_N")
	)
	(segment
		(start 136.85012 -116.47805)
		(end 136.85012 -121.209816)
		(width 0.17272)
		(layer "B.Cu")
		(net "BRICK_P12V0_ON_OFF_R")
	)
	(segment
		(start 132.850128 -67.869816)
		(end 132.850128 -76.30795)
		(width 0.4572)
		(layer "B.Cu")
		(net "P12V_MB0_SENSE-")
	)
	(segment
		(start 140.850112 -76.30795)
		(end 140.850112 -67.869816)
		(width 0.17272)
		(layer "B.Cu")
		(net "BRICK0_PMBADD")
	)
	(segment
		(start 278.45004 -20.955)
		(end 277.368 -20.955)
		(width 0.381)
		(layer "F.Cu")
		(net "P52V_BUSBAR")
	)
	(via
		(at 277.368 -20.955)
		(size 0.508)
		(drill 0.254)
		(layers "F.Cu" "B.Cu")
		(net "P52V_BUSBAR")
	)
	(segment
		(start 277.368 -20.955)
		(end 278.64181 -20.955)
		(width 0.4318)
		(layer "B.Cu")
		(net "P52V_BUSBAR")
	)
	(segment
		(start 301.4218 -49.5808)
		(end 308.1782 -56.3372)
		(width 0.4318)
		(layer "B.Cu")
		(net "P52V_BUSBAR")
	)
	(segment
		(start 300.4185 -49.5808)
		(end 301.4218 -49.5808)
		(width 0.4318)
		(layer "B.Cu")
		(net "P52V_BUSBAR")
	)
	(segment
		(start 308.1782 -56.3372)
		(end 308.1782 -69.64807)
		(width 0.4318)
		(layer "B.Cu")
		(net "P52V_BUSBAR")
	)
	(segment
		(start 297.5991 -46.7614)
		(end 300.4185 -49.5808)
		(width 0.4318)
		(layer "B.Cu")
		(net "P52V_BUSBAR")
	)
	(segment
		(start 292.94328 -26.87828)
		(end 297.5991 -31.5341)
		(width 0.4318)
		(layer "B.Cu")
		(net "P52V_BUSBAR")
	)
	(segment
		(start 278.64181 -20.955)
		(end 292.94328 -26.87828)
		(width 0.4318)
		(layer "B.Cu")
		(net "P52V_BUSBAR")
	)
	(segment
		(start 308.1782 -69.64807)
		(end 311.410096 -72.879966)
		(width 0.4318)
		(layer "B.Cu")
		(net "P52V_BUSBAR")
	)
	(segment
		(start 297.5991 -31.5341)
		(end 297.5991 -46.7614)
		(width 0.4318)
		(layer "B.Cu")
		(net "P52V_BUSBAR")
	)
	(segment
		(start 163.97605 -9.398)
		(end 164.58565 -9.398)
		(width 0.508)
		(layer "F.Cu")
		(net "GND")
	)
	(segment
		(start 44.138596 -71.691246)
		(end 45.420026 -70.409816)
		(width 0.889)
		(layer "F.Cu")
		(net "GND")
	)
	(segment
		(start 179.324 -15.13205)
		(end 179.324 -15.74165)
		(width 0.508)
		(layer "F.Cu")
		(net "GND")
	)
	(segment
		(start 45.420026 -70.409816)
		(end 46.701456 -71.691246)
		(width 0.889)
		(layer "F.Cu")
		(net "GND")
	)
	(segment
		(start 38.90772 -54.80939)
		(end 38.90772 -54.2671)
		(width 0.254)
		(layer "F.Cu")
		(net "GND")
	)
	(segment
		(start 45.09516 -59.59602)
		(end 43.953938 -58.454798)
		(width 0.254)
		(layer "F.Cu")
		(net "GND")
	)
	(segment
		(start 271.96161 -44.39539)
		(end 271.96161 -45.36059)
		(width 0.381)
		(layer "F.Cu")
		(net "GND")
	)
	(segment
		(start 46.042834 -54.013354)
		(end 46.824646 -54.013354)
		(width 0.381)
		(layer "F.Cu")
		(net "GND")
	)
	(segment
		(start 281.869896 -25.71496)
		(end 282.702 -25.71496)
		(width 0.381)
		(layer "F.Cu")
		(net "GND")
	)
	(segment
		(start 44.138596 -69.128386)
		(end 45.420026 -70.409816)
		(width 0.889)
		(layer "F.Cu")
		(net "GND")
	)
	(segment
		(start 43.925236 -55.65394)
		(end 43.6245 -55.954676)
		(width 0.17272)
		(layer "F.Cu")
		(net "GND")
	)
	(segment
		(start 298.46905 -28.321)
		(end 299.07865 -28.321)
		(width 0.508)
		(layer "F.Cu")
		(net "GND")
	)
	(segment
		(start 43.953938 -58.454798)
		(end 43.081448 -58.454798)
		(width 0.254)
		(layer "F.Cu")
		(net "GND")
	)
	(segment
		(start 282.72105 -22.352)
		(end 283.845 -22.352)
		(width 0.381)
		(layer "F.Cu")
		(net "GND")
	)
	(segment
		(start 283.4386 -21.082)
		(end 284.353 -21.082)
		(width 0.381)
		(layer "F.Cu")
		(net "GND")
	)
	(segment
		(start 45.420026 -70.409816)
		(end 46.701456 -69.128386)
		(width 0.889)
		(layer "F.Cu")
		(net "GND")
	)
	(segment
		(start 173.86935 -9.271)
		(end 174.47895 -9.271)
		(width 0.508)
		(layer "F.Cu")
		(net "GND")
	)
	(segment
		(start 43.6245 -55.954676)
		(end 43.081448 -55.954676)
		(width 0.17272)
		(layer "F.Cu")
		(net "GND")
	)
	(segment
		(start 277.114 -24.65705)
		(end 277.114 -25.273)
		(width 0.381)
		(layer "F.Cu")
		(net "GND")
	)
	(segment
		(start 210.98002 -83.566)
		(end 210.185 -83.566)
		(width 0.508)
		(layer "F.Cu")
		(net "GND")
	)
	(segment
		(start 298.8056 -26.797)
		(end 299.593 -26.797)
		(width 0.508)
		(layer "F.Cu")
		(net "GND")
	)
	(segment
		(start 38.90772 -54.2671)
		(end 38.98392 -54.1909)
		(width 0.254)
		(layer "F.Cu")
		(net "GND")
	)
	(segment
		(start 278.1554 -24.65705)
		(end 278.1554 -25.273)
		(width 0.381)
		(layer "F.Cu")
		(net "GND")
	)
	(segment
		(start 50.511456 -69.128386)
		(end 49.230026 -70.409816)
		(width 0.889)
		(layer "F.Cu")
		(net "GND")
	)
	(segment
		(start 46.1645 -59.59602)
		(end 45.09516 -59.59602)
		(width 0.254)
		(layer "F.Cu")
		(net "GND")
	)
	(segment
		(start 47.948596 -69.128386)
		(end 49.230026 -70.409816)
		(width 0.889)
		(layer "F.Cu")
		(net "GND")
	)
	(segment
		(start 292.48989 -31.727902)
		(end 293.37 -31.727902)
		(width 0.381)
		(layer "F.Cu")
		(net "GND")
	)
	(segment
		(start 283.845 -22.352)
		(end 284.353 -21.844)
		(width 0.381)
		(layer "F.Cu")
		(net "GND")
	)
	(segment
		(start 47.948596 -71.691246)
		(end 49.230026 -70.409816)
		(width 0.889)
		(layer "F.Cu")
		(net "GND")
	)
	(segment
		(start 49.230026 -70.409816)
		(end 50.511456 -71.691246)
		(width 0.889)
		(layer "F.Cu")
		(net "GND")
	)
	(segment
		(start 43.081448 -56.454802)
		(end 43.868848 -56.454802)
		(width 0.17272)
		(layer "F.Cu")
		(net "GND")
	)
	(segment
		(start 174.47895 -8.255)
		(end 173.86935 -8.255)
		(width 0.508)
		(layer "F.Cu")
		(net "GND")
	)
	(segment
		(start 202.654916 -66.608706)
		(end 202.654916 -65.922906)
		(width 0.508)
		(layer "F.Cu")
		(net "GND")
	)
	(segment
		(start 205.613 -66.58102)
		(end 205.613 -65.89522)
		(width 0.508)
		(layer "F.Cu")
		(net "GND")
	)
	(via
		(at 132.850128 -77.71765)
		(size 0.508)
		(drill 0.254)
		(layers "F.Cu" "B.Cu")
		(net "GND")
	)
	(via
		(at 239.02289 -87.496396)
		(size 0.508)
		(drill 0.254)
		(layers "F.Cu" "B.Cu")
		(net "GND")
	)
	(via
		(at 0.76327 -67.370452)
		(size 0.508)
		(drill 0.254)
		(layers "F.Cu" "B.Cu")
		(net "GND")
	)
	(via
		(at 186.30646 -50.292)
		(size 0.508)
		(drill 0.254)
		(layers "F.Cu" "B.Cu")
		(net "GND")
	)
	(via
		(at 242.463828 -0.763016)
		(size 0.508)
		(drill 0.254)
		(layers "F.Cu" "B.Cu")
		(net "GND")
	)
	(via
		(at 327.236074 -114.544348)
		(size 0.508)
		(drill 0.254)
		(layers "F.Cu" "B.Cu")
		(net "GND")
	)
	(via
		(at 230.632 -83.30565)
		(size 0.508)
		(drill 0.254)
		(layers "F.Cu" "B.Cu")
		(net "GND")
	)
	(via
		(at 222.885 -92.964)
		(size 0.508)
		(drill 0.254)
		(layers "F.Cu" "B.Cu")
		(net "GND")
	)
	(via
		(at 310.006492 -146.237706)
		(size 0.508)
		(drill 0.254)
		(layers "F.Cu" "B.Cu")
		(net "GND")
	)
	(via
		(at 282.308808 -138.938)
		(size 0.508)
		(drill 0.254)
		(layers "F.Cu" "B.Cu")
		(net "GND")
	)
	(via
		(at 75.438 -49.784)
		(size 0.508)
		(drill 0.254)
		(layers "F.Cu" "B.Cu")
		(net "GND")
	)
	(via
		(at 156.103828 -0.763016)
		(size 0.508)
		(drill 0.254)
		(layers "F.Cu" "B.Cu")
		(net "GND")
	)
	(via
		(at 58.810906 -126.492)
		(size 0.508)
		(drill 0.254)
		(layers "F.Cu" "B.Cu")
		(net "GND")
	)
	(via
		(at 165.6842 -14.4272)
		(size 0.508)
		(drill 0.254)
		(layers "F.Cu" "B.Cu")
		(net "GND")
	)
	(via
		(at 138.446002 -86.446106)
		(size 0.508)
		(drill 0.254)
		(layers "F.Cu" "B.Cu")
		(net "GND")
	)
	(via
		(at 193.43624 -9.779)
		(size 0.508)
		(drill 0.254)
		(layers "F.Cu" "B.Cu")
		(net "GND")
	)
	(via
		(at 327.236074 -124.704348)
		(size 0.508)
		(drill 0.254)
		(layers "F.Cu" "B.Cu")
		(net "GND")
	)
	(via
		(at 205.613 -65.89522)
		(size 0.508)
		(drill 0.254)
		(layers "F.Cu" "B.Cu")
		(net "GND")
	)
	(via
		(at 285.79318 -9.799828)
		(size 0.508)
		(drill 0.254)
		(layers "F.Cu" "B.Cu")
		(net "GND")
	)
	(via
		(at 232.303828 -0.763016)
		(size 0.508)
		(drill 0.254)
		(layers "F.Cu" "B.Cu")
		(net "GND")
	)
	(via
		(at 140.208 -62.738)
		(size 0.508)
		(drill 0.254)
		(layers "F.Cu" "B.Cu")
		(net "GND")
	)
	(via
		(at 219.837 -92.964)
		(size 0.508)
		(drill 0.254)
		(layers "F.Cu" "B.Cu")
		(net "GND")
	)
	(via
		(at 120.543828 -0.763016)
		(size 0.508)
		(drill 0.254)
		(layers "F.Cu" "B.Cu")
		(net "GND")
	)
	(via
		(at 55.499 -77.47)
		(size 0.508)
		(drill 0.254)
		(layers "F.Cu" "B.Cu")
		(net "GND")
	)
	(via
		(at 313.583828 -0.763016)
		(size 0.508)
		(drill 0.254)
		(layers "F.Cu" "B.Cu")
		(net "GND")
	)
	(via
		(at 278.6634 -9.037828)
		(size 0.508)
		(drill 0.254)
		(layers "F.Cu" "B.Cu")
		(net "GND")
	)
	(via
		(at 243.966492 -146.237706)
		(size 0.508)
		(drill 0.254)
		(layers "F.Cu" "B.Cu")
		(net "GND")
	)
	(via
		(at 159.004 -51.562)
		(size 0.508)
		(drill 0.254)
		(layers "F.Cu" "B.Cu")
		(net "GND")
	)
	(via
		(at 138.811 -131.572)
		(size 0.508)
		(drill 0.254)
		(layers "F.Cu" "B.Cu")
		(net "GND")
	)
	(via
		(at 267.863828 -0.763016)
		(size 0.508)
		(drill 0.254)
		(layers "F.Cu" "B.Cu")
		(net "GND")
	)
	(via
		(at 279.41905 -35.54095)
		(size 0.508)
		(drill 0.254)
		(layers "F.Cu" "B.Cu")
		(net "GND")
	)
	(via
		(at 192.06464 -16.256)
		(size 0.508)
		(drill 0.254)
		(layers "F.Cu" "B.Cu")
		(net "GND")
	)
	(via
		(at 289.6743 -21.048218)
		(size 0.508)
		(drill 0.254)
		(layers "F.Cu" "B.Cu")
		(net "GND")
	)
	(via
		(at 130.703828 -0.763016)
		(size 0.508)
		(drill 0.254)
		(layers "F.Cu" "B.Cu")
		(net "GND")
	)
	(via
		(at 140.863828 -0.763016)
		(size 0.508)
		(drill 0.254)
		(layers "F.Cu" "B.Cu")
		(net "GND")
	)
	(via
		(at 239.776 -92.964)
		(size 0.508)
		(drill 0.254)
		(layers "F.Cu" "B.Cu")
		(net "GND")
	)
	(via
		(at 2.517902 -129.546604)
		(size 0.508)
		(drill 0.254)
		(layers "F.Cu" "B.Cu")
		(net "GND")
	)
	(via
		(at 35.6616 -64.86144)
		(size 0.508)
		(drill 0.254)
		(layers "F.Cu" "B.Cu")
		(net "GND")
	)
	(via
		(at 98.810826 -126.492)
		(size 0.508)
		(drill 0.254)
		(layers "F.Cu" "B.Cu")
		(net "GND")
	)
	(via
		(at 115.463828 -0.763016)
		(size 0.508)
		(drill 0.254)
		(layers "F.Cu" "B.Cu")
		(net "GND")
	)
	(via
		(at 0.76327 -47.050452)
		(size 0.508)
		(drill 0.254)
		(layers "F.Cu" "B.Cu")
		(net "GND")
	)
	(via
		(at 45.856906 -126.492)
		(size 0.508)
		(drill 0.254)
		(layers "F.Cu" "B.Cu")
		(net "GND")
	)
	(via
		(at 59.93765 -77.47)
		(size 0.508)
		(drill 0.254)
		(layers "F.Cu" "B.Cu")
		(net "GND")
	)
	(via
		(at 138.811 -126.492)
		(size 0.508)
		(drill 0.254)
		(layers "F.Cu" "B.Cu")
		(net "GND")
	)
	(via
		(at 327.236074 -109.464348)
		(size 0.508)
		(drill 0.254)
		(layers "F.Cu" "B.Cu")
		(net "GND")
	)
	(via
		(at 216.027 -92.964)
		(size 0.508)
		(drill 0.254)
		(layers "F.Cu" "B.Cu")
		(net "GND")
	)
	(via
		(at 34.183828 -0.763016)
		(size 0.508)
		(drill 0.254)
		(layers "F.Cu" "B.Cu")
		(net "GND")
	)
	(via
		(at 279.9334 -9.037828)
		(size 0.508)
		(drill 0.254)
		(layers "F.Cu" "B.Cu")
		(net "GND")
	)
	(via
		(at 80.899 -51.689)
		(size 0.508)
		(drill 0.254)
		(layers "F.Cu" "B.Cu")
		(net "GND")
	)
	(via
		(at 327.236074 -12.944348)
		(size 0.508)
		(drill 0.254)
		(layers "F.Cu" "B.Cu")
		(net "GND")
	)
	(via
		(at 279.933654 -13.649198)
		(size 0.508)
		(drill 0.254)
		(layers "F.Cu" "B.Cu")
		(net "GND")
	)
	(via
		(at 44.343828 -0.763016)
		(size 0.508)
		(drill 0.254)
		(layers "F.Cu" "B.Cu")
		(net "GND")
	)
	(via
		(at 327.236074 -48.504348)
		(size 0.508)
		(drill 0.254)
		(layers "F.Cu" "B.Cu")
		(net "GND")
	)
	(via
		(at 242.189 -92.964)
		(size 0.508)
		(drill 0.254)
		(layers "F.Cu" "B.Cu")
		(net "GND")
	)
	(via
		(at 304.926492 -146.237706)
		(size 0.508)
		(drill 0.254)
		(layers "F.Cu" "B.Cu")
		(net "GND")
	)
	(via
		(at 299.07865 -28.321)
		(size 0.508)
		(drill 0.254)
		(layers "F.Cu" "B.Cu")
		(net "GND")
	)
	(via
		(at 290.3093 -21.048218)
		(size 0.508)
		(drill 0.254)
		(layers "F.Cu" "B.Cu")
		(net "GND")
	)
	(via
		(at 164.58565 -9.398)
		(size 0.508)
		(drill 0.254)
		(layers "F.Cu" "B.Cu")
		(net "GND")
	)
	(via
		(at 279.898094 -5.366004)
		(size 0.508)
		(drill 0.254)
		(layers "F.Cu" "B.Cu")
		(net "GND")
	)
	(via
		(at 169.926 -52.197)
		(size 0.508)
		(drill 0.254)
		(layers "F.Cu" "B.Cu")
		(net "GND")
	)
	(via
		(at 274.446492 -146.237706)
		(size 0.508)
		(drill 0.254)
		(layers "F.Cu" "B.Cu")
		(net "GND")
	)
	(via
		(at 299.293534 -31.407608)
		(size 0.508)
		(drill 0.254)
		(layers "F.Cu" "B.Cu")
		(net "GND")
	)
	(via
		(at 327.236074 -18.024348)
		(size 0.508)
		(drill 0.254)
		(layers "F.Cu" "B.Cu")
		(net "GND")
	)
	(via
		(at 46.618906 -131.572)
		(size 0.508)
		(drill 0.254)
		(layers "F.Cu" "B.Cu")
		(net "GND")
	)
	(via
		(at 300.563534 -30.645608)
		(size 0.508)
		(drill 0.254)
		(layers "F.Cu" "B.Cu")
		(net "GND")
	)
	(via
		(at 79.647034 -86.500208)
		(size 0.508)
		(drill 0.254)
		(layers "F.Cu" "B.Cu")
		(net "GND")
	)
	(via
		(at 95.143828 -0.763016)
		(size 0.508)
		(drill 0.254)
		(layers "F.Cu" "B.Cu")
		(net "GND")
	)
	(via
		(at 57.65165 -77.47)
		(size 0.508)
		(drill 0.254)
		(layers "F.Cu" "B.Cu")
		(net "GND")
	)
	(via
		(at 228.870002 -89.49436)
		(size 0.508)
		(drill 0.254)
		(layers "F.Cu" "B.Cu")
		(net "GND")
	)
	(via
		(at 166.619174 -126.492)
		(size 0.508)
		(drill 0.254)
		(layers "F.Cu" "B.Cu")
		(net "GND")
	)
	(via
		(at 192.72504 -16.256)
		(size 0.508)
		(drill 0.254)
		(layers "F.Cu" "B.Cu")
		(net "GND")
	)
	(via
		(at 237.031784 -78.71714)
		(size 0.508)
		(drill 0.254)
		(layers "F.Cu" "B.Cu")
		(net "GND")
	)
	(via
		(at 283.070808 -138.938)
		(size 0.508)
		(drill 0.254)
		(layers "F.Cu" "B.Cu")
		(net "GND")
	)
	(via
		(at 239.014 -92.964)
		(size 0.508)
		(drill 0.254)
		(layers "F.Cu" "B.Cu")
		(net "GND")
	)
	(via
		(at 96.849946 -113.03635)
		(size 0.508)
		(drill 0.254)
		(layers "F.Cu" "B.Cu")
		(net "GND")
	)
	(via
		(at 186.30646 -49.657)
		(size 0.508)
		(drill 0.254)
		(layers "F.Cu" "B.Cu")
		(net "GND")
	)
	(via
		(at 126.619 -126.492)
		(size 0.508)
		(drill 0.254)
		(layers "F.Cu" "B.Cu")
		(net "GND")
	)
	(via
		(at 214.884 -66.17335)
		(size 0.508)
		(drill 0.254)
		(layers "F.Cu" "B.Cu")
		(net "GND")
	)
	(via
		(at 279.898094 -4.604004)
		(size 0.508)
		(drill 0.254)
		(layers "F.Cu" "B.Cu")
		(net "GND")
	)
	(via
		(at 249.046492 -146.237706)
		(size 0.508)
		(drill 0.254)
		(layers "F.Cu" "B.Cu")
		(net "GND")
	)
	(via
		(at 166.619174 -131.572)
		(size 0.508)
		(drill 0.254)
		(layers "F.Cu" "B.Cu")
		(net "GND")
	)
	(via
		(at 299.846492 -146.237706)
		(size 0.508)
		(drill 0.254)
		(layers "F.Cu" "B.Cu")
		(net "GND")
	)
	(via
		(at 280.568654 -13.649198)
		(size 0.508)
		(drill 0.254)
		(layers "F.Cu" "B.Cu")
		(net "GND")
	)
	(via
		(at 80.899 -52.324)
		(size 0.508)
		(drill 0.254)
		(layers "F.Cu" "B.Cu")
		(net "GND")
	)
	(via
		(at 278.628094 -4.604004)
		(size 0.508)
		(drill 0.254)
		(layers "F.Cu" "B.Cu")
		(net "GND")
	)
	(via
		(at 85.856826 -131.572)
		(size 0.508)
		(drill 0.254)
		(layers "F.Cu" "B.Cu")
		(net "GND")
	)
	(via
		(at 287.662874 -4.604004)
		(size 0.508)
		(drill 0.254)
		(layers "F.Cu" "B.Cu")
		(net "GND")
	)
	(via
		(at 283.103828 -0.763016)
		(size 0.508)
		(drill 0.254)
		(layers "F.Cu" "B.Cu")
		(net "GND")
	)
	(via
		(at 283.070808 -136.652)
		(size 0.508)
		(drill 0.254)
		(layers "F.Cu" "B.Cu")
		(net "GND")
	)
	(via
		(at 180.84546 -52.197)
		(size 0.508)
		(drill 0.254)
		(layers "F.Cu" "B.Cu")
		(net "GND")
	)
	(via
		(at 289.941 -31.60395)
		(size 0.508)
		(drill 0.254)
		(layers "F.Cu" "B.Cu")
		(net "GND")
	)
	(via
		(at 272.5928 -31.2928)
		(size 0.508)
		(drill 0.254)
		(layers "F.Cu" "B.Cu")
		(net "GND")
	)
	(via
		(at 149.225 -112.84204)
		(size 0.508)
		(drill 0.254)
		(layers "F.Cu" "B.Cu")
		(net "GND")
	)
	(via
		(at 159.004 -52.197)
		(size 0.508)
		(drill 0.254)
		(layers "F.Cu" "B.Cu")
		(net "GND")
	)
	(via
		(at 0.76327 -108.010452)
		(size 0.508)
		(drill 0.254)
		(layers "F.Cu" "B.Cu")
		(net "GND")
	)
	(via
		(at 206.903828 -0.763016)
		(size 0.508)
		(drill 0.254)
		(layers "F.Cu" "B.Cu")
		(net "GND")
	)
	(via
		(at 279.526492 -146.237706)
		(size 0.508)
		(drill 0.254)
		(layers "F.Cu" "B.Cu")
		(net "GND")
	)
	(via
		(at 215.41105 -77.851)
		(size 0.508)
		(drill 0.254)
		(layers "F.Cu" "B.Cu")
		(net "GND")
	)
	(via
		(at 236.982 -74.542904)
		(size 0.508)
		(drill 0.254)
		(layers "F.Cu" "B.Cu")
		(net "GND")
	)
	(via
		(at 35.686492 -146.237706)
		(size 0.508)
		(drill 0.254)
		(layers "F.Cu" "B.Cu")
		(net "GND")
	)
	(via
		(at 224.282 -74.65695)
		(size 0.508)
		(drill 0.254)
		(layers "F.Cu" "B.Cu")
		(net "GND")
	)
	(via
		(at 29.103828 -0.763016)
		(size 0.508)
		(drill 0.254)
		(layers "F.Cu" "B.Cu")
		(net "GND")
	)
	(via
		(at 237.363 -92.964)
		(size 0.508)
		(drill 0.254)
		(layers "F.Cu" "B.Cu")
		(net "GND")
	)
	(via
		(at 108.204 -50.419)
		(size 0.508)
		(drill 0.254)
		(layers "F.Cu" "B.Cu")
		(net "GND")
	)
	(via
		(at 167.6908 -14.4272)
		(size 0.508)
		(drill 0.254)
		(layers "F.Cu" "B.Cu")
		(net "GND")
	)
	(via
		(at 0.76327 -36.890452)
		(size 0.508)
		(drill 0.254)
		(layers "F.Cu" "B.Cu")
		(net "GND")
	)
	(via
		(at 111.002826 -131.572)
		(size 0.508)
		(drill 0.254)
		(layers "F.Cu" "B.Cu")
		(net "GND")
	)
	(via
		(at 181.503828 -0.763016)
		(size 0.508)
		(drill 0.254)
		(layers "F.Cu" "B.Cu")
		(net "GND")
	)
	(via
		(at 180.850286 -77.71765)
		(size 0.508)
		(drill 0.254)
		(layers "F.Cu" "B.Cu")
		(net "GND")
	)
	(via
		(at 97.282 -50.419)
		(size 0.508)
		(drill 0.254)
		(layers "F.Cu" "B.Cu")
		(net "GND")
	)
	(via
		(at 141.097 -60.706)
		(size 0.508)
		(drill 0.254)
		(layers "F.Cu" "B.Cu")
		(net "GND")
	)
	(via
		(at 101.219 -61.595)
		(size 0.508)
		(drill 0.254)
		(layers "F.Cu" "B.Cu")
		(net "GND")
	)
	(via
		(at 288.297874 -4.604004)
		(size 0.508)
		(drill 0.254)
		(layers "F.Cu" "B.Cu")
		(net "GND")
	)
	(via
		(at 52.850034 -77.71765)
		(size 0.508)
		(drill 0.254)
		(layers "F.Cu" "B.Cu")
		(net "GND")
	)
	(via
		(at 102.743 -52.324)
		(size 0.508)
		(drill 0.254)
		(layers "F.Cu" "B.Cu")
		(net "GND")
	)
	(via
		(at 294.766492 -146.237706)
		(size 0.508)
		(drill 0.254)
		(layers "F.Cu" "B.Cu")
		(net "GND")
	)
	(via
		(at 287.06318 -9.799828)
		(size 0.508)
		(drill 0.254)
		(layers "F.Cu" "B.Cu")
		(net "GND")
	)
	(via
		(at 238.76 -74.542904)
		(size 0.508)
		(drill 0.254)
		(layers "F.Cu" "B.Cu")
		(net "GND")
	)
	(via
		(at 36.4236 -66.38544)
		(size 0.508)
		(drill 0.254)
		(layers "F.Cu" "B.Cu")
		(net "GND")
	)
	(via
		(at 247.543828 -0.763016)
		(size 0.508)
		(drill 0.254)
		(layers "F.Cu" "B.Cu")
		(net "GND")
	)
	(via
		(at 327.236074 -38.344348)
		(size 0.508)
		(drill 0.254)
		(layers "F.Cu" "B.Cu")
		(net "GND")
	)
	(via
		(at 288.4043 -21.048218)
		(size 0.508)
		(drill 0.254)
		(layers "F.Cu" "B.Cu")
		(net "GND")
	)
	(via
		(at 303.423828 -0.763016)
		(size 0.508)
		(drill 0.254)
		(layers "F.Cu" "B.Cu")
		(net "GND")
	)
	(via
		(at 99.822 -77.47)
		(size 0.508)
		(drill 0.254)
		(layers "F.Cu" "B.Cu")
		(net "GND")
	)
	(via
		(at 175.387 -52.197)
		(size 0.508)
		(drill 0.254)
		(layers "F.Cu" "B.Cu")
		(net "GND")
	)
	(via
		(at 280.568654 -14.411198)
		(size 0.508)
		(drill 0.254)
		(layers "F.Cu" "B.Cu")
		(net "GND")
	)
	(via
		(at 327.236074 -139.944348)
		(size 0.508)
		(drill 0.254)
		(layers "F.Cu" "B.Cu")
		(net "GND")
	)
	(via
		(at 327.236074 -28.184348)
		(size 0.508)
		(drill 0.254)
		(layers "F.Cu" "B.Cu")
		(net "GND")
	)
	(via
		(at 224.536 -72.00265)
		(size 0.508)
		(drill 0.254)
		(layers "F.Cu" "B.Cu")
		(net "GND")
	)
	(via
		(at 165.857174 -131.572)
		(size 0.508)
		(drill 0.254)
		(layers "F.Cu" "B.Cu")
		(net "GND")
	)
	(via
		(at 20.446492 -146.237706)
		(size 0.508)
		(drill 0.254)
		(layers "F.Cu" "B.Cu")
		(net "GND")
	)
	(via
		(at 46.618906 -126.492)
		(size 0.508)
		(drill 0.254)
		(layers "F.Cu" "B.Cu")
		(net "GND")
	)
	(via
		(at 0.76327 -97.850452)
		(size 0.508)
		(drill 0.254)
		(layers "F.Cu" "B.Cu")
		(net "GND")
	)
	(via
		(at 199.771 -85.466936)
		(size 0.508)
		(drill 0.254)
		(layers "F.Cu" "B.Cu")
		(net "GND")
	)
	(via
		(at 230.124 -92.964)
		(size 0.508)
		(drill 0.254)
		(layers "F.Cu" "B.Cu")
		(net "GND")
	)
	(via
		(at 8.783828 -0.763016)
		(size 0.508)
		(drill 0.254)
		(layers "F.Cu" "B.Cu")
		(net "GND")
	)
	(via
		(at 285.79318 -9.037828)
		(size 0.508)
		(drill 0.254)
		(layers "F.Cu" "B.Cu")
		(net "GND")
	)
	(via
		(at 281.168094 -5.366004)
		(size 0.508)
		(drill 0.254)
		(layers "F.Cu" "B.Cu")
		(net "GND")
	)
	(via
		(at 275.52396 -27.432)
		(size 0.508)
		(drill 0.254)
		(layers "F.Cu" "B.Cu")
		(net "GND")
	)
	(via
		(at 281.168094 -4.604004)
		(size 0.508)
		(drill 0.254)
		(layers "F.Cu" "B.Cu")
		(net "GND")
	)
	(via
		(at 175.387 -50.292)
		(size 0.508)
		(drill 0.254)
		(layers "F.Cu" "B.Cu")
		(net "GND")
	)
	(via
		(at 25.526492 -146.237706)
		(size 0.508)
		(drill 0.254)
		(layers "F.Cu" "B.Cu")
		(net "GND")
	)
	(via
		(at 193.43624 -14.097)
		(size 0.508)
		(drill 0.254)
		(layers "F.Cu" "B.Cu")
		(net "GND")
	)
	(via
		(at 58.048906 -126.492)
		(size 0.508)
		(drill 0.254)
		(layers "F.Cu" "B.Cu")
		(net "GND")
	)
	(via
		(at 286.392874 -5.366004)
		(size 0.508)
		(drill 0.254)
		(layers "F.Cu" "B.Cu")
		(net "GND")
	)
	(via
		(at 70.240906 -131.572)
		(size 0.508)
		(drill 0.254)
		(layers "F.Cu" "B.Cu")
		(net "GND")
	)
	(via
		(at 212.74405 -81.534)
		(size 0.508)
		(drill 0.254)
		(layers "F.Cu" "B.Cu")
		(net "GND")
	)
	(via
		(at 327.236074 -43.424348)
		(size 0.508)
		(drill 0.254)
		(layers "F.Cu" "B.Cu")
		(net "GND")
	)
	(via
		(at 289.6743 -21.810218)
		(size 0.508)
		(drill 0.254)
		(layers "F.Cu" "B.Cu")
		(net "GND")
	)
	(via
		(at 136.85012 -113.03635)
		(size 0.508)
		(drill 0.254)
		(layers "F.Cu" "B.Cu")
		(net "GND")
	)
	(via
		(at 284.353 -21.082)
		(size 0.508)
		(drill 0.254)
		(layers "F.Cu" "B.Cu")
		(net "GND")
	)
	(via
		(at 282.308808 -137.414)
		(size 0.508)
		(drill 0.254)
		(layers "F.Cu" "B.Cu")
		(net "GND")
	)
	(via
		(at 102.108 -59.69)
		(size 0.508)
		(drill 0.254)
		(layers "F.Cu" "B.Cu")
		(net "GND")
	)
	(via
		(at 301.833534 -31.407608)
		(size 0.508)
		(drill 0.254)
		(layers "F.Cu" "B.Cu")
		(net "GND")
	)
	(via
		(at 58.048906 -131.572)
		(size 0.508)
		(drill 0.254)
		(layers "F.Cu" "B.Cu")
		(net "GND")
	)
	(via
		(at 177.0126 -13.5382)
		(size 0.508)
		(drill 0.254)
		(layers "F.Cu" "B.Cu")
		(net "GND")
	)
	(via
		(at 299.928534 -30.645608)
		(size 0.508)
		(drill 0.254)
		(layers "F.Cu" "B.Cu")
		(net "GND")
	)
	(via
		(at 86.36 -52.324)
		(size 0.508)
		(drill 0.254)
		(layers "F.Cu" "B.Cu")
		(net "GND")
	)
	(via
		(at 262.783828 -0.763016)
		(size 0.508)
		(drill 0.254)
		(layers "F.Cu" "B.Cu")
		(net "GND")
	)
	(via
		(at 169.926 -50.292)
		(size 0.508)
		(drill 0.254)
		(layers "F.Cu" "B.Cu")
		(net "GND")
	)
	(via
		(at 192.72504 -7.62)
		(size 0.508)
		(drill 0.254)
		(layers "F.Cu" "B.Cu")
		(net "GND")
	)
	(via
		(at 86.618826 -126.492)
		(size 0.508)
		(drill 0.254)
		(layers "F.Cu" "B.Cu")
		(net "GND")
	)
	(via
		(at 100.849938 -77.71765)
		(size 0.508)
		(drill 0.254)
		(layers "F.Cu" "B.Cu")
		(net "GND")
	)
	(via
		(at 257.703828 -0.763016)
		(size 0.508)
		(drill 0.254)
		(layers "F.Cu" "B.Cu")
		(net "GND")
	)
	(via
		(at 215.77046 -49.784)
		(size 0.508)
		(drill 0.254)
		(layers "F.Cu" "B.Cu")
		(net "GND")
	)
	(via
		(at 102.108 -60.452)
		(size 0.508)
		(drill 0.254)
		(layers "F.Cu" "B.Cu")
		(net "GND")
	)
	(via
		(at 264.286492 -146.237706)
		(size 0.508)
		(drill 0.254)
		(layers "F.Cu" "B.Cu")
		(net "GND")
	)
	(via
		(at 180.208174 -61.849)
		(size 0.508)
		(drill 0.254)
		(layers "F.Cu" "B.Cu")
		(net "GND")
	)
	(via
		(at 224.536 -92.964)
		(size 0.508)
		(drill 0.254)
		(layers "F.Cu" "B.Cu")
		(net "GND")
	)
	(via
		(at 161.183828 -0.763016)
		(size 0.508)
		(drill 0.254)
		(layers "F.Cu" "B.Cu")
		(net "GND")
	)
	(via
		(at 193.43624 -16.256)
		(size 0.508)
		(drill 0.254)
		(layers "F.Cu" "B.Cu")
		(net "GND")
	)
	(via
		(at 171.343828 -0.763016)
		(size 0.508)
		(drill 0.254)
		(layers "F.Cu" "B.Cu")
		(net "GND")
	)
	(via
		(at 168.4528 -14.4272)
		(size 0.508)
		(drill 0.254)
		(layers "F.Cu" "B.Cu")
		(net "GND")
	)
	(via
		(at 285.411926 -139.7)
		(size 0.508)
		(drill 0.254)
		(layers "F.Cu" "B.Cu")
		(net "GND")
	)
	(via
		(at 282.308808 -140.462)
		(size 0.508)
		(drill 0.254)
		(layers "F.Cu" "B.Cu")
		(net "GND")
	)
	(via
		(at 97.282 -52.324)
		(size 0.508)
		(drill 0.254)
		(layers "F.Cu" "B.Cu")
		(net "GND")
	)
	(via
		(at 108.204 -52.324)
		(size 0.508)
		(drill 0.254)
		(layers "F.Cu" "B.Cu")
		(net "GND")
	)
	(via
		(at 186.583828 -0.763016)
		(size 0.508)
		(drill 0.254)
		(layers "F.Cu" "B.Cu")
		(net "GND")
	)
	(via
		(at 188.595 -91.821)
		(size 0.508)
		(drill 0.254)
		(layers "F.Cu" "B.Cu")
		(net "GND")
	)
	(via
		(at 176.3268 -13.5382)
		(size 0.508)
		(drill 0.254)
		(layers "F.Cu" "B.Cu")
		(net "GND")
	)
	(via
		(at 179.324 -15.74165)
		(size 0.508)
		(drill 0.254)
		(layers "F.Cu" "B.Cu")
		(net "GND")
	)
	(via
		(at 315.086492 -146.237706)
		(size 0.508)
		(drill 0.254)
		(layers "F.Cu" "B.Cu")
		(net "GND")
	)
	(via
		(at 80.899 -50.419)
		(size 0.508)
		(drill 0.254)
		(layers "F.Cu" "B.Cu")
		(net "GND")
	)
	(via
		(at 280.533094 -4.604004)
		(size 0.508)
		(drill 0.254)
		(layers "F.Cu" "B.Cu")
		(net "GND")
	)
	(via
		(at 141.097 -59.944)
		(size 0.508)
		(drill 0.254)
		(layers "F.Cu" "B.Cu")
		(net "GND")
	)
	(via
		(at 281.203654 -13.649198)
		(size 0.508)
		(drill 0.254)
		(layers "F.Cu" "B.Cu")
		(net "GND")
	)
	(via
		(at 277.114 -25.273)
		(size 0.508)
		(drill 0.254)
		(layers "F.Cu" "B.Cu")
		(net "GND")
	)
	(via
		(at 98.810826 -131.572)
		(size 0.508)
		(drill 0.254)
		(layers "F.Cu" "B.Cu")
		(net "GND")
	)
	(via
		(at 288.33318 -9.799828)
		(size 0.508)
		(drill 0.254)
		(layers "F.Cu" "B.Cu")
		(net "GND")
	)
	(via
		(at 181.097174 -59.944)
		(size 0.508)
		(drill 0.254)
		(layers "F.Cu" "B.Cu")
		(net "GND")
	)
	(via
		(at 279.263094 -4.604004)
		(size 0.508)
		(drill 0.254)
		(layers "F.Cu" "B.Cu")
		(net "GND")
	)
	(via
		(at 232.537 -92.964)
		(size 0.508)
		(drill 0.254)
		(layers "F.Cu" "B.Cu")
		(net "GND")
	)
	(via
		(at 49.423828 -0.763016)
		(size 0.508)
		(drill 0.254)
		(layers "F.Cu" "B.Cu")
		(net "GND")
	)
	(via
		(at 283.070808 -138.176)
		(size 0.508)
		(drill 0.254)
		(layers "F.Cu" "B.Cu")
		(net "GND")
	)
	(via
		(at 229.87 -72.00265)
		(size 0.508)
		(drill 0.254)
		(layers "F.Cu" "B.Cu")
		(net "GND")
	)
	(via
		(at 174.371 -14.4272)
		(size 0.508)
		(drill 0.254)
		(layers "F.Cu" "B.Cu")
		(net "GND")
	)
	(via
		(at 262.763 -36.068)
		(size 0.508)
		(drill 0.254)
		(layers "F.Cu" "B.Cu")
		(net "GND")
	)
	(via
		(at 135.50265 -77.597)
		(size 0.508)
		(drill 0.254)
		(layers "F.Cu" "B.Cu")
		(net "GND")
	)
	(via
		(at 86.618826 -131.572)
		(size 0.508)
		(drill 0.254)
		(layers "F.Cu" "B.Cu")
		(net "GND")
	)
	(via
		(at 36.4236 -65.62344)
		(size 0.508)
		(drill 0.254)
		(layers "F.Cu" "B.Cu")
		(net "GND")
	)
	(via
		(at 5.206492 -146.237706)
		(size 0.508)
		(drill 0.254)
		(layers "F.Cu" "B.Cu")
		(net "GND")
	)
	(via
		(at 285.757874 -5.366004)
		(size 0.508)
		(drill 0.254)
		(layers "F.Cu" "B.Cu")
		(net "GND")
	)
	(via
		(at 287.027874 -5.366004)
		(size 0.508)
		(drill 0.254)
		(layers "F.Cu" "B.Cu")
		(net "GND")
	)
	(via
		(at 220.599 -92.964)
		(size 0.508)
		(drill 0.254)
		(layers "F.Cu" "B.Cu")
		(net "GND")
	)
	(via
		(at 308.503828 -0.763016)
		(size 0.508)
		(drill 0.254)
		(layers "F.Cu" "B.Cu")
		(net "GND")
	)
	(via
		(at 327.236074 -78.984348)
		(size 0.508)
		(drill 0.254)
		(layers "F.Cu" "B.Cu")
		(net "GND")
	)
	(via
		(at 0.76327 -15.191232)
		(size 0.508)
		(drill 0.254)
		(layers "F.Cu" "B.Cu")
		(net "GND")
	)
	(via
		(at 49.72304 -62.2554)
		(size 0.508)
		(drill 0.254)
		(layers "F.Cu" "B.Cu")
		(net "GND")
	)
	(via
		(at 324.977252 -145.746724)
		(size 0.508)
		(drill 0.254)
		(layers "F.Cu" "B.Cu")
		(net "GND")
	)
	(via
		(at 173.6344 -14.4272)
		(size 0.508)
		(drill 0.254)
		(layers "F.Cu" "B.Cu")
		(net "GND")
	)
	(via
		(at 140.850112 -77.71765)
		(size 0.508)
		(drill 0.254)
		(layers "F.Cu" "B.Cu")
		(net "GND")
	)
	(via
		(at 137.78865 -77.597)
		(size 0.508)
		(drill 0.254)
		(layers "F.Cu" "B.Cu")
		(net "GND")
	)
	(via
		(at 287.027874 -4.604004)
		(size 0.508)
		(drill 0.254)
		(layers "F.Cu" "B.Cu")
		(net "GND")
	)
	(via
		(at 286.42818 -9.799828)
		(size 0.508)
		(drill 0.254)
		(layers "F.Cu" "B.Cu")
		(net "GND")
	)
	(via
		(at 43.925236 -55.65394)
		(size 0.508)
		(drill 0.254)
		(layers "F.Cu" "B.Cu")
		(net "GND")
	)
	(via
		(at 39.40556 -61.01842)
		(size 0.508)
		(drill 0.254)
		(layers "F.Cu" "B.Cu")
		(net "GND")
	)
	(via
		(at 212.344 -66.167)
		(size 0.508)
		(drill 0.254)
		(layers "F.Cu" "B.Cu")
		(net "GND")
	)
	(via
		(at 54.503828 -0.763016)
		(size 0.508)
		(drill 0.254)
		(layers "F.Cu" "B.Cu")
		(net "GND")
	)
	(via
		(at 284.353 -21.844)
		(size 0.508)
		(drill 0.254)
		(layers "F.Cu" "B.Cu")
		(net "GND")
	)
	(via
		(at 110.240826 -131.572)
		(size 0.508)
		(drill 0.254)
		(layers "F.Cu" "B.Cu")
		(net "GND")
	)
	(via
		(at 278.023828 -0.763016)
		(size 0.508)
		(drill 0.254)
		(layers "F.Cu" "B.Cu")
		(net "GND")
	)
	(via
		(at 279.298654 -13.649198)
		(size 0.508)
		(drill 0.254)
		(layers "F.Cu" "B.Cu")
		(net "GND")
	)
	(via
		(at 75.438 -50.419)
		(size 0.508)
		(drill 0.254)
		(layers "F.Cu" "B.Cu")
		(net "GND")
	)
	(via
		(at 241.427 -92.964)
		(size 0.508)
		(drill 0.254)
		(layers "F.Cu" "B.Cu")
		(net "GND")
	)
	(via
		(at 0.76327 -102.930452)
		(size 0.508)
		(drill 0.254)
		(layers "F.Cu" "B.Cu")
		(net "GND")
	)
	(via
		(at 238.886492 -146.237706)
		(size 0.508)
		(drill 0.254)
		(layers "F.Cu" "B.Cu")
		(net "GND")
	)
	(via
		(at 192.7606 -6.9596)
		(size 0.508)
		(drill 0.254)
		(layers "F.Cu" "B.Cu")
		(net "GND")
	)
	(via
		(at 278.663654 -13.649198)
		(size 0.508)
		(drill 0.254)
		(layers "F.Cu" "B.Cu")
		(net "GND")
	)
	(via
		(at 180.074824 -77.597)
		(size 0.508)
		(drill 0.254)
		(layers "F.Cu" "B.Cu")
		(net "GND")
	)
	(via
		(at 180.84546 -50.292)
		(size 0.508)
		(drill 0.254)
		(layers "F.Cu" "B.Cu")
		(net "GND")
	)
	(via
		(at 231.775 -92.964)
		(size 0.508)
		(drill 0.254)
		(layers "F.Cu" "B.Cu")
		(net "GND")
	)
	(via
		(at 169.926 -51.562)
		(size 0.508)
		(drill 0.254)
		(layers "F.Cu" "B.Cu")
		(net "GND")
	)
	(via
		(at 215.77046 -51.689)
		(size 0.508)
		(drill 0.254)
		(layers "F.Cu" "B.Cu")
		(net "GND")
	)
	(via
		(at 234.188 -92.964)
		(size 0.508)
		(drill 0.254)
		(layers "F.Cu" "B.Cu")
		(net "GND")
	)
	(via
		(at 59.583828 -0.763016)
		(size 0.508)
		(drill 0.254)
		(layers "F.Cu" "B.Cu")
		(net "GND")
	)
	(via
		(at 283.070808 -139.7)
		(size 0.508)
		(drill 0.254)
		(layers "F.Cu" "B.Cu")
		(net "GND")
	)
	(via
		(at 227.223828 -0.763016)
		(size 0.508)
		(drill 0.254)
		(layers "F.Cu" "B.Cu")
		(net "GND")
	)
	(via
		(at 326.838564 -3.209036)
		(size 0.508)
		(drill 0.254)
		(layers "F.Cu" "B.Cu")
		(net "GND")
	)
	(via
		(at 180.84546 -49.657)
		(size 0.508)
		(drill 0.254)
		(layers "F.Cu" "B.Cu")
		(net "GND")
	)
	(via
		(at 79.903828 -0.763016)
		(size 0.508)
		(drill 0.254)
		(layers "F.Cu" "B.Cu")
		(net "GND")
	)
	(via
		(at 287.7693 -21.810218)
		(size 0.508)
		(drill 0.254)
		(layers "F.Cu" "B.Cu")
		(net "GND")
	)
	(via
		(at 190.241174 -126.492)
		(size 0.508)
		(drill 0.254)
		(layers "F.Cu" "B.Cu")
		(net "GND")
	)
	(via
		(at 232.537 -72.00265)
		(size 0.508)
		(drill 0.254)
		(layers "F.Cu" "B.Cu")
		(net "GND")
	)
	(via
		(at 215.77046 -52.324)
		(size 0.508)
		(drill 0.254)
		(layers "F.Cu" "B.Cu")
		(net "GND")
	)
	(via
		(at 271.1704 -31.2928)
		(size 0.508)
		(drill 0.254)
		(layers "F.Cu" "B.Cu")
		(net "GND")
	)
	(via
		(at 178.049174 -131.572)
		(size 0.508)
		(drill 0.254)
		(layers "F.Cu" "B.Cu")
		(net "GND")
	)
	(via
		(at 223.012 -91.05265)
		(size 0.508)
		(drill 0.254)
		(layers "F.Cu" "B.Cu")
		(net "GND")
	)
	(via
		(at 289.686492 -146.237706)
		(size 0.508)
		(drill 0.254)
		(layers "F.Cu" "B.Cu")
		(net "GND")
	)
	(via
		(at 192.72504 -14.097)
		(size 0.508)
		(drill 0.254)
		(layers "F.Cu" "B.Cu")
		(net "GND")
	)
	(via
		(at 44.00931 -86.500208)
		(size 0.508)
		(drill 0.254)
		(layers "F.Cu" "B.Cu")
		(net "GND")
	)
	(via
		(at 284.649926 -138.176)
		(size 0.508)
		(drill 0.254)
		(layers "F.Cu" "B.Cu")
		(net "GND")
	)
	(via
		(at 284.606492 -146.237706)
		(size 0.508)
		(drill 0.254)
		(layers "F.Cu" "B.Cu")
		(net "GND")
	)
	(via
		(at 294.4622 -32.9438)
		(size 0.508)
		(drill 0.254)
		(layers "F.Cu" "B.Cu")
		(net "GND")
	)
	(via
		(at 271.96161 -45.36059)
		(size 0.508)
		(drill 0.254)
		(layers "F.Cu" "B.Cu")
		(net "GND")
	)
	(via
		(at 90.063828 -0.763016)
		(size 0.508)
		(drill 0.254)
		(layers "F.Cu" "B.Cu")
		(net "GND")
	)
	(via
		(at 301.198534 -30.645608)
		(size 0.508)
		(drill 0.254)
		(layers "F.Cu" "B.Cu")
		(net "GND")
	)
	(via
		(at 140.07465 -77.597)
		(size 0.508)
		(drill 0.254)
		(layers "F.Cu" "B.Cu")
		(net "GND")
	)
	(via
		(at 191.663828 -0.763016)
		(size 0.508)
		(drill 0.254)
		(layers "F.Cu" "B.Cu")
		(net "GND")
	)
	(via
		(at 287.06318 -9.037828)
		(size 0.508)
		(drill 0.254)
		(layers "F.Cu" "B.Cu")
		(net "GND")
	)
	(via
		(at 327.236074 -58.664348)
		(size 0.508)
		(drill 0.254)
		(layers "F.Cu" "B.Cu")
		(net "GND")
	)
	(via
		(at 225.298 -92.964)
		(size 0.508)
		(drill 0.254)
		(layers "F.Cu" "B.Cu")
		(net "GND")
	)
	(via
		(at 0.76327 -57.210452)
		(size 0.508)
		(drill 0.254)
		(layers "F.Cu" "B.Cu")
		(net "GND")
	)
	(via
		(at 236.601 -92.964)
		(size 0.508)
		(drill 0.254)
		(layers "F.Cu" "B.Cu")
		(net "GND")
	)
	(via
		(at 0.76327 -62.290452)
		(size 0.508)
		(drill 0.254)
		(layers "F.Cu" "B.Cu")
		(net "GND")
	)
	(via
		(at 74.823828 -0.763016)
		(size 0.508)
		(drill 0.254)
		(layers "F.Cu" "B.Cu")
		(net "GND")
	)
	(via
		(at 164.465 -51.562)
		(size 0.508)
		(drill 0.254)
		(layers "F.Cu" "B.Cu")
		(net "GND")
	)
	(via
		(at 56.850026 -113.03635)
		(size 0.508)
		(drill 0.254)
		(layers "F.Cu" "B.Cu")
		(net "GND")
	)
	(via
		(at 214.56904 -85.363558)
		(size 0.508)
		(drill 0.254)
		(layers "F.Cu" "B.Cu")
		(net "GND")
	)
	(via
		(at 192.72504 -11.938)
		(size 0.508)
		(drill 0.254)
		(layers "F.Cu" "B.Cu")
		(net "GND")
	)
	(via
		(at 177.673 -8.763)
		(size 0.508)
		(drill 0.254)
		(layers "F.Cu" "B.Cu")
		(net "GND")
	)
	(via
		(at 285.411926 -138.938)
		(size 0.508)
		(drill 0.254)
		(layers "F.Cu" "B.Cu")
		(net "GND")
	)
	(via
		(at 192.06464 -9.779)
		(size 0.508)
		(drill 0.254)
		(layers "F.Cu" "B.Cu")
		(net "GND")
	)
	(via
		(at 0.76327 -72.450452)
		(size 0.508)
		(drill 0.254)
		(layers "F.Cu" "B.Cu")
		(net "GND")
	)
	(via
		(at 327.236074 -134.864348)
		(size 0.508)
		(drill 0.254)
		(layers "F.Cu" "B.Cu")
		(net "GND")
	)
	(via
		(at 64.663828 -0.763016)
		(size 0.508)
		(drill 0.254)
		(layers "F.Cu" "B.Cu")
		(net "GND")
	)
	(via
		(at 327.236074 -63.744348)
		(size 0.508)
		(drill 0.254)
		(layers "F.Cu" "B.Cu")
		(net "GND")
	)
	(via
		(at 149.733 -113.411)
		(size 0.508)
		(drill 0.254)
		(layers "F.Cu" "B.Cu")
		(net "GND")
	)
	(via
		(at 259.206492 -146.237706)
		(size 0.508)
		(drill 0.254)
		(layers "F.Cu" "B.Cu")
		(net "GND")
	)
	(via
		(at 175.387 -51.562)
		(size 0.508)
		(drill 0.254)
		(layers "F.Cu" "B.Cu")
		(net "GND")
	)
	(via
		(at 327.236074 -129.784348)
		(size 0.508)
		(drill 0.254)
		(layers "F.Cu" "B.Cu")
		(net "GND")
	)
	(via
		(at 272.5928 -32.7152)
		(size 0.508)
		(drill 0.254)
		(layers "F.Cu" "B.Cu")
		(net "GND")
	)
	(via
		(at 191.003174 -126.492)
		(size 0.508)
		(drill 0.254)
		(layers "F.Cu" "B.Cu")
		(net "GND")
	)
	(via
		(at 282.308808 -136.652)
		(size 0.508)
		(drill 0.254)
		(layers "F.Cu" "B.Cu")
		(net "GND")
	)
	(via
		(at 110.383828 -0.763016)
		(size 0.508)
		(drill 0.254)
		(layers "F.Cu" "B.Cu")
		(net "GND")
	)
	(via
		(at 71.002906 -126.492)
		(size 0.508)
		(drill 0.254)
		(layers "F.Cu" "B.Cu")
		(net "GND")
	)
	(via
		(at 275.40204 -38.7604)
		(size 0.508)
		(drill 0.254)
		(layers "F.Cu" "B.Cu")
		(net "GND")
	)
	(via
		(at 229.362 -92.964)
		(size 0.508)
		(drill 0.254)
		(layers "F.Cu" "B.Cu")
		(net "GND")
	)
	(via
		(at 48.19904 -61.4934)
		(size 0.508)
		(drill 0.254)
		(layers "F.Cu" "B.Cu")
		(net "GND")
	)
	(via
		(at 237.383828 -0.763016)
		(size 0.508)
		(drill 0.254)
		(layers "F.Cu" "B.Cu")
		(net "GND")
	)
	(via
		(at 227.711 -92.964)
		(size 0.508)
		(drill 0.254)
		(layers "F.Cu" "B.Cu")
		(net "GND")
	)
	(via
		(at 278.6634 -9.799828)
		(size 0.508)
		(drill 0.254)
		(layers "F.Cu" "B.Cu")
		(net "GND")
	)
	(via
		(at 105.303828 -0.763016)
		(size 0.508)
		(drill 0.254)
		(layers "F.Cu" "B.Cu")
		(net "GND")
	)
	(via
		(at 0.76327 -82.610452)
		(size 0.508)
		(drill 0.254)
		(layers "F.Cu" "B.Cu")
		(net "GND")
	)
	(via
		(at 178.811174 -126.492)
		(size 0.508)
		(drill 0.254)
		(layers "F.Cu" "B.Cu")
		(net "GND")
	)
	(via
		(at 231.775 -83.30565)
		(size 0.508)
		(drill 0.254)
		(layers "F.Cu" "B.Cu")
		(net "GND")
	)
	(via
		(at 327.236074 -119.624348)
		(size 0.508)
		(drill 0.254)
		(layers "F.Cu" "B.Cu")
		(net "GND")
	)
	(via
		(at 43.868848 -56.454802)
		(size 0.508)
		(drill 0.254)
		(layers "F.Cu" "B.Cu")
		(net "GND")
	)
	(via
		(at 86.36 -50.419)
		(size 0.508)
		(drill 0.254)
		(layers "F.Cu" "B.Cu")
		(net "GND")
	)
	(via
		(at 287.662874 -5.366004)
		(size 0.508)
		(drill 0.254)
		(layers "F.Cu" "B.Cu")
		(net "GND")
	)
	(via
		(at 279.2984 -9.799828)
		(size 0.508)
		(drill 0.254)
		(layers "F.Cu" "B.Cu")
		(net "GND")
	)
	(via
		(at 165.857174 -126.492)
		(size 0.508)
		(drill 0.254)
		(layers "F.Cu" "B.Cu")
		(net "GND")
	)
	(via
		(at 0.76327 -8.841232)
		(size 0.508)
		(drill 0.254)
		(layers "F.Cu" "B.Cu")
		(net "GND")
	)
	(via
		(at 111.002826 -126.492)
		(size 0.508)
		(drill 0.254)
		(layers "F.Cu" "B.Cu")
		(net "GND")
	)
	(via
		(at 240.538 -74.542904)
		(size 0.508)
		(drill 0.254)
		(layers "F.Cu" "B.Cu")
		(net "GND")
	)
	(via
		(at 150.241 -131.572)
		(size 0.508)
		(drill 0.254)
		(layers "F.Cu" "B.Cu")
		(net "GND")
	)
	(via
		(at 75.438 -51.689)
		(size 0.508)
		(drill 0.254)
		(layers "F.Cu" "B.Cu")
		(net "GND")
	)
	(via
		(at 285.757874 -4.604004)
		(size 0.508)
		(drill 0.254)
		(layers "F.Cu" "B.Cu")
		(net "GND")
	)
	(via
		(at 91.821 -50.419)
		(size 0.508)
		(drill 0.254)
		(layers "F.Cu" "B.Cu")
		(net "GND")
	)
	(via
		(at 327.236074 -94.224348)
		(size 0.508)
		(drill 0.254)
		(layers "F.Cu" "B.Cu")
		(net "GND")
	)
	(via
		(at 0.76327 -52.130452)
		(size 0.508)
		(drill 0.254)
		(layers "F.Cu" "B.Cu")
		(net "GND")
	)
	(via
		(at 282.829 -37.465)
		(size 0.508)
		(drill 0.254)
		(layers "F.Cu" "B.Cu")
		(net "GND")
	)
	(via
		(at 284.649926 -137.414)
		(size 0.508)
		(drill 0.254)
		(layers "F.Cu" "B.Cu")
		(net "GND")
	)
	(via
		(at 293.116 -38.481)
		(size 0.508)
		(drill 0.254)
		(layers "F.Cu" "B.Cu")
		(net "GND")
	)
	(via
		(at 280.5684 -9.037828)
		(size 0.508)
		(drill 0.254)
		(layers "F.Cu" "B.Cu")
		(net "GND")
	)
	(via
		(at 0.76327 -87.690452)
		(size 0.508)
		(drill 0.254)
		(layers "F.Cu" "B.Cu")
		(net "GND")
	)
	(via
		(at 0.767842 -139.525248)
		(size 0.508)
		(drill 0.254)
		(layers "F.Cu" "B.Cu")
		(net "GND")
	)
	(via
		(at 216.027 -91.45905)
		(size 0.508)
		(drill 0.254)
		(layers "F.Cu" "B.Cu")
		(net "GND")
	)
	(via
		(at 284.649926 -140.462)
		(size 0.508)
		(drill 0.254)
		(layers "F.Cu" "B.Cu")
		(net "GND")
	)
	(via
		(at 230.109014 -77.851)
		(size 0.508)
		(drill 0.254)
		(layers "F.Cu" "B.Cu")
		(net "GND")
	)
	(via
		(at 279.263094 -5.366004)
		(size 0.508)
		(drill 0.254)
		(layers "F.Cu" "B.Cu")
		(net "GND")
	)
	(via
		(at 192.06464 -7.62)
		(size 0.508)
		(drill 0.254)
		(layers "F.Cu" "B.Cu")
		(net "GND")
	)
	(via
		(at 51.24704 -61.4934)
		(size 0.508)
		(drill 0.254)
		(layers "F.Cu" "B.Cu")
		(net "GND")
	)
	(via
		(at 284.649926 -136.652)
		(size 0.508)
		(drill 0.254)
		(layers "F.Cu" "B.Cu")
		(net "GND")
	)
	(via
		(at 151.023828 -0.763016)
		(size 0.508)
		(drill 0.254)
		(layers "F.Cu" "B.Cu")
		(net "GND")
	)
	(via
		(at 289.0393 -21.048218)
		(size 0.508)
		(drill 0.254)
		(layers "F.Cu" "B.Cu")
		(net "GND")
	)
	(via
		(at 193.43624 -7.62)
		(size 0.508)
		(drill 0.254)
		(layers "F.Cu" "B.Cu")
		(net "GND")
	)
	(via
		(at 216.154 -66.17335)
		(size 0.508)
		(drill 0.254)
		(layers "F.Cu" "B.Cu")
		(net "GND")
	)
	(via
		(at 170.4594 -14.4272)
		(size 0.508)
		(drill 0.254)
		(layers "F.Cu" "B.Cu")
		(net "GND")
	)
	(via
		(at 159.004 -50.292)
		(size 0.508)
		(drill 0.254)
		(layers "F.Cu" "B.Cu")
		(net "GND")
	)
	(via
		(at 293.263828 -0.763016)
		(size 0.508)
		(drill 0.254)
		(layers "F.Cu" "B.Cu")
		(net "GND")
	)
	(via
		(at 15.366492 -146.237706)
		(size 0.508)
		(drill 0.254)
		(layers "F.Cu" "B.Cu")
		(net "GND")
	)
	(via
		(at 61.595 -61.722)
		(size 0.508)
		(drill 0.254)
		(layers "F.Cu" "B.Cu")
		(net "GND")
	)
	(via
		(at 191.003174 -131.572)
		(size 0.508)
		(drill 0.254)
		(layers "F.Cu" "B.Cu")
		(net "GND")
	)
	(via
		(at 222.123 -92.964)
		(size 0.508)
		(drill 0.254)
		(layers "F.Cu" "B.Cu")
		(net "GND")
	)
	(via
		(at 186.30646 -52.197)
		(size 0.508)
		(drill 0.254)
		(layers "F.Cu" "B.Cu")
		(net "GND")
	)
	(via
		(at 10.045446 -115.548664)
		(size 0.508)
		(drill 0.254)
		(layers "F.Cu" "B.Cu")
		(net "GND")
	)
	(via
		(at 97.282 -49.784)
		(size 0.508)
		(drill 0.254)
		(layers "F.Cu" "B.Cu")
		(net "GND")
	)
	(via
		(at 71.002906 -131.572)
		(size 0.508)
		(drill 0.254)
		(layers "F.Cu" "B.Cu")
		(net "GND")
	)
	(via
		(at 222.143828 -0.763016)
		(size 0.508)
		(drill 0.254)
		(layers "F.Cu" "B.Cu")
		(net "GND")
	)
	(via
		(at 210.185 -83.566)
		(size 0.508)
		(drill 0.254)
		(layers "F.Cu" "B.Cu")
		(net "GND")
	)
	(via
		(at 279.933654 -14.411198)
		(size 0.508)
		(drill 0.254)
		(layers "F.Cu" "B.Cu")
		(net "GND")
	)
	(via
		(at 159.004 -49.657)
		(size 0.508)
		(drill 0.254)
		(layers "F.Cu" "B.Cu")
		(net "GND")
	)
	(via
		(at 86.36 -49.784)
		(size 0.508)
		(drill 0.254)
		(layers "F.Cu" "B.Cu")
		(net "GND")
	)
	(via
		(at 285.411926 -137.414)
		(size 0.508)
		(drill 0.254)
		(layers "F.Cu" "B.Cu")
		(net "GND")
	)
	(via
		(at 109.224826 -112.84204)
		(size 0.508)
		(drill 0.254)
		(layers "F.Cu" "B.Cu")
		(net "GND")
	)
	(via
		(at 293.37 -31.727902)
		(size 0.508)
		(drill 0.254)
		(layers "F.Cu" "B.Cu")
		(net "GND")
	)
	(via
		(at 279.2984 -9.037828)
		(size 0.508)
		(drill 0.254)
		(layers "F.Cu" "B.Cu")
		(net "GND")
	)
	(via
		(at 181.097174 -60.706)
		(size 0.508)
		(drill 0.254)
		(layers "F.Cu" "B.Cu")
		(net "GND")
	)
	(via
		(at 73.84288 -86.445852)
		(size 0.508)
		(drill 0.254)
		(layers "F.Cu" "B.Cu")
		(net "GND")
	)
	(via
		(at 125.857 -126.492)
		(size 0.508)
		(drill 0.254)
		(layers "F.Cu" "B.Cu")
		(net "GND")
	)
	(via
		(at 283.070808 -137.414)
		(size 0.508)
		(drill 0.254)
		(layers "F.Cu" "B.Cu")
		(net "GND")
	)
	(via
		(at 176.423828 -0.763016)
		(size 0.508)
		(drill 0.254)
		(layers "F.Cu" "B.Cu")
		(net "GND")
	)
	(via
		(at 125.857 -131.572)
		(size 0.508)
		(drill 0.254)
		(layers "F.Cu" "B.Cu")
		(net "GND")
	)
	(via
		(at 269.366492 -146.237706)
		(size 0.508)
		(drill 0.254)
		(layers "F.Cu" "B.Cu")
		(net "GND")
	)
	(via
		(at 3.242818 -18.306288)
		(size 0.508)
		(drill 0.254)
		(layers "F.Cu" "B.Cu")
		(net "GND")
	)
	(via
		(at 4.967732 -115.465606)
		(size 0.508)
		(drill 0.254)
		(layers "F.Cu" "B.Cu")
		(net "GND")
	)
	(via
		(at 192.06464 -11.938)
		(size 0.508)
		(drill 0.254)
		(layers "F.Cu" "B.Cu")
		(net "GND")
	)
	(via
		(at 140.208 -61.849)
		(size 0.508)
		(drill 0.254)
		(layers "F.Cu" "B.Cu")
		(net "GND")
	)
	(via
		(at 226.914202 -75.87996)
		(size 0.508)
		(drill 0.254)
		(layers "F.Cu" "B.Cu")
		(net "GND")
	)
	(via
		(at 171.704 -14.4272)
		(size 0.508)
		(drill 0.254)
		(layers "F.Cu" "B.Cu")
		(net "GND")
	)
	(via
		(at 280.533094 -5.366004)
		(size 0.508)
		(drill 0.254)
		(layers "F.Cu" "B.Cu")
		(net "GND")
	)
	(via
		(at 327.236074 -23.104348)
		(size 0.508)
		(drill 0.254)
		(layers "F.Cu" "B.Cu")
		(net "GND")
	)
	(via
		(at 69.743828 -0.763016)
		(size 0.508)
		(drill 0.254)
		(layers "F.Cu" "B.Cu")
		(net "GND")
	)
	(via
		(at 288.297874 -5.366004)
		(size 0.508)
		(drill 0.254)
		(layers "F.Cu" "B.Cu")
		(net "GND")
	)
	(via
		(at 327.236074 -53.584348)
		(size 0.508)
		(drill 0.254)
		(layers "F.Cu" "B.Cu")
		(net "GND")
	)
	(via
		(at 300.563534 -31.407608)
		(size 0.508)
		(drill 0.254)
		(layers "F.Cu" "B.Cu")
		(net "GND")
	)
	(via
		(at 84.983828 -0.763016)
		(size 0.508)
		(drill 0.254)
		(layers "F.Cu" "B.Cu")
		(net "GND")
	)
	(via
		(at 176.022 -14.3764)
		(size 0.508)
		(drill 0.254)
		(layers "F.Cu" "B.Cu")
		(net "GND")
	)
	(via
		(at 91.821 -52.324)
		(size 0.508)
		(drill 0.254)
		(layers "F.Cu" "B.Cu")
		(net "GND")
	)
	(via
		(at 327.236074 -89.144348)
		(size 0.508)
		(drill 0.254)
		(layers "F.Cu" "B.Cu")
		(net "GND")
	)
	(via
		(at 58.810906 -131.572)
		(size 0.508)
		(drill 0.254)
		(layers "F.Cu" "B.Cu")
		(net "GND")
	)
	(via
		(at 51.24704 -62.2554)
		(size 0.508)
		(drill 0.254)
		(layers "F.Cu" "B.Cu")
		(net "GND")
	)
	(via
		(at 327.236074 -99.304348)
		(size 0.508)
		(drill 0.254)
		(layers "F.Cu" "B.Cu")
		(net "GND")
	)
	(via
		(at 166.4462 -14.4272)
		(size 0.508)
		(drill 0.254)
		(layers "F.Cu" "B.Cu")
		(net "GND")
	)
	(via
		(at 327.236074 -84.064348)
		(size 0.508)
		(drill 0.254)
		(layers "F.Cu" "B.Cu")
		(net "GND")
	)
	(via
		(at 215.265 -92.964)
		(size 0.508)
		(drill 0.254)
		(layers "F.Cu" "B.Cu")
		(net "GND")
	)
	(via
		(at 175.387 -49.657)
		(size 0.508)
		(drill 0.254)
		(layers "F.Cu" "B.Cu")
		(net "GND")
	)
	(via
		(at 153.543 -51.562)
		(size 0.508)
		(drill 0.254)
		(layers "F.Cu" "B.Cu")
		(net "GND")
	)
	(via
		(at 35.6616 -66.38544)
		(size 0.508)
		(drill 0.254)
		(layers "F.Cu" "B.Cu")
		(net "GND")
	)
	(via
		(at 110.240826 -126.492)
		(size 0.508)
		(drill 0.254)
		(layers "F.Cu" "B.Cu")
		(net "GND")
	)
	(via
		(at 219.71 -79.5528)
		(size 0.508)
		(drill 0.254)
		(layers "F.Cu" "B.Cu")
		(net "GND")
	)
	(via
		(at 166.263828 -0.763016)
		(size 0.508)
		(drill 0.254)
		(layers "F.Cu" "B.Cu")
		(net "GND")
	)
	(via
		(at 217.551 -92.964)
		(size 0.508)
		(drill 0.254)
		(layers "F.Cu" "B.Cu")
		(net "GND")
	)
	(via
		(at 164.465 -52.197)
		(size 0.508)
		(drill 0.254)
		(layers "F.Cu" "B.Cu")
		(net "GND")
	)
	(via
		(at 30.606492 -146.237706)
		(size 0.508)
		(drill 0.254)
		(layers "F.Cu" "B.Cu")
		(net "GND")
	)
	(via
		(at 301.198534 -31.407608)
		(size 0.508)
		(drill 0.254)
		(layers "F.Cu" "B.Cu")
		(net "GND")
	)
	(via
		(at 285.411926 -138.176)
		(size 0.508)
		(drill 0.254)
		(layers "F.Cu" "B.Cu")
		(net "GND")
	)
	(via
		(at 0.767842 -133.175248)
		(size 0.508)
		(drill 0.254)
		(layers "F.Cu" "B.Cu")
		(net "GND")
	)
	(via
		(at 169.6974 -14.4272)
		(size 0.508)
		(drill 0.254)
		(layers "F.Cu" "B.Cu")
		(net "GND")
	)
	(via
		(at 288.183828 -0.763016)
		(size 0.508)
		(drill 0.254)
		(layers "F.Cu" "B.Cu")
		(net "GND")
	)
	(via
		(at 48.96104 -62.2554)
		(size 0.508)
		(drill 0.254)
		(layers "F.Cu" "B.Cu")
		(net "GND")
	)
	(via
		(at 320.166492 -146.237706)
		(size 0.508)
		(drill 0.254)
		(layers "F.Cu" "B.Cu")
		(net "GND")
	)
	(via
		(at 92.849954 -77.71765)
		(size 0.508)
		(drill 0.254)
		(layers "F.Cu" "B.Cu")
		(net "GND")
	)
	(via
		(at 282.308808 -138.176)
		(size 0.508)
		(drill 0.254)
		(layers "F.Cu" "B.Cu")
		(net "GND")
	)
	(via
		(at 151.003 -126.492)
		(size 0.508)
		(drill 0.254)
		(layers "F.Cu" "B.Cu")
		(net "GND")
	)
	(via
		(at 120.16613 -86.446106)
		(size 0.508)
		(drill 0.254)
		(layers "F.Cu" "B.Cu")
		(net "GND")
	)
	(via
		(at 97.282 -51.689)
		(size 0.508)
		(drill 0.254)
		(layers "F.Cu" "B.Cu")
		(net "GND")
	)
	(via
		(at 153.543 -49.657)
		(size 0.508)
		(drill 0.254)
		(layers "F.Cu" "B.Cu")
		(net "GND")
	)
	(via
		(at 299.293534 -30.645608)
		(size 0.508)
		(drill 0.254)
		(layers "F.Cu" "B.Cu")
		(net "GND")
	)
	(via
		(at 169.926 -49.657)
		(size 0.508)
		(drill 0.254)
		(layers "F.Cu" "B.Cu")
		(net "GND")
	)
	(via
		(at 180.84546 -51.562)
		(size 0.508)
		(drill 0.254)
		(layers "F.Cu" "B.Cu")
		(net "GND")
	)
	(via
		(at 271.5006 -27.94)
		(size 0.508)
		(drill 0.254)
		(layers "F.Cu" "B.Cu")
		(net "GND")
	)
	(via
		(at 153.543 -52.197)
		(size 0.508)
		(drill 0.254)
		(layers "F.Cu" "B.Cu")
		(net "GND")
	)
	(via
		(at 208.153 -83.566)
		(size 0.508)
		(drill 0.254)
		(layers "F.Cu" "B.Cu")
		(net "GND")
	)
	(via
		(at 38.98392 -54.1909)
		(size 0.508)
		(drill 0.254)
		(layers "F.Cu" "B.Cu")
		(net "GND")
	)
	(via
		(at 151.003 -131.572)
		(size 0.508)
		(drill 0.254)
		(layers "F.Cu" "B.Cu")
		(net "GND")
	)
	(via
		(at 3.761994 -0.947928)
		(size 0.508)
		(drill 0.254)
		(layers "F.Cu" "B.Cu")
		(net "GND")
	)
	(via
		(at 327.236074 -33.264348)
		(size 0.508)
		(drill 0.254)
		(layers "F.Cu" "B.Cu")
		(net "GND")
	)
	(via
		(at 211.983828 -0.763016)
		(size 0.508)
		(drill 0.254)
		(layers "F.Cu" "B.Cu")
		(net "GND")
	)
	(via
		(at 280.5684 -9.799828)
		(size 0.508)
		(drill 0.254)
		(layers "F.Cu" "B.Cu")
		(net "GND")
	)
	(via
		(at 176.850294 -113.036096)
		(size 0.508)
		(drill 0.254)
		(layers "F.Cu" "B.Cu")
		(net "GND")
	)
	(via
		(at 91.821 -49.784)
		(size 0.508)
		(drill 0.254)
		(layers "F.Cu" "B.Cu")
		(net "GND")
	)
	(via
		(at 327.054464 -143.227806)
		(size 0.508)
		(drill 0.254)
		(layers "F.Cu" "B.Cu")
		(net "GND")
	)
	(via
		(at 173.86935 -8.255)
		(size 0.508)
		(drill 0.254)
		(layers "F.Cu" "B.Cu")
		(net "GND")
	)
	(via
		(at 281.2034 -9.037828)
		(size 0.508)
		(drill 0.254)
		(layers "F.Cu" "B.Cu")
		(net "GND")
	)
	(via
		(at 279.298654 -14.411198)
		(size 0.508)
		(drill 0.254)
		(layers "F.Cu" "B.Cu")
		(net "GND")
	)
	(via
		(at 60.850018 -77.71765)
		(size 0.508)
		(drill 0.254)
		(layers "F.Cu" "B.Cu")
		(net "GND")
	)
	(via
		(at 46.68901 -56.109362)
		(size 0.508)
		(drill 0.254)
		(layers "F.Cu" "B.Cu")
		(net "GND")
	)
	(via
		(at 109.732826 -114.81435)
		(size 0.508)
		(drill 0.254)
		(layers "F.Cu" "B.Cu")
		(net "GND")
	)
	(via
		(at 281.2034 -9.799828)
		(size 0.508)
		(drill 0.254)
		(layers "F.Cu" "B.Cu")
		(net "GND")
	)
	(via
		(at 298.343828 -0.763016)
		(size 0.508)
		(drill 0.254)
		(layers "F.Cu" "B.Cu")
		(net "GND")
	)
	(via
		(at 1.15316 -143.764762)
		(size 0.508)
		(drill 0.254)
		(layers "F.Cu" "B.Cu")
		(net "GND")
	)
	(via
		(at 113.60277 -86.446106)
		(size 0.508)
		(drill 0.254)
		(layers "F.Cu" "B.Cu")
		(net "GND")
	)
	(via
		(at 6.926834 -32.333692)
		(size 0.508)
		(drill 0.254)
		(layers "F.Cu" "B.Cu")
		(net "GND")
	)
	(via
		(at 153.543 -50.292)
		(size 0.508)
		(drill 0.254)
		(layers "F.Cu" "B.Cu")
		(net "GND")
	)
	(via
		(at 35.6616 -65.62344)
		(size 0.508)
		(drill 0.254)
		(layers "F.Cu" "B.Cu")
		(net "GND")
	)
	(via
		(at 254.126492 -146.237706)
		(size 0.508)
		(drill 0.254)
		(layers "F.Cu" "B.Cu")
		(net "GND")
	)
	(via
		(at 36.4236 -64.86144)
		(size 0.508)
		(drill 0.254)
		(layers "F.Cu" "B.Cu")
		(net "GND")
	)
	(via
		(at 100.223828 -0.763016)
		(size 0.508)
		(drill 0.254)
		(layers "F.Cu" "B.Cu")
		(net "GND")
	)
	(via
		(at 45.856906 -131.572)
		(size 0.508)
		(drill 0.254)
		(layers "F.Cu" "B.Cu")
		(net "GND")
	)
	(via
		(at 172.466 -14.4272)
		(size 0.508)
		(drill 0.254)
		(layers "F.Cu" "B.Cu")
		(net "GND")
	)
	(via
		(at 324.524878 -1.048512)
		(size 0.508)
		(drill 0.254)
		(layers "F.Cu" "B.Cu")
		(net "GND")
	)
	(via
		(at 279.9334 -9.799828)
		(size 0.508)
		(drill 0.254)
		(layers "F.Cu" "B.Cu")
		(net "GND")
	)
	(via
		(at 0.76327 -92.770452)
		(size 0.508)
		(drill 0.254)
		(layers "F.Cu" "B.Cu")
		(net "GND")
	)
	(via
		(at 139.573 -113.036096)
		(size 0.508)
		(drill 0.254)
		(layers "F.Cu" "B.Cu")
		(net "GND")
	)
	(via
		(at 212.24494 -90.31986)
		(size 0.508)
		(drill 0.254)
		(layers "F.Cu" "B.Cu")
		(net "GND")
	)
	(via
		(at 86.36 -51.689)
		(size 0.508)
		(drill 0.254)
		(layers "F.Cu" "B.Cu")
		(net "GND")
	)
	(via
		(at 222.885 -72.00265)
		(size 0.508)
		(drill 0.254)
		(layers "F.Cu" "B.Cu")
		(net "GND")
	)
	(via
		(at 135.783828 -0.763016)
		(size 0.508)
		(drill 0.254)
		(layers "F.Cu" "B.Cu")
		(net "GND")
	)
	(via
		(at 39.263828 -0.763016)
		(size 0.508)
		(drill 0.254)
		(layers "F.Cu" "B.Cu")
		(net "GND")
	)
	(via
		(at 287.69818 -9.037828)
		(size 0.508)
		(drill 0.254)
		(layers "F.Cu" "B.Cu")
		(net "GND")
	)
	(via
		(at 272.943828 -0.763016)
		(size 0.508)
		(drill 0.254)
		(layers "F.Cu" "B.Cu")
		(net "GND")
	)
	(via
		(at 290.3093 -21.810218)
		(size 0.508)
		(drill 0.254)
		(layers "F.Cu" "B.Cu")
		(net "GND")
	)
	(via
		(at 46.824646 -54.013354)
		(size 0.508)
		(drill 0.254)
		(layers "F.Cu" "B.Cu")
		(net "GND")
	)
	(via
		(at 70.240906 -126.492)
		(size 0.508)
		(drill 0.254)
		(layers "F.Cu" "B.Cu")
		(net "GND")
	)
	(via
		(at 213.614 -66.17335)
		(size 0.508)
		(drill 0.254)
		(layers "F.Cu" "B.Cu")
		(net "GND")
	)
	(via
		(at 217.063828 -0.763016)
		(size 0.508)
		(drill 0.254)
		(layers "F.Cu" "B.Cu")
		(net "GND")
	)
	(via
		(at 299.593 -26.797)
		(size 0.508)
		(drill 0.254)
		(layers "F.Cu" "B.Cu")
		(net "GND")
	)
	(via
		(at 271.8816 -31.2928)
		(size 0.508)
		(drill 0.254)
		(layers "F.Cu" "B.Cu")
		(net "GND")
	)
	(via
		(at 102.743 -49.784)
		(size 0.508)
		(drill 0.254)
		(layers "F.Cu" "B.Cu")
		(net "GND")
	)
	(via
		(at 235.458 -91.71305)
		(size 0.508)
		(drill 0.254)
		(layers "F.Cu" "B.Cu")
		(net "GND")
	)
	(via
		(at 50.48504 -61.4934)
		(size 0.508)
		(drill 0.254)
		(layers "F.Cu" "B.Cu")
		(net "GND")
	)
	(via
		(at 299.928534 -31.407608)
		(size 0.508)
		(drill 0.254)
		(layers "F.Cu" "B.Cu")
		(net "GND")
	)
	(via
		(at 288.33318 -9.037828)
		(size 0.508)
		(drill 0.254)
		(layers "F.Cu" "B.Cu")
		(net "GND")
	)
	(via
		(at 173.86935 -9.271)
		(size 0.508)
		(drill 0.254)
		(layers "F.Cu" "B.Cu")
		(net "GND")
	)
	(via
		(at 98.048826 -131.572)
		(size 0.508)
		(drill 0.254)
		(layers "F.Cu" "B.Cu")
		(net "GND")
	)
	(via
		(at 101.219 -62.738)
		(size 0.508)
		(drill 0.254)
		(layers "F.Cu" "B.Cu")
		(net "GND")
	)
	(via
		(at 108.204 -49.784)
		(size 0.508)
		(drill 0.254)
		(layers "F.Cu" "B.Cu")
		(net "GND")
	)
	(via
		(at 138.049 -126.492)
		(size 0.508)
		(drill 0.254)
		(layers "F.Cu" "B.Cu")
		(net "GND")
	)
	(via
		(at 278.1554 -25.273)
		(size 0.508)
		(drill 0.254)
		(layers "F.Cu" "B.Cu")
		(net "GND")
	)
	(via
		(at 102.743 -50.419)
		(size 0.508)
		(drill 0.254)
		(layers "F.Cu" "B.Cu")
		(net "GND")
	)
	(via
		(at 202.654916 -65.922906)
		(size 0.508)
		(drill 0.254)
		(layers "F.Cu" "B.Cu")
		(net "GND")
	)
	(via
		(at 276.972522 -106.005122)
		(size 0.508)
		(drill 0.254)
		(layers "F.Cu" "B.Cu")
		(net "GND")
	)
	(via
		(at 180.213 -62.738)
		(size 0.508)
		(drill 0.254)
		(layers "F.Cu" "B.Cu")
		(net "GND")
	)
	(via
		(at 206.74965 -90.678)
		(size 0.508)
		(drill 0.254)
		(layers "F.Cu" "B.Cu")
		(net "GND")
	)
	(via
		(at 138.049 -131.572)
		(size 0.508)
		(drill 0.254)
		(layers "F.Cu" "B.Cu")
		(net "GND")
	)
	(via
		(at 289.941 -30.607)
		(size 0.508)
		(drill 0.254)
		(layers "F.Cu" "B.Cu")
		(net "GND")
	)
	(via
		(at 205.359 -69.32295)
		(size 0.508)
		(drill 0.254)
		(layers "F.Cu" "B.Cu")
		(net "GND")
	)
	(via
		(at 224.282 -91.059)
		(size 0.508)
		(drill 0.254)
		(layers "F.Cu" "B.Cu")
		(net "GND")
	)
	(via
		(at 18.943828 -0.763016)
		(size 0.508)
		(drill 0.254)
		(layers "F.Cu" "B.Cu")
		(net "GND")
	)
	(via
		(at 172.850302 -77.71765)
		(size 0.508)
		(drill 0.254)
		(layers "F.Cu" "B.Cu")
		(net "GND")
	)
	(via
		(at 125.623828 -0.763016)
		(size 0.508)
		(drill 0.254)
		(layers "F.Cu" "B.Cu")
		(net "GND")
	)
	(via
		(at 252.623828 -0.763016)
		(size 0.508)
		(drill 0.254)
		(layers "F.Cu" "B.Cu")
		(net "GND")
	)
	(via
		(at 286.42818 -9.037828)
		(size 0.508)
		(drill 0.254)
		(layers "F.Cu" "B.Cu")
		(net "GND")
	)
	(via
		(at 289.0393 -21.810218)
		(size 0.508)
		(drill 0.254)
		(layers "F.Cu" "B.Cu")
		(net "GND")
	)
	(via
		(at 178.811174 -131.572)
		(size 0.508)
		(drill 0.254)
		(layers "F.Cu" "B.Cu")
		(net "GND")
	)
	(via
		(at 272.5928 -32.004)
		(size 0.508)
		(drill 0.254)
		(layers "F.Cu" "B.Cu")
		(net "GND")
	)
	(via
		(at 318.663828 -0.763016)
		(size 0.508)
		(drill 0.254)
		(layers "F.Cu" "B.Cu")
		(net "GND")
	)
	(via
		(at 327.236074 -68.824348)
		(size 0.508)
		(drill 0.254)
		(layers "F.Cu" "B.Cu")
		(net "GND")
	)
	(via
		(at 301.833534 -30.645608)
		(size 0.508)
		(drill 0.254)
		(layers "F.Cu" "B.Cu")
		(net "GND")
	)
	(via
		(at 75.438 -52.324)
		(size 0.508)
		(drill 0.254)
		(layers "F.Cu" "B.Cu")
		(net "GND")
	)
	(via
		(at 232.73004 -85.617558)
		(size 0.508)
		(drill 0.254)
		(layers "F.Cu" "B.Cu")
		(net "GND")
	)
	(via
		(at 185.9534 -84.4296)
		(size 0.508)
		(drill 0.254)
		(layers "F.Cu" "B.Cu")
		(net "GND")
	)
	(via
		(at 209.789014 -86.24824)
		(size 0.508)
		(drill 0.254)
		(layers "F.Cu" "B.Cu")
		(net "GND")
	)
	(via
		(at 287.7693 -21.048218)
		(size 0.508)
		(drill 0.254)
		(layers "F.Cu" "B.Cu")
		(net "GND")
	)
	(via
		(at 327.236074 -104.384348)
		(size 0.508)
		(drill 0.254)
		(layers "F.Cu" "B.Cu")
		(net "GND")
	)
	(via
		(at 209.804 -66.17335)
		(size 0.508)
		(drill 0.254)
		(layers "F.Cu" "B.Cu")
		(net "GND")
	)
	(via
		(at 97.52965 -77.47)
		(size 0.508)
		(drill 0.254)
		(layers "F.Cu" "B.Cu")
		(net "GND")
	)
	(via
		(at 61.595 -62.865)
		(size 0.508)
		(drill 0.254)
		(layers "F.Cu" "B.Cu")
		(net "GND")
	)
	(via
		(at 284.649926 -138.938)
		(size 0.508)
		(drill 0.254)
		(layers "F.Cu" "B.Cu")
		(net "GND")
	)
	(via
		(at 24.023828 -0.763016)
		(size 0.508)
		(drill 0.254)
		(layers "F.Cu" "B.Cu")
		(net "GND")
	)
	(via
		(at 186.30646 -51.562)
		(size 0.508)
		(drill 0.254)
		(layers "F.Cu" "B.Cu")
		(net "GND")
	)
	(via
		(at 177.8 -77.597)
		(size 0.508)
		(drill 0.254)
		(layers "F.Cu" "B.Cu")
		(net "GND")
	)
	(via
		(at 193.43624 -11.938)
		(size 0.508)
		(drill 0.254)
		(layers "F.Cu" "B.Cu")
		(net "GND")
	)
	(via
		(at 286.392874 -4.604004)
		(size 0.508)
		(drill 0.254)
		(layers "F.Cu" "B.Cu")
		(net "GND")
	)
	(via
		(at 196.743828 -0.763016)
		(size 0.508)
		(drill 0.254)
		(layers "F.Cu" "B.Cu")
		(net "GND")
	)
	(via
		(at 145.943828 -0.763016)
		(size 0.508)
		(drill 0.254)
		(layers "F.Cu" "B.Cu")
		(net "GND")
	)
	(via
		(at 80.899 -49.784)
		(size 0.508)
		(drill 0.254)
		(layers "F.Cu" "B.Cu")
		(net "GND")
	)
	(via
		(at 95.37065 -77.47)
		(size 0.508)
		(drill 0.254)
		(layers "F.Cu" "B.Cu")
		(net "GND")
	)
	(via
		(at 0.76327 -41.970452)
		(size 0.508)
		(drill 0.254)
		(layers "F.Cu" "B.Cu")
		(net "GND")
	)
	(via
		(at 10.286492 -146.237706)
		(size 0.508)
		(drill 0.254)
		(layers "F.Cu" "B.Cu")
		(net "GND")
	)
	(via
		(at 178.049174 -126.492)
		(size 0.508)
		(drill 0.254)
		(layers "F.Cu" "B.Cu")
		(net "GND")
	)
	(via
		(at 206.74965 -91.948)
		(size 0.508)
		(drill 0.254)
		(layers "F.Cu" "B.Cu")
		(net "GND")
	)
	(via
		(at 284.649926 -139.7)
		(size 0.508)
		(drill 0.254)
		(layers "F.Cu" "B.Cu")
		(net "GND")
	)
	(via
		(at 62.484 -59.817)
		(size 0.508)
		(drill 0.254)
		(layers "F.Cu" "B.Cu")
		(net "GND")
	)
	(via
		(at 327.236074 -7.864348)
		(size 0.508)
		(drill 0.254)
		(layers "F.Cu" "B.Cu")
		(net "GND")
	)
	(via
		(at 0.76327 -5.031232)
		(size 0.508)
		(drill 0.254)
		(layers "F.Cu" "B.Cu")
		(net "GND")
	)
	(via
		(at 50.48504 -62.2554)
		(size 0.508)
		(drill 0.254)
		(layers "F.Cu" "B.Cu")
		(net "GND")
	)
	(via
		(at 190.241174 -131.572)
		(size 0.508)
		(drill 0.254)
		(layers "F.Cu" "B.Cu")
		(net "GND")
	)
	(via
		(at 287.69818 -9.799828)
		(size 0.508)
		(drill 0.254)
		(layers "F.Cu" "B.Cu")
		(net "GND")
	)
	(via
		(at 1.92913 -32.606742)
		(size 0.508)
		(drill 0.254)
		(layers "F.Cu" "B.Cu")
		(net "GND")
	)
	(via
		(at 126.619 -131.572)
		(size 0.508)
		(drill 0.254)
		(layers "F.Cu" "B.Cu")
		(net "GND")
	)
	(via
		(at 176.8094 -14.4018)
		(size 0.508)
		(drill 0.254)
		(layers "F.Cu" "B.Cu")
		(net "GND")
	)
	(via
		(at 227.203 -72.00265)
		(size 0.508)
		(drill 0.254)
		(layers "F.Cu" "B.Cu")
		(net "GND")
	)
	(via
		(at 282.308808 -139.7)
		(size 0.508)
		(drill 0.254)
		(layers "F.Cu" "B.Cu")
		(net "GND")
	)
	(via
		(at 270.51 -39.73195)
		(size 0.508)
		(drill 0.254)
		(layers "F.Cu" "B.Cu")
		(net "GND")
	)
	(via
		(at 281.203654 -14.411198)
		(size 0.508)
		(drill 0.254)
		(layers "F.Cu" "B.Cu")
		(net "GND")
	)
	(via
		(at 218.313 -92.964)
		(size 0.508)
		(drill 0.254)
		(layers "F.Cu" "B.Cu")
		(net "GND")
	)
	(via
		(at 215.77046 -50.419)
		(size 0.508)
		(drill 0.254)
		(layers "F.Cu" "B.Cu")
		(net "GND")
	)
	(via
		(at 285.411926 -140.462)
		(size 0.508)
		(drill 0.254)
		(layers "F.Cu" "B.Cu")
		(net "GND")
	)
	(via
		(at 278.663654 -14.411198)
		(size 0.508)
		(drill 0.254)
		(layers "F.Cu" "B.Cu")
		(net "GND")
	)
	(via
		(at 49.72304 -61.4934)
		(size 0.508)
		(drill 0.254)
		(layers "F.Cu" "B.Cu")
		(net "GND")
	)
	(via
		(at 234.95 -92.964)
		(size 0.508)
		(drill 0.254)
		(layers "F.Cu" "B.Cu")
		(net "GND")
	)
	(via
		(at 62.484 -60.579)
		(size 0.508)
		(drill 0.254)
		(layers "F.Cu" "B.Cu")
		(net "GND")
	)
	(via
		(at 108.204 -51.689)
		(size 0.508)
		(drill 0.254)
		(layers "F.Cu" "B.Cu")
		(net "GND")
	)
	(via
		(at 150.241 -126.492)
		(size 0.508)
		(drill 0.254)
		(layers "F.Cu" "B.Cu")
		(net "GND")
	)
	(via
		(at 226.949 -92.964)
		(size 0.508)
		(drill 0.254)
		(layers "F.Cu" "B.Cu")
		(net "GND")
	)
	(via
		(at 102.743 -51.689)
		(size 0.508)
		(drill 0.254)
		(layers "F.Cu" "B.Cu")
		(net "GND")
	)
	(via
		(at 285.411926 -136.652)
		(size 0.508)
		(drill 0.254)
		(layers "F.Cu" "B.Cu")
		(net "GND")
	)
	(via
		(at 211.074 -66.167)
		(size 0.508)
		(drill 0.254)
		(layers "F.Cu" "B.Cu")
		(net "GND")
	)
	(via
		(at 327.236074 -73.904348)
		(size 0.508)
		(drill 0.254)
		(layers "F.Cu" "B.Cu")
		(net "GND")
	)
	(via
		(at 201.823828 -0.763016)
		(size 0.508)
		(drill 0.254)
		(layers "F.Cu" "B.Cu")
		(net "GND")
	)
	(via
		(at 175.2346 -14.3764)
		(size 0.508)
		(drill 0.254)
		(layers "F.Cu" "B.Cu")
		(net "GND")
	)
	(via
		(at 175.502824 -77.597)
		(size 0.508)
		(drill 0.254)
		(layers "F.Cu" "B.Cu")
		(net "GND")
	)
	(via
		(at 232.283 -74.168)
		(size 0.508)
		(drill 0.254)
		(layers "F.Cu" "B.Cu")
		(net "GND")
	)
	(via
		(at 276.987 -95.631)
		(size 0.508)
		(drill 0.254)
		(layers "F.Cu" "B.Cu")
		(net "GND")
	)
	(via
		(at 289.941 -34.18205)
		(size 0.508)
		(drill 0.254)
		(layers "F.Cu" "B.Cu")
		(net "GND")
	)
	(via
		(at 48.96104 -61.4934)
		(size 0.508)
		(drill 0.254)
		(layers "F.Cu" "B.Cu")
		(net "GND")
	)
	(via
		(at 0.76327 -77.530452)
		(size 0.508)
		(drill 0.254)
		(layers "F.Cu" "B.Cu")
		(net "GND")
	)
	(via
		(at 278.628094 -5.366004)
		(size 0.508)
		(drill 0.254)
		(layers "F.Cu" "B.Cu")
		(net "GND")
	)
	(via
		(at 164.465 -50.292)
		(size 0.508)
		(drill 0.254)
		(layers "F.Cu" "B.Cu")
		(net "GND")
	)
	(via
		(at 48.19904 -62.2554)
		(size 0.508)
		(drill 0.254)
		(layers "F.Cu" "B.Cu")
		(net "GND")
	)
	(via
		(at 85.856826 -126.492)
		(size 0.508)
		(drill 0.254)
		(layers "F.Cu" "B.Cu")
		(net "GND")
	)
	(via
		(at 192.06464 -14.097)
		(size 0.508)
		(drill 0.254)
		(layers "F.Cu" "B.Cu")
		(net "GND")
	)
	(via
		(at 91.821 -51.689)
		(size 0.508)
		(drill 0.254)
		(layers "F.Cu" "B.Cu")
		(net "GND")
	)
	(via
		(at 192.72504 -9.779)
		(size 0.508)
		(drill 0.254)
		(layers "F.Cu" "B.Cu")
		(net "GND")
	)
	(via
		(at 282.702 -25.71496)
		(size 0.508)
		(drill 0.254)
		(layers "F.Cu" "B.Cu")
		(net "GND")
	)
	(via
		(at 164.465 -49.657)
		(size 0.508)
		(drill 0.254)
		(layers "F.Cu" "B.Cu")
		(net "GND")
	)
	(via
		(at 13.863828 -0.763016)
		(size 0.508)
		(drill 0.254)
		(layers "F.Cu" "B.Cu")
		(net "GND")
	)
	(via
		(at 283.070808 -140.462)
		(size 0.508)
		(drill 0.254)
		(layers "F.Cu" "B.Cu")
		(net "GND")
	)
	(via
		(at 98.048826 -126.492)
		(size 0.508)
		(drill 0.254)
		(layers "F.Cu" "B.Cu")
		(net "GND")
	)
	(via
		(at 175.6156 -13.5382)
		(size 0.508)
		(drill 0.254)
		(layers "F.Cu" "B.Cu")
		(net "GND")
	)
	(via
		(at 288.4043 -21.810218)
		(size 0.508)
		(drill 0.254)
		(layers "F.Cu" "B.Cu")
		(net "GND")
	)
	(via
		(at 217.424 -66.17335)
		(size 0.508)
		(drill 0.254)
		(layers "F.Cu" "B.Cu")
		(net "GND")
	)
	(via
		(at 0.76327 -113.090452)
		(size 0.508)
		(drill 0.254)
		(layers "F.Cu" "B.Cu")
		(net "GND")
	)
	(segment
		(start 293.00805 -38.58895)
		(end 293.00805 -39.116)
		(width 0.381)
		(layer "B.Cu")
		(net "GND")
	)
	(segment
		(start 239.02289 -87.496396)
		(end 239.02289 -86.404196)
		(width 0.3556)
		(layer "B.Cu")
		(net "GND")
	)
	(segment
		(start 293.877238 -32.9438)
		(end 292.718998 -34.10204)
		(width 0.381)
		(layer "B.Cu")
		(net "GND")
	)
	(segment
		(start 174.893224 -77.597)
		(end 175.502824 -77.597)
		(width 0.508)
		(layer "B.Cu")
		(net "GND")
	)
	(segment
		(start 148.319998 -112.84204)
		(end 149.225 -112.84204)
		(width 0.508)
		(layer "B.Cu")
		(net "GND")
	)
	(segment
		(start 180.850286 -77.10805)
		(end 180.850286 -77.71765)
		(width 0.508)
		(layer "B.Cu")
		(net "GND")
	)
	(segment
		(start 226.914202 -75.87996)
		(end 226.076002 -75.87996)
		(width 0.508)
		(layer "B.Cu")
		(net "GND")
	)
	(segment
		(start 172.850302 -77.10805)
		(end 172.850302 -77.71765)
		(width 0.508)
		(layer "B.Cu")
		(net "GND")
	)
	(segment
		(start 224.282 -74.65695)
		(end 223.52 -74.65695)
		(width 0.508)
		(layer "B.Cu")
		(net "GND")
	)
	(segment
		(start 176.850294 -113.64595)
		(end 176.850294 -113.036096)
		(width 0.508)
		(layer "B.Cu")
		(net "GND")
	)
	(segment
		(start 237.031784 -78.71714)
		(end 237.031784 -79.32674)
		(width 0.508)
		(layer "B.Cu")
		(net "GND")
	)
	(segment
		(start 238.76 -74.542904)
		(end 238.76 -73.93305)
		(width 0.508)
		(layer "B.Cu")
		(net "GND")
	)
	(segment
		(start 231.775 -83.30565)
		(end 231.775 -82.69605)
		(width 0.508)
		(layer "B.Cu")
		(net "GND")
	)
	(segment
		(start 224.282 -91.059)
		(end 224.282 -90.44305)
		(width 0.508)
		(layer "B.Cu")
		(net "GND")
	)
	(segment
		(start 215.265 -91.45905)
		(end 216.027 -91.45905)
		(width 0.4572)
		(layer "B.Cu")
		(net "GND")
	)
	(segment
		(start 271.145 -39.73195)
		(end 270.51 -39.73195)
		(width 0.381)
		(layer "B.Cu")
		(net "GND")
	)
	(segment
		(start 54.88305 -77.47)
		(end 55.499 -77.47)
		(width 0.508)
		(layer "B.Cu")
		(net "GND")
	)
	(segment
		(start 57.04205 -77.47)
		(end 57.65165 -77.47)
		(width 0.508)
		(layer "B.Cu")
		(net "GND")
	)
	(segment
		(start 198.81088 -85.466936)
		(end 199.771 -85.466936)
		(width 0.4064)
		(layer "B.Cu")
		(net "GND")
	)
	(segment
		(start 276.987 -94.662244)
		(end 277.709122 -93.940122)
		(width 0.381)
		(layer "B.Cu")
		(net "GND")
	)
	(segment
		(start 177.179224 -77.597)
		(end 177.8 -77.597)
		(width 0.508)
		(layer "B.Cu")
		(net "GND")
	)
	(segment
		(start 223.012 -91.05265)
		(end 223.012 -90.44305)
		(width 0.508)
		(layer "B.Cu")
		(net "GND")
	)
	(segment
		(start 219.71 -79.5528)
		(end 219.71 -80.7974)
		(width 0.508)
		(layer "B.Cu")
		(net "GND")
	)
	(segment
		(start 188.595 -91.821)
		(end 189.21095 -91.821)
		(width 0.508)
		(layer "B.Cu")
		(net "GND")
	)
	(segment
		(start 276.987 -95.631)
		(end 276.987 -94.662244)
		(width 0.381)
		(layer "B.Cu")
		(net "GND")
	)
	(segment
		(start 108.319824 -112.84204)
		(end 109.224826 -112.84204)
		(width 0.508)
		(layer "B.Cu")
		(net "GND")
	)
	(segment
		(start 212.24494 -90.44305)
		(end 211.73694 -90.95105)
		(width 0.508)
		(layer "B.Cu")
		(net "GND")
	)
	(segment
		(start 228.870002 -89.49436)
		(end 228.870002 -88.70696)
		(width 0.508)
		(layer "B.Cu")
		(net "GND")
	)
	(segment
		(start 229.87 -72.00265)
		(end 229.87 -71.39305)
		(width 0.508)
		(layer "B.Cu")
		(net "GND")
	)
	(segment
		(start 52.850034 -77.10805)
		(end 52.850034 -77.71765)
		(width 0.508)
		(layer "B.Cu")
		(net "GND")
	)
	(segment
		(start 210.185 -83.566)
		(end 210.185 -82.95005)
		(width 0.508)
		(layer "B.Cu")
		(net "GND")
	)
	(segment
		(start 216.027 -91.45905)
		(end 216.662 -91.45905)
		(width 0.508)
		(layer "B.Cu")
		(net "GND")
	)
	(segment
		(start 137.17905 -77.597)
		(end 137.78865 -77.597)
		(width 0.508)
		(layer "B.Cu")
		(net "GND")
	)
	(segment
		(start 134.89305 -77.597)
		(end 135.50265 -77.597)
		(width 0.508)
		(layer "B.Cu")
		(net "GND")
	)
	(segment
		(start 215.41105 -77.851)
		(end 215.41105 -78.994)
		(width 0.3556)
		(layer "B.Cu")
		(net "GND")
	)
	(segment
		(start 213.614 -66.17335)
		(end 213.614 -66.78295)
		(width 0.508)
		(layer "B.Cu")
		(net "GND")
	)
	(segment
		(start 282.939998 -38.29304)
		(end 282.939998 -37.575998)
		(width 0.381)
		(layer "B.Cu")
		(net "GND")
	)
	(segment
		(start 206.74965 -91.948)
		(end 206.14005 -91.948)
		(width 0.508)
		(layer "B.Cu")
		(net "GND")
	)
	(segment
		(start 227.203 -72.00265)
		(end 227.203 -71.39305)
		(width 0.508)
		(layer "B.Cu")
		(net "GND")
	)
	(segment
		(start 214.884 -66.17335)
		(end 214.884 -66.78295)
		(width 0.508)
		(layer "B.Cu")
		(net "GND")
	)
	(segment
		(start 96.92005 -77.47)
		(end 97.52965 -77.47)
		(width 0.508)
		(layer "B.Cu")
		(net "GND")
	)
	(segment
		(start 109.732826 -115.42395)
		(end 109.732826 -114.81435)
		(width 0.508)
		(layer "B.Cu")
		(net "GND")
	)
	(segment
		(start 56.850026 -113.64595)
		(end 56.850026 -113.03635)
		(width 0.508)
		(layer "B.Cu")
		(net "GND")
	)
	(segment
		(start 139.573 -113.64595)
		(end 139.573 -113.036096)
		(width 0.381)
		(layer "B.Cu")
		(net "GND")
	)
	(segment
		(start 212.344 -66.167)
		(end 212.344 -66.78295)
		(width 0.508)
		(layer "B.Cu")
		(net "GND")
	)
	(segment
		(start 232.73004 -85.617558)
		(end 232.73004 -86.658958)
		(width 0.508)
		(layer "B.Cu")
		(net "GND")
	)
	(segment
		(start 280.543 -35.54095)
		(end 279.41905 -35.54095)
		(width 0.381)
		(layer "B.Cu")
		(net "GND")
	)
	(segment
		(start 222.25 -74.65695)
		(end 220.98 -74.65695)
		(width 0.508)
		(layer "B.Cu")
		(net "GND")
	)
	(segment
		(start 240.538 -74.542904)
		(end 240.538 -73.93305)
		(width 0.508)
		(layer "B.Cu")
		(net "GND")
	)
	(segment
		(start 208.153 -83.566)
		(end 208.153 -82.95005)
		(width 0.508)
		(layer "B.Cu")
		(net "GND")
	)
	(segment
		(start 232.283 -74.168)
		(end 232.283 -74.78395)
		(width 0.508)
		(layer "B.Cu")
		(net "GND")
	)
	(segment
		(start 235.458 -91.71305)
		(end 234.823 -91.71305)
		(width 0.508)
		(layer "B.Cu")
		(net "GND")
	)
	(segment
		(start 211.074 -66.167)
		(end 211.074 -66.78295)
		(width 0.508)
		(layer "B.Cu")
		(net "GND")
	)
	(segment
		(start 222.885 -72.00265)
		(end 222.885 -71.39305)
		(width 0.508)
		(layer "B.Cu")
		(net "GND")
	)
	(segment
		(start 94.76105 -77.47)
		(end 95.37065 -77.47)
		(width 0.508)
		(layer "B.Cu")
		(net "GND")
	)
	(segment
		(start 96.849946 -113.64595)
		(end 96.849946 -113.03635)
		(width 0.508)
		(layer "B.Cu")
		(net "GND")
	)
	(segment
		(start 209.789014 -86.24824)
		(end 209.789014 -86.93404)
		(width 0.508)
		(layer "B.Cu")
		(net "GND")
	)
	(segment
		(start 289.941 -29.86405)
		(end 289.941 -30.607)
		(width 0.381)
		(layer "B.Cu")
		(net "GND")
	)
	(segment
		(start 262.74395 -35.433)
		(end 262.763 -35.45205)
		(width 0.381)
		(layer "B.Cu")
		(net "GND")
	)
	(segment
		(start 44.967906 -56.454802)
		(end 43.868848 -56.454802)
		(width 0.381)
		(layer "B.Cu")
		(net "GND")
	)
	(segment
		(start 271.911064 -28.350464)
		(end 271.911064 -28.932886)
		(width 0.381)
		(layer "B.Cu")
		(net "GND")
	)
	(segment
		(start 293.00805 -39.387018)
		(end 291.27704 -41.118028)
		(width 0.381)
		(layer "B.Cu")
		(net "GND")
	)
	(segment
		(start 212.74405 -81.534)
		(end 212.74405 -82.169)
		(width 0.508)
		(layer "B.Cu")
		(net "GND")
	)
	(segment
		(start 262.763 -35.45205)
		(end 262.763 -36.068)
		(width 0.381)
		(layer "B.Cu")
		(net "GND")
	)
	(segment
		(start 271.5006 -27.94)
		(end 271.911064 -28.350464)
		(width 0.381)
		(layer "B.Cu")
		(net "GND")
	)
	(segment
		(start 214.56904 -85.363558)
		(end 214.56904 -86.404958)
		(width 0.508)
		(layer "B.Cu")
		(net "GND")
	)
	(segment
		(start 45.287946 -56.774842)
		(end 44.967906 -56.454802)
		(width 0.381)
		(layer "B.Cu")
		(net "GND")
	)
	(segment
		(start 212.24494 -90.31986)
		(end 212.24494 -90.44305)
		(width 0.508)
		(layer "B.Cu")
		(net "GND")
	)
	(segment
		(start 205.359 -69.32295)
		(end 205.994 -69.32295)
		(width 0.508)
		(layer "B.Cu")
		(net "GND")
	)
	(segment
		(start 282.939998 -37.575998)
		(end 282.829 -37.465)
		(width 0.381)
		(layer "B.Cu")
		(net "GND")
	)
	(segment
		(start 136.85012 -113.64595)
		(end 136.85012 -113.03635)
		(width 0.508)
		(layer "B.Cu")
		(net "GND")
	)
	(segment
		(start 275.40204 -37.862002)
		(end 275.40204 -38.7604)
		(width 0.381)
		(layer "B.Cu")
		(net "GND")
	)
	(segment
		(start 132.850128 -77.10805)
		(end 132.850128 -77.71765)
		(width 0.508)
		(layer "B.Cu")
		(net "GND")
	)
	(segment
		(start 236.982 -74.542904)
		(end 236.982 -73.93305)
		(width 0.508)
		(layer "B.Cu")
		(net "GND")
	)
	(segment
		(start 100.849938 -77.10805)
		(end 100.849938 -77.71765)
		(width 0.508)
		(layer "B.Cu")
		(net "GND")
	)
	(segment
		(start 179.465224 -77.597)
		(end 180.074824 -77.597)
		(width 0.508)
		(layer "B.Cu")
		(net "GND")
	)
	(segment
		(start 206.74965 -90.678)
		(end 206.14005 -90.678)
		(width 0.508)
		(layer "B.Cu")
		(net "GND")
	)
	(segment
		(start 92.849954 -77.10805)
		(end 92.849954 -77.71765)
		(width 0.508)
		(layer "B.Cu")
		(net "GND")
	)
	(segment
		(start 60.850018 -77.10805)
		(end 60.850018 -77.71765)
		(width 0.508)
		(layer "B.Cu")
		(net "GND")
	)
	(segment
		(start 99.20605 -77.47)
		(end 99.822 -77.47)
		(width 0.508)
		(layer "B.Cu")
		(net "GND")
	)
	(segment
		(start 140.850112 -77.10805)
		(end 140.850112 -77.71765)
		(width 0.508)
		(layer "B.Cu")
		(net "GND")
	)
	(segment
		(start 277.709122 -106.005122)
		(end 276.972522 -106.005122)
		(width 0.381)
		(layer "B.Cu")
		(net "GND")
	)
	(segment
		(start 223.52 -74.65695)
		(end 222.25 -74.65695)
		(width 0.508)
		(layer "B.Cu")
		(net "GND")
	)
	(segment
		(start 149.733 -114.02695)
		(end 149.733 -113.411)
		(width 0.381)
		(layer "B.Cu")
		(net "GND")
	)
	(segment
		(start 216.154 -66.17335)
		(end 216.154 -66.78295)
		(width 0.508)
		(layer "B.Cu")
		(net "GND")
	)
	(segment
		(start 211.73694 -90.95105)
		(end 211.455 -90.95105)
		(width 0.508)
		(layer "B.Cu")
		(net "GND")
	)
	(segment
		(start 230.632 -83.30565)
		(end 230.632 -82.69605)
		(width 0.508)
		(layer "B.Cu")
		(net "GND")
	)
	(segment
		(start 293.116 -38.481)
		(end 293.00805 -38.58895)
		(width 0.381)
		(layer "B.Cu")
		(net "GND")
	)
	(segment
		(start 209.804 -66.17335)
		(end 209.804 -66.78295)
		(width 0.508)
		(layer "B.Cu")
		(net "GND")
	)
	(segment
		(start 291.27704 -41.118028)
		(end 291.27704 -42.73423)
		(width 0.381)
		(layer "B.Cu")
		(net "GND")
	)
	(segment
		(start 139.46505 -77.597)
		(end 140.07465 -77.597)
		(width 0.508)
		(layer "B.Cu")
		(net "GND")
	)
	(segment
		(start 224.536 -72.00265)
		(end 224.536 -71.39305)
		(width 0.508)
		(layer "B.Cu")
		(net "GND")
	)
	(segment
		(start 274.745958 -27.432)
		(end 275.52396 -27.432)
		(width 0.381)
		(layer "B.Cu")
		(net "GND")
	)
	(segment
		(start 271.911064 -28.932886)
		(end 271.88795 -28.956)
		(width 0.381)
		(layer "B.Cu")
		(net "GND")
	)
	(segment
		(start 59.32805 -77.47)
		(end 59.93765 -77.47)
		(width 0.508)
		(layer "B.Cu")
		(net "GND")
	)
	(segment
		(start 230.109014 -77.851)
		(end 230.109014 -78.55204)
		(width 0.508)
		(layer "B.Cu")
		(net "GND")
	)
	(segment
		(start 294.4622 -32.9438)
		(end 293.877238 -32.9438)
		(width 0.381)
		(layer "B.Cu")
		(net "GND")
	)
	(segment
		(start 274.63496 -27.542998)
		(end 274.745958 -27.432)
		(width 0.381)
		(layer "B.Cu")
		(net "GND")
	)
	(segment
		(start 232.537 -72.00265)
		(end 232.537 -71.39305)
		(width 0.508)
		(layer "B.Cu")
		(net "GND")
	)
	(segment
		(start 217.424 -66.17335)
		(end 217.424 -66.78295)
		(width 0.508)
		(layer "B.Cu")
		(net "GND")
	)
	(segment
		(start 293.00805 -39.116)
		(end 293.00805 -39.387018)
		(width 0.381)
		(layer "B.Cu")
		(net "GND")
	)
	(segment
		(start 235.458 -91.71305)
		(end 235.458 -92.418916)
		(width 0.508)
		(layer "In1.Cu")
		(net "GND")
	)
	(segment
		(start 12.39012 -64.159892)
		(end 13.177774 -64.947546)
		(width 0.508)
		(layer "In2.Cu")
		(net "GND")
	)
	(segment
		(start 89.229946 -70.409816)
		(end 90.511376 -69.128386)
		(width 0.889)
		(layer "In2.Cu")
		(net "GND")
	)
	(segment
		(start 47.948596 -69.128386)
		(end 49.230026 -70.409816)
		(width 0.889)
		(layer "In2.Cu")
		(net "GND")
	)
	(segment
		(start 125.42012 -70.409816)
		(end 126.70155 -69.128386)
		(width 0.889)
		(layer "In2.Cu")
		(net "GND")
	)
	(segment
		(start 44.138596 -71.691246)
		(end 45.420026 -70.409816)
		(width 0.889)
		(layer "In2.Cu")
		(net "GND")
	)
	(segment
		(start 12.39012 -60.779914)
		(end 13.177774 -59.99226)
		(width 0.508)
		(layer "In2.Cu")
		(net "GND")
	)
	(segment
		(start 45.420026 -70.409816)
		(end 46.701456 -71.691246)
		(width 0.889)
		(layer "In2.Cu")
		(net "GND")
	)
	(segment
		(start 11.602466 -63.372238)
		(end 12.39012 -64.159892)
		(width 0.508)
		(layer "In2.Cu")
		(net "GND")
	)
	(segment
		(start 169.230294 -70.409816)
		(end 170.511724 -69.128386)
		(width 0.889)
		(layer "In2.Cu")
		(net "GND")
	)
	(segment
		(start 9.85012 -59.079892)
		(end 10.637774 -59.867546)
		(width 0.508)
		(layer "In2.Cu")
		(net "GND")
	)
	(segment
		(start 129.23012 -70.409816)
		(end 130.51155 -69.128386)
		(width 0.889)
		(layer "In2.Cu")
		(net "GND")
	)
	(segment
		(start 9.062466 -59.867546)
		(end 9.85012 -59.079892)
		(width 0.508)
		(layer "In2.Cu")
		(net "GND")
	)
	(segment
		(start 165.420294 -70.409816)
		(end 166.701724 -69.128386)
		(width 0.889)
		(layer "In2.Cu")
		(net "GND")
	)
	(segment
		(start 169.230294 -70.409816)
		(end 170.511724 -71.691246)
		(width 0.889)
		(layer "In2.Cu")
		(net "GND")
	)
	(segment
		(start 9.85012 -65.859914)
		(end 10.637774 -66.647568)
		(width 0.508)
		(layer "In2.Cu")
		(net "GND")
	)
	(segment
		(start 12.39012 -59.079892)
		(end 13.177774 -59.867546)
		(width 0.508)
		(layer "In2.Cu")
		(net "GND")
	)
	(segment
		(start 49.230026 -70.409816)
		(end 50.511456 -71.691246)
		(width 0.889)
		(layer "In2.Cu")
		(net "GND")
	)
	(segment
		(start 9.85012 -59.079892)
		(end 10.637774 -58.292238)
		(width 0.508)
		(layer "In2.Cu")
		(net "GND")
	)
	(segment
		(start 11.602466 -58.292238)
		(end 12.39012 -59.079892)
		(width 0.508)
		(layer "In2.Cu")
		(net "GND")
	)
	(segment
		(start 89.229946 -70.409816)
		(end 90.511376 -71.691246)
		(width 0.889)
		(layer "In2.Cu")
		(net "GND")
	)
	(segment
		(start 124.13869 -69.128386)
		(end 125.42012 -70.409816)
		(width 0.889)
		(layer "In2.Cu")
		(net "GND")
	)
	(segment
		(start 9.85012 -64.159892)
		(end 10.637774 -63.372238)
		(width 0.508)
		(layer "In2.Cu")
		(net "GND")
	)
	(segment
		(start 11.602466 -65.07226)
		(end 12.39012 -65.859914)
		(width 0.508)
		(layer "In2.Cu")
		(net "GND")
	)
	(segment
		(start 12.39012 -59.079892)
		(end 13.177774 -58.292238)
		(width 0.508)
		(layer "In2.Cu")
		(net "GND")
	)
	(segment
		(start 11.602466 -66.647568)
		(end 12.39012 -65.859914)
		(width 0.508)
		(layer "In2.Cu")
		(net "GND")
	)
	(segment
		(start 9.85012 -65.859914)
		(end 10.637774 -65.07226)
		(width 0.508)
		(layer "In2.Cu")
		(net "GND")
	)
	(segment
		(start 9.062466 -64.947546)
		(end 9.85012 -64.159892)
		(width 0.508)
		(layer "In2.Cu")
		(net "GND")
	)
	(segment
		(start 164.138864 -71.691246)
		(end 165.420294 -70.409816)
		(width 0.889)
		(layer "In2.Cu")
		(net "GND")
	)
	(segment
		(start 9.062466 -58.292238)
		(end 9.85012 -59.079892)
		(width 0.508)
		(layer "In2.Cu")
		(net "GND")
	)
	(segment
		(start 12.39012 -60.779914)
		(end 13.177774 -61.567568)
		(width 0.508)
		(layer "In2.Cu")
		(net "GND")
	)
	(segment
		(start 9.062466 -63.372238)
		(end 9.85012 -64.159892)
		(width 0.508)
		(layer "In2.Cu")
		(net "GND")
	)
	(segment
		(start 9.062466 -59.99226)
		(end 9.85012 -60.779914)
		(width 0.508)
		(layer "In2.Cu")
		(net "GND")
	)
	(segment
		(start 12.39012 -65.859914)
		(end 13.177774 -66.647568)
		(width 0.508)
		(layer "In2.Cu")
		(net "GND")
	)
	(segment
		(start 45.420026 -70.409816)
		(end 46.701456 -69.128386)
		(width 0.889)
		(layer "In2.Cu")
		(net "GND")
	)
	(segment
		(start 124.13869 -71.691246)
		(end 125.42012 -70.409816)
		(width 0.889)
		(layer "In2.Cu")
		(net "GND")
	)
	(segment
		(start 89.229946 -70.409816)
		(end 87.948516 -69.128386)
		(width 0.889)
		(layer "In2.Cu")
		(net "GND")
	)
	(segment
		(start 129.23012 -70.409816)
		(end 130.51155 -71.691246)
		(width 0.889)
		(layer "In2.Cu")
		(net "GND")
	)
	(segment
		(start 9.85012 -64.159892)
		(end 10.637774 -64.947546)
		(width 0.508)
		(layer "In2.Cu")
		(net "GND")
	)
	(segment
		(start 47.948596 -71.691246)
		(end 49.230026 -70.409816)
		(width 0.889)
		(layer "In2.Cu")
		(net "GND")
	)
	(segment
		(start 9.85012 -60.779914)
		(end 10.637774 -61.567568)
		(width 0.508)
		(layer "In2.Cu")
		(net "GND")
	)
	(segment
		(start 87.948516 -71.691246)
		(end 89.229946 -70.409816)
		(width 0.889)
		(layer "In2.Cu")
		(net "GND")
	)
	(segment
		(start 44.138596 -69.128386)
		(end 45.420026 -70.409816)
		(width 0.889)
		(layer "In2.Cu")
		(net "GND")
	)
	(segment
		(start 11.602466 -64.947546)
		(end 12.39012 -64.159892)
		(width 0.508)
		(layer "In2.Cu")
		(net "GND")
	)
	(segment
		(start 12.39012 -64.159892)
		(end 13.177774 -63.372238)
		(width 0.508)
		(layer "In2.Cu")
		(net "GND")
	)
	(segment
		(start 85.419946 -70.409816)
		(end 86.701376 -71.691246)
		(width 0.889)
		(layer "In2.Cu")
		(net "GND")
	)
	(segment
		(start 164.138864 -69.128386)
		(end 165.420294 -70.409816)
		(width 0.889)
		(layer "In2.Cu")
		(net "GND")
	)
	(segment
		(start 127.94869 -71.691246)
		(end 129.23012 -70.409816)
		(width 0.889)
		(layer "In2.Cu")
		(net "GND")
	)
	(segment
		(start 9.062466 -61.567568)
		(end 9.85012 -60.779914)
		(width 0.508)
		(layer "In2.Cu")
		(net "GND")
	)
	(segment
		(start 11.602466 -61.567568)
		(end 12.39012 -60.779914)
		(width 0.508)
		(layer "In2.Cu")
		(net "GND")
	)
	(segment
		(start 85.419946 -70.409816)
		(end 84.138516 -69.128386)
		(width 0.889)
		(layer "In2.Cu")
		(net "GND")
	)
	(segment
		(start 9.062466 -66.647568)
		(end 9.85012 -65.859914)
		(width 0.508)
		(layer "In2.Cu")
		(net "GND")
	)
	(segment
		(start 11.602466 -59.867546)
		(end 12.39012 -59.079892)
		(width 0.508)
		(layer "In2.Cu")
		(net "GND")
	)
	(segment
		(start 9.85012 -60.779914)
		(end 10.637774 -59.99226)
		(width 0.508)
		(layer "In2.Cu")
		(net "GND")
	)
	(segment
		(start 127.94869 -69.128386)
		(end 129.23012 -70.409816)
		(width 0.889)
		(layer "In2.Cu")
		(net "GND")
	)
	(segment
		(start 165.420294 -70.409816)
		(end 166.701724 -71.691246)
		(width 0.889)
		(layer "In2.Cu")
		(net "GND")
	)
	(segment
		(start 11.602466 -59.99226)
		(end 12.39012 -60.779914)
		(width 0.508)
		(layer "In2.Cu")
		(net "GND")
	)
	(segment
		(start 167.948864 -71.691246)
		(end 169.230294 -70.409816)
		(width 0.889)
		(layer "In2.Cu")
		(net "GND")
	)
	(segment
		(start 9.062466 -65.07226)
		(end 9.85012 -65.859914)
		(width 0.508)
		(layer "In2.Cu")
		(net "GND")
	)
	(segment
		(start 85.419946 -70.409816)
		(end 86.701376 -69.128386)
		(width 0.889)
		(layer "In2.Cu")
		(net "GND")
	)
	(segment
		(start 84.138516 -71.691246)
		(end 85.419946 -70.409816)
		(width 0.889)
		(layer "In2.Cu")
		(net "GND")
	)
	(segment
		(start 12.39012 -65.859914)
		(end 13.177774 -65.07226)
		(width 0.508)
		(layer "In2.Cu")
		(net "GND")
	)
	(segment
		(start 167.948864 -69.128386)
		(end 169.230294 -70.409816)
		(width 0.889)
		(layer "In2.Cu")
		(net "GND")
	)
	(segment
		(start 125.42012 -70.409816)
		(end 126.70155 -71.691246)
		(width 0.889)
		(layer "In2.Cu")
		(net "GND")
	)
	(segment
		(start 205.37678 -68.505832)
		(end 205.359 -68.523612)
		(width 0.508)
		(layer "In3.Cu")
		(net "GND")
	)
	(segment
		(start 235.458 -91.71305)
		(end 235.458 -92.383356)
		(width 0.508)
		(layer "In3.Cu")
		(net "GND")
	)
	(segment
		(start 205.359 -68.523612)
		(end 205.359 -69.32295)
		(width 0.508)
		(layer "In3.Cu")
		(net "GND")
	)
	(segment
		(start 216.027 -91.45905)
		(end 216.027 -92.181934)
		(width 0.508)
		(layer "In3.Cu")
		(net "GND")
	)
	(segment
		(start 216.027 -91.45905)
		(end 216.027 -92.017342)
		(width 0.508)
		(layer "In6.Cu")
		(net "GND")
	)
	(segment
		(start 235.458 -91.71305)
		(end 235.458 -92.383356)
		(width 0.508)
		(layer "In6.Cu")
		(net "GND")
	)
	(segment
		(start 205.453234 -68.59397)
		(end 205.359 -68.688204)
		(width 0.508)
		(layer "In6.Cu")
		(net "GND")
	)
	(segment
		(start 205.359 -68.688204)
		(end 205.359 -69.32295)
		(width 0.508)
		(layer "In6.Cu")
		(net "GND")
	)
	(segment
		(start 235.458 -91.71305)
		(end 235.458 -92.548202)
		(width 0.508)
		(layer "In8.Cu")
		(net "GND")
	)
	(segment
		(start 205.447392 -68.582286)
		(end 205.359 -68.670678)
		(width 0.508)
		(layer "In8.Cu")
		(net "GND")
	)
	(segment
		(start 205.359 -68.670678)
		(end 205.359 -69.32295)
		(width 0.508)
		(layer "In8.Cu")
		(net "GND")
	)
	(segment
		(start 216.027 -91.45905)
		(end 216.027 -92.10548)
		(width 0.508)
		(layer "In8.Cu")
		(net "GND")
	)
	(via
		(at 222.25 -88.207342)
		(size 0.762)
		(drill 0.254)
		(layers "F.Cu" "B.Cu")
		(net "FRU_WP_N")
	)
	(segment
		(start 222.25 -86.0806)
		(end 222.25 -88.207342)
		(width 0.17272)
		(layer "B.Cu")
		(net "FRU_WP_N")
	)
	(segment
		(start 221.996 -89.64295)
		(end 223.012 -89.64295)
		(width 0.17272)
		(layer "B.Cu")
		(net "FRU_WP_N")
	)
	(segment
		(start 222.25 -88.207342)
		(end 222.25 -88.94699)
		(width 0.17272)
		(layer "B.Cu")
		(net "FRU_WP_N")
	)
	(segment
		(start 221.996 -89.20099)
		(end 221.996 -89.64295)
		(width 0.17272)
		(layer "B.Cu")
		(net "FRU_WP_N")
	)
	(segment
		(start 222.25 -88.94699)
		(end 221.996 -89.20099)
		(width 0.17272)
		(layer "B.Cu")
		(net "FRU_WP_N")
	)
	(via
		(at 220.98 -79.448152)
		(size 0.762)
		(drill 0.254)
		(layers "F.Cu" "B.Cu")
		(net "FRU_ADDR2")
	)
	(segment
		(start 220.903546 -78.75905)
		(end 220.98 -78.75905)
		(width 0.17272)
		(layer "B.Cu")
		(net "FRU_ADDR2")
	)
	(segment
		(start 220.98 -75.45705)
		(end 220.36024 -76.07681)
		(width 0.17272)
		(layer "B.Cu")
		(net "FRU_ADDR2")
	)
	(segment
		(start 220.36024 -76.07681)
		(end 220.36024 -78.215744)
		(width 0.17272)
		(layer "B.Cu")
		(net "FRU_ADDR2")
	)
	(segment
		(start 220.36024 -78.215744)
		(end 220.903546 -78.75905)
		(width 0.17272)
		(layer "B.Cu")
		(net "FRU_ADDR2")
	)
	(segment
		(start 220.98 -79.448152)
		(end 220.98 -80.7974)
		(width 0.17272)
		(layer "B.Cu")
		(net "FRU_ADDR2")
	)
	(segment
		(start 220.98 -78.75905)
		(end 220.98 -79.448152)
		(width 0.17272)
		(layer "B.Cu")
		(net "FRU_ADDR2")
	)
	(via
		(at 191.516 -90.667078)
		(size 0.508)
		(drill 0.254)
		(layers "F.Cu" "B.Cu")
		(net "SMB_PDB_MISC_SDA")
	)
	(via
		(at 238.90605 -77.216)
		(size 0.508)
		(drill 0.254)
		(layers "F.Cu" "B.Cu")
		(net "SMB_PDB_MISC_SDA")
	)
	(segment
		(start 193.11112 -90.667078)
		(end 191.516 -90.667078)
		(width 0.17272)
		(layer "B.Cu")
		(net "SMB_PDB_MISC_SDA")
	)
	(segment
		(start 238.90605 -77.216)
		(end 238.90605 -77.851)
		(width 0.17272)
		(layer "B.Cu")
		(net "SMB_PDB_MISC_SDA")
	)
	(segment
		(start 196.113654 -90.5002)
		(end 199.875394 -86.73846)
		(width 0.12954)
		(layer "In7.Cu")
		(net "SMB_PDB_MISC_SDA")
	)
	(segment
		(start 232.791 -77.216)
		(end 238.90605 -77.216)
		(width 0.12954)
		(layer "In7.Cu")
		(net "SMB_PDB_MISC_SDA")
	)
	(segment
		(start 201.729594 -86.73846)
		(end 205.410054 -83.058)
		(width 0.12954)
		(layer "In7.Cu")
		(net "SMB_PDB_MISC_SDA")
	)
	(segment
		(start 191.682878 -90.5002)
		(end 196.113654 -90.5002)
		(width 0.12954)
		(layer "In7.Cu")
		(net "SMB_PDB_MISC_SDA")
	)
	(segment
		(start 214.29726 -85.90026)
		(end 224.10674 -85.90026)
		(width 0.12954)
		(layer "In7.Cu")
		(net "SMB_PDB_MISC_SDA")
	)
	(segment
		(start 199.875394 -86.73846)
		(end 201.729594 -86.73846)
		(width 0.12954)
		(layer "In7.Cu")
		(net "SMB_PDB_MISC_SDA")
	)
	(segment
		(start 191.516 -90.667078)
		(end 191.682878 -90.5002)
		(width 0.12954)
		(layer "In7.Cu")
		(net "SMB_PDB_MISC_SDA")
	)
	(segment
		(start 211.455 -83.058)
		(end 214.29726 -85.90026)
		(width 0.12954)
		(layer "In7.Cu")
		(net "SMB_PDB_MISC_SDA")
	)
	(segment
		(start 205.410054 -83.058)
		(end 211.455 -83.058)
		(width 0.12954)
		(layer "In7.Cu")
		(net "SMB_PDB_MISC_SDA")
	)
	(segment
		(start 224.10674 -85.90026)
		(end 232.791 -77.216)
		(width 0.12954)
		(layer "In7.Cu")
		(net "SMB_PDB_MISC_SDA")
	)
	(via
		(at 237.621064 -91.71305)
		(size 0.762)
		(drill 0.254)
		(layers "F.Cu" "B.Cu")
		(net "SMB_PDB_MISC_SCL")
	)
	(via
		(at 191.516 -89.789)
		(size 0.508)
		(drill 0.254)
		(layers "F.Cu" "B.Cu")
		(net "SMB_PDB_MISC_SCL")
	)
	(segment
		(start 192.378838 -90.017092)
		(end 193.11112 -90.017092)
		(width 0.17272)
		(layer "B.Cu")
		(net "SMB_PDB_MISC_SCL")
	)
	(segment
		(start 192.150746 -89.789)
		(end 192.378838 -90.017092)
		(width 0.17272)
		(layer "B.Cu")
		(net "SMB_PDB_MISC_SCL")
	)
	(segment
		(start 237.621064 -91.71305)
		(end 238.252 -91.71305)
		(width 0.17272)
		(layer "B.Cu")
		(net "SMB_PDB_MISC_SCL")
	)
	(segment
		(start 191.516 -89.789)
		(end 192.150746 -89.789)
		(width 0.17272)
		(layer "B.Cu")
		(net "SMB_PDB_MISC_SCL")
	)
	(segment
		(start 203.005182 -87.3252)
		(end 200.2536 -87.3252)
		(width 0.12954)
		(layer "In7.Cu")
		(net "SMB_PDB_MISC_SCL")
	)
	(segment
		(start 204.597 -85.733382)
		(end 203.005182 -87.3252)
		(width 0.12954)
		(layer "In7.Cu")
		(net "SMB_PDB_MISC_SCL")
	)
	(segment
		(start 233.553254 -89.154)
		(end 230.886254 -86.487)
		(width 0.12954)
		(layer "In7.Cu")
		(net "SMB_PDB_MISC_SCL")
	)
	(segment
		(start 205.1812 -84.2264)
		(end 204.597 -84.8106)
		(width 0.12954)
		(layer "In7.Cu")
		(net "SMB_PDB_MISC_SCL")
	)
	(segment
		(start 191.008 -89.91854)
		(end 191.13754 -89.789)
		(width 0.12954)
		(layer "In7.Cu")
		(net "SMB_PDB_MISC_SCL")
	)
	(segment
		(start 213.995254 -86.487)
		(end 211.734654 -84.2264)
		(width 0.12954)
		(layer "In7.Cu")
		(net "SMB_PDB_MISC_SCL")
	)
	(segment
		(start 235.062014 -89.154)
		(end 233.553254 -89.154)
		(width 0.12954)
		(layer "In7.Cu")
		(net "SMB_PDB_MISC_SCL")
	)
	(segment
		(start 191.13754 -89.789)
		(end 191.516 -89.789)
		(width 0.12954)
		(layer "In7.Cu")
		(net "SMB_PDB_MISC_SCL")
	)
	(segment
		(start 230.886254 -86.487)
		(end 213.995254 -86.487)
		(width 0.12954)
		(layer "In7.Cu")
		(net "SMB_PDB_MISC_SCL")
	)
	(segment
		(start 196.3928 -91.186)
		(end 191.13754 -91.186)
		(width 0.12954)
		(layer "In7.Cu")
		(net "SMB_PDB_MISC_SCL")
	)
	(segment
		(start 200.2536 -87.3252)
		(end 196.3928 -91.186)
		(width 0.12954)
		(layer "In7.Cu")
		(net "SMB_PDB_MISC_SCL")
	)
	(segment
		(start 191.008 -91.05646)
		(end 191.008 -89.91854)
		(width 0.12954)
		(layer "In7.Cu")
		(net "SMB_PDB_MISC_SCL")
	)
	(segment
		(start 237.621064 -91.71305)
		(end 235.062014 -89.154)
		(width 0.12954)
		(layer "In7.Cu")
		(net "SMB_PDB_MISC_SCL")
	)
	(segment
		(start 204.597 -84.8106)
		(end 204.597 -85.733382)
		(width 0.12954)
		(layer "In7.Cu")
		(net "SMB_PDB_MISC_SCL")
	)
	(segment
		(start 211.734654 -84.2264)
		(end 205.1812 -84.2264)
		(width 0.12954)
		(layer "In7.Cu")
		(net "SMB_PDB_MISC_SCL")
	)
	(segment
		(start 191.13754 -91.186)
		(end 191.008 -91.05646)
		(width 0.12954)
		(layer "In7.Cu")
		(net "SMB_PDB_MISC_SCL")
	)
	(via
		(at 236.855 -77.56779)
		(size 0.6604)
		(drill 0.3302)
		(layers "F.Cu" "B.Cu")
		(net "SMB_PDB_MISC_SDA_R")
	)
	(segment
		(start 238.155734 -78.96479)
		(end 236.855 -77.664056)
		(width 0.17272)
		(layer "B.Cu")
		(net "SMB_PDB_MISC_SDA_R")
	)
	(segment
		(start 237.82274 -77.56779)
		(end 238.10595 -77.851)
		(width 0.17272)
		(layer "B.Cu")
		(net "SMB_PDB_MISC_SDA_R")
	)
	(segment
		(start 236.855 -77.664056)
		(end 236.855 -77.56779)
		(width 0.17272)
		(layer "B.Cu")
		(net "SMB_PDB_MISC_SDA_R")
	)
	(segment
		(start 237.722664 -80.54086)
		(end 238.155734 -80.10779)
		(width 0.17272)
		(layer "B.Cu")
		(net "SMB_PDB_MISC_SDA_R")
	)
	(segment
		(start 236.855 -77.56779)
		(end 237.82274 -77.56779)
		(width 0.17272)
		(layer "B.Cu")
		(net "SMB_PDB_MISC_SDA_R")
	)
	(segment
		(start 237.722664 -81.939384)
		(end 237.722664 -80.54086)
		(width 0.17272)
		(layer "B.Cu")
		(net "SMB_PDB_MISC_SDA_R")
	)
	(segment
		(start 238.155734 -80.10779)
		(end 238.155734 -78.96479)
		(width 0.17272)
		(layer "B.Cu")
		(net "SMB_PDB_MISC_SDA_R")
	)
	(via
		(at 239.406684 -90.91295)
		(size 0.6604)
		(drill 0.3302)
		(layers "F.Cu" "B.Cu")
		(net "SMB_PDB_MISC_SCL_R")
	)
	(segment
		(start 239.406684 -90.62974)
		(end 239.406684 -90.91295)
		(width 0.17272)
		(layer "B.Cu")
		(net "SMB_PDB_MISC_SCL_R")
	)
	(segment
		(start 237.722664 -86.404196)
		(end 237.722664 -87.80272)
		(width 0.17272)
		(layer "B.Cu")
		(net "SMB_PDB_MISC_SCL_R")
	)
	(segment
		(start 237.722664 -87.80272)
		(end 238.282734 -88.36279)
		(width 0.17272)
		(layer "B.Cu")
		(net "SMB_PDB_MISC_SCL_R")
	)
	(segment
		(start 238.282734 -88.36279)
		(end 238.282734 -89.50579)
		(width 0.17272)
		(layer "B.Cu")
		(net "SMB_PDB_MISC_SCL_R")
	)
	(segment
		(start 238.282734 -89.50579)
		(end 239.406684 -90.62974)
		(width 0.17272)
		(layer "B.Cu")
		(net "SMB_PDB_MISC_SCL_R")
	)
	(segment
		(start 239.406684 -90.91295)
		(end 238.252 -90.91295)
		(width 0.17272)
		(layer "B.Cu")
		(net "SMB_PDB_MISC_SCL_R")
	)
	(zone
		(layer "F.Cu")
		(hatch none 0.5)
		(connect_pads
			(clearance 0)
		)
		(min_thickness 0.25)
		(keepout
			(tracks allowed)
			(vias allowed)
			(pads allowed)
			(copperpour allowed)
			(footprints not_allowed)
		)
		(placement
			(enabled no)
			(sheetname "")
		)
		(fill
			(thermal_gap 0.5)
			(thermal_bridge_width 0.5)
			(island_removal_mode 0)
		)
		(polygon
			(pts
				(arc
					(start 239.750092 -132.78993)
					(mid 234.750102 -137.78992)
					(end 239.750092 -142.78991)
				)
				(arc
					(start 261.750048 -142.78991)
					(mid 266.750038 -137.78992)
					(end 261.750048 -132.78993)
				)
			)
		)
		(polygon
			(pts
				(arc
					(start 261.750048 -136.29005)
					(mid 263.250172 -137.790174)
					(end 261.750048 -139.290044)
				)
				(xy 258.750054 -139.290044)
				(arc
					(start 239.881918 -140.286486)
					(mid 237.250048 -137.78992)
					(end 239.881918 -135.293354)
				)
				(xy 258.750054 -136.29005)
			)
		)
	)
	(zone
		(layer "F.Cu")
		(hatch none 0.5)
		(connect_pads
			(clearance 0)
		)
		(min_thickness 0.25)
		(keepout
			(tracks allowed)
			(vias allowed)
			(pads allowed)
			(copperpour allowed)
			(footprints not_allowed)
		)
		(placement
			(enabled no)
			(sheetname "")
		)
		(fill
			(thermal_gap 0.5)
			(thermal_bridge_width 0.5)
			(island_removal_mode 0)
		)
		(polygon
			(pts
				(arc
					(start 229.100126 -52.900072)
					(mid 224.100136 -57.900062)
					(end 229.100126 -62.900052)
				)
				(arc
					(start 251.100082 -62.900052)
					(mid 256.100072 -57.900062)
					(end 251.100082 -52.900072)
				)
			)
		)
	)
	(zone
		(layer "F.Cu")
		(hatch none 0.5)
		(connect_pads
			(clearance 0)
		)
		(min_thickness 0.25)
		(keepout
			(tracks allowed)
			(vias allowed)
			(pads allowed)
			(copperpour allowed)
			(footprints not_allowed)
		)
		(placement
			(enabled no)
			(sheetname "")
		)
		(fill
			(thermal_gap 0.5)
			(thermal_bridge_width 0.5)
			(island_removal_mode 0)
		)
		(polygon
			(pts
				(arc
					(start 315.410088 -101.454966)
					(mid 311.410096 -105.454958)
					(end 307.410104 -101.454966)
				)
				(arc
					(start 307.410104 -101.454966)
					(mid 311.410096 -97.454974)
					(end 315.410088 -101.454966)
				)
			)
		)
		(polygon
			(pts
				(arc
					(start 309.300118 -101.454966)
					(mid 311.410096 -99.344988)
					(end 313.520074 -101.454966)
				)
				(arc
					(start 313.520074 -101.454966)
					(mid 311.410096 -103.564944)
					(end 309.300118 -101.454966)
				)
			)
		)
	)
	(zone
		(layer "F.Cu")
		(hatch none 0.5)
		(connect_pads
			(clearance 0)
		)
		(min_thickness 0.25)
		(keepout
			(tracks allowed)
			(vias allowed)
			(pads allowed)
			(copperpour allowed)
			(footprints not_allowed)
		)
		(placement
			(enabled no)
			(sheetname "")
		)
		(fill
			(thermal_gap 0.5)
			(thermal_bridge_width 0.5)
			(island_removal_mode 0)
		)
		(polygon
			(pts
				(xy 57.520078 -26.459942) (xy 57.520078 -47.040038) (xy 140.219938 -47.040038) (xy 140.219938 -26.459942)
			)
		)
	)
	(zone
		(layer "F.Cu")
		(hatch none 0.5)
		(connect_pads
			(clearance 0)
		)
		(min_thickness 0.25)
		(keepout
			(tracks allowed)
			(vias allowed)
			(pads allowed)
			(copperpour allowed)
			(footprints not_allowed)
		)
		(placement
			(enabled no)
			(sheetname "")
		)
		(fill
			(thermal_gap 0.5)
			(thermal_bridge_width 0.5)
			(island_removal_mode 0)
		)
		(polygon
			(pts
				(arc
					(start 208.000092 -16.999966)
					(mid 203.000102 -11.999976)
					(end 208.000092 -6.999986)
				)
				(arc
					(start 230.000048 -6.999986)
					(mid 235.000038 -11.999976)
					(end 230.000048 -16.999966)
				)
			)
		)
	)
	(zone
		(layer "F.Cu")
		(hatch none 0.5)
		(connect_pads
			(clearance 0)
		)
		(min_thickness 0.25)
		(keepout
			(tracks allowed)
			(vias allowed)
			(pads allowed)
			(copperpour allowed)
			(footprints not_allowed)
		)
		(placement
			(enabled no)
			(sheetname "")
		)
		(fill
			(thermal_gap 0.5)
			(thermal_bridge_width 0.5)
			(island_removal_mode 0)
		)
		(polygon
			(pts
				(xy 38.999922 -48.719994) (xy 215.000078 -48.719994) (xy 215.000078 -50.71999) (xy 38.999922 -50.71999)
			)
		)
	)
	(zone
		(layer "F.Cu")
		(hatch none 0.5)
		(connect_pads
			(clearance 0)
		)
		(min_thickness 0.25)
		(keepout
			(tracks allowed)
			(vias allowed)
			(pads allowed)
			(copperpour allowed)
			(footprints not_allowed)
		)
		(placement
			(enabled no)
			(sheetname "")
		)
		(fill
			(thermal_gap 0.5)
			(thermal_bridge_width 0.5)
			(island_removal_mode 0)
		)
		(polygon
			(pts
				(arc
					(start 108.000038 -16.999966)
					(mid 103.000048 -11.999976)
					(end 108.000038 -6.999986)
				)
				(arc
					(start 129.999994 -6.999986)
					(mid 134.999984 -11.999976)
					(end 129.999994 -16.999966)
				)
			)
		)
	)
	(zone
		(layer "F.Cu")
		(hatch none 0.5)
		(connect_pads
			(clearance 0)
		)
		(min_thickness 0.25)
		(keepout
			(tracks allowed)
			(vias allowed)
			(pads allowed)
			(copperpour allowed)
			(footprints not_allowed)
		)
		(placement
			(enabled no)
			(sheetname "")
		)
		(fill
			(thermal_gap 0.5)
			(thermal_bridge_width 0.5)
			(island_removal_mode 0)
		)
		(polygon
			(pts
				(xy 304.729896 -145.999962) (xy 304.729896 -0.999998)
				(arc
					(start 323.000116 -0.999998)
					(mid 325.828537 -2.171569)
					(end 327.000108 -4.99999)
				)
				(arc
					(start 327.000108 -141.99997)
					(mid 325.828537 -144.828391)
					(end 323.000116 -145.999962)
				)
			)
		)
	)
	(zone
		(layer "F.Cu")
		(hatch none 0.5)
		(connect_pads
			(clearance 0)
		)
		(min_thickness 0.25)
		(keepout
			(tracks not_allowed)
			(vias allowed)
			(pads allowed)
			(copperpour not_allowed)
			(footprints allowed)
		)
		(placement
			(enabled no)
			(sheetname "")
		)
		(fill
			(thermal_gap 0.5)
			(thermal_bridge_width 0.5)
			(island_removal_mode 0)
		)
		(polygon
			(pts
				(arc
					(start 129.999994 -18.015966)
					(mid 136.015984 -11.999976)
					(end 129.999994 -5.983986)
				)
				(arc
					(start 108.000038 -5.983986)
					(mid 101.984048 -11.999976)
					(end 108.000038 -18.015966)
				)
			)
		)
	)
	(zone
		(layer "F.Cu")
		(hatch none 0.5)
		(connect_pads
			(clearance 0)
		)
		(min_thickness 0.25)
		(keepout
			(tracks allowed)
			(vias allowed)
			(pads allowed)
			(copperpour allowed)
			(footprints not_allowed)
		)
		(placement
			(enabled no)
			(sheetname "")
		)
		(fill
			(thermal_gap 0.5)
			(thermal_bridge_width 0.5)
			(island_removal_mode 0)
		)
		(polygon
			(pts
				(xy 35.450018 -40.649906) (xy 35.450018 -0.999998) (xy 103.000048 -0.999998)
				(arc
					(start 103.000048 -11.999976)
					(mid 104.464511 -15.535503)
					(end 108.000038 -16.999966)
				)
				(arc
					(start 129.999994 -16.999966)
					(mid 132.655505 -16.236662)
					(end 134.500112 -14.17955)
				)
				(xy 134.500112 -26.459942) (xy 57.520078 -26.459942) (xy 57.520078 -47.040038) (xy 140.219938 -47.040038)
				(xy 140.219938 -26.459942) (xy 134.999984 -26.459942)
				(arc
					(start 134.999984 -11.999976)
					(mid 133.535521 -8.464449)
					(end 129.999994 -6.999986)
				)
				(arc
					(start 108.000038 -6.999986)
					(mid 105.344491 -7.763426)
					(end 103.49992 -9.820656)
				)
				(xy 103.49992 -0.999998) (xy 254.225044 -0.999998) (xy 254.225044 -23.839678) (xy 163.135056 -23.839678)
				(xy 163.135056 -44.41952) (xy 254.225044 -44.41952)
				(arc
					(start 254.225044 -53.996844)
					(mid 252.756001 -53.182257)
					(end 251.100082 -52.900072)
				)
				(arc
					(start 229.100126 -52.900072)
					(mid 224.100136 -57.900062)
					(end 229.100126 -62.900052)
				)
				(arc
					(start 251.100082 -62.900052)
					(mid 255.694586 -59.87248)
					(end 254.724916 -54.45633)
				)
				(xy 254.724916 -0.999998) (xy 304.729896 -0.999998) (xy 304.729896 -145.999962) (xy 266.750038 -145.999962)
				(arc
					(start 266.750038 -137.78992)
					(mid 265.285575 -134.254393)
					(end 261.750048 -132.78993)
				)
				(arc
					(start 239.750092 -132.78993)
					(mid 234.750102 -137.78992)
					(end 239.750092 -142.78991)
				)
				(arc
					(start 261.750048 -142.78991)
					(mid 264.405375 -142.026517)
					(end 266.249912 -139.969494)
				)
				(xy 266.249912 -145.999962) (xy 198.250048 -145.999962) (xy 198.250048 -63.719964) (xy 215.000078 -63.719964)
				(xy 215.000078 -48.719994) (xy 38.999922 -48.719994) (xy 38.999922 -63.719964) (xy 35.450018 -63.719964)
				(xy 35.450018 -107.1499) (xy 15.260066 -107.1499) (xy 15.260066 -40.649906)
			)
		)
		(polygon
			(pts
				(arc
					(start 208.000092 -16.999966)
					(mid 203.000102 -11.999976)
					(end 208.000092 -6.999986)
				)
				(arc
					(start 230.000048 -6.999986)
					(mid 235.000038 -11.999976)
					(end 230.000048 -16.999966)
				)
			)
		)
	)
	(zone
		(layer "F.Cu")
		(hatch none 0.5)
		(connect_pads
			(clearance 0)
		)
		(min_thickness 0.25)
		(keepout
			(tracks allowed)
			(vias allowed)
			(pads allowed)
			(copperpour allowed)
			(footprints not_allowed)
		)
		(placement
			(enabled no)
			(sheetname "")
		)
		(fill
			(thermal_gap 0.5)
			(thermal_bridge_width 0.5)
			(island_removal_mode 0)
		)
		(polygon
			(pts
				(arc
					(start 320.079878 -132.40004)
					(mid 314.999878 -137.48004)
					(end 309.919878 -132.40004)
				)
				(arc
					(start 309.919878 -132.40004)
					(mid 314.999878 -127.32004)
					(end 320.079878 -132.40004)
				)
			)
		)
		(polygon
			(pts
				(arc
					(start 311.799986 -132.40004)
					(mid 315.000132 -129.199894)
					(end 318.200024 -132.40004)
				)
				(arc
					(start 318.200024 -132.40004)
					(mid 315.000132 -135.599932)
					(end 311.799986 -132.40004)
				)
			)
		)
	)
	(zone
		(layer "F.Cu")
		(hatch none 0.5)
		(connect_pads
			(clearance 0)
		)
		(min_thickness 0.25)
		(keepout
			(tracks allowed)
			(vias allowed)
			(pads allowed)
			(copperpour allowed)
			(footprints not_allowed)
		)
		(placement
			(enabled no)
			(sheetname "")
		)
		(fill
			(thermal_gap 0.5)
			(thermal_bridge_width 0.5)
			(island_removal_mode 0)
		)
		(polygon
			(pts
				(xy 38.999922 -130.50012) (xy 195.000118 -130.50012) (xy 195.000118 -126.810008) (xy 38.999922 -126.810008)
			)
		)
	)
	(zone
		(layer "F.Cu")
		(hatch none 0.5)
		(connect_pads
			(clearance 0)
		)
		(min_thickness 0.25)
		(keepout
			(tracks allowed)
			(vias allowed)
			(pads allowed)
			(copperpour allowed)
			(footprints not_allowed)
		)
		(placement
			(enabled no)
			(sheetname "")
		)
		(fill
			(thermal_gap 0.5)
			(thermal_bridge_width 0.5)
			(island_removal_mode 0)
		)
		(polygon
			(pts
				(arc
					(start 320.079878 -14.59992)
					(mid 314.999878 -19.67992)
					(end 309.919878 -14.59992)
				)
				(arc
					(start 309.919878 -14.59992)
					(mid 314.999878 -9.51992)
					(end 320.079878 -14.59992)
				)
			)
		)
		(polygon
			(pts
				(arc
					(start 311.799986 -14.59992)
					(mid 315.000132 -11.399774)
					(end 318.200024 -14.59992)
				)
				(arc
					(start 318.200024 -14.59992)
					(mid 315.000132 -17.799812)
					(end 311.799986 -14.59992)
				)
			)
		)
	)
	(zone
		(layer "F.Cu")
		(hatch none 0.5)
		(connect_pads
			(clearance 0)
		)
		(min_thickness 0.25)
		(keepout
			(tracks allowed)
			(vias allowed)
			(pads allowed)
			(copperpour allowed)
			(footprints not_allowed)
		)
		(placement
			(enabled no)
			(sheetname "")
		)
		(fill
			(thermal_gap 0.5)
			(thermal_bridge_width 0.5)
			(island_removal_mode 0)
		)
		(polygon
			(pts
				(arc
					(start 7.999984 -6.999986)
					(mid 2.999994 -11.999976)
					(end 7.999984 -16.999966)
				)
				(arc
					(start 29.99994 -16.999966)
					(mid 34.99993 -11.999976)
					(end 29.99994 -6.999986)
				)
			)
		)
		(polygon
			(pts
				(arc
					(start 29.99994 -10.500106)
					(mid 31.500064 -12.00023)
					(end 29.99994 -13.5001)
				)
				(xy 26.999946 -13.5001)
				(arc
					(start 8.13181 -14.496542)
					(mid 5.49994 -11.999976)
					(end 8.13181 -9.50341)
				)
				(xy 26.999946 -10.500106)
			)
		)
	)
	(zone
		(layer "F.Cu")
		(hatch none 0.5)
		(connect_pads
			(clearance 0)
		)
		(min_thickness 0.25)
		(keepout
			(tracks allowed)
			(vias allowed)
			(pads allowed)
			(copperpour allowed)
			(footprints not_allowed)
		)
		(placement
			(enabled no)
			(sheetname "")
		)
		(fill
			(thermal_gap 0.5)
			(thermal_bridge_width 0.5)
			(island_removal_mode 0)
		)
		(polygon
			(pts
				(arc
					(start 320.079878 -132.450078)
					(mid 309.91252 -132.40004)
					(end 320.079878 -132.350002)
				)
				(arc
					(start 327.49998 -132.350002)
					(mid 302.48088 -132.40004)
					(end 327.49998 -132.450078)
				)
			)
		)
	)
	(zone
		(layer "F.Cu")
		(hatch none 0.5)
		(connect_pads
			(clearance 0)
		)
		(min_thickness 0.25)
		(keepout
			(tracks allowed)
			(vias allowed)
			(pads allowed)
			(copperpour allowed)
			(footprints not_allowed)
		)
		(placement
			(enabled no)
			(sheetname "")
		)
		(fill
			(thermal_gap 0.5)
			(thermal_bridge_width 0.5)
			(island_removal_mode 0)
		)
		(polygon
			(pts
				(arc
					(start 7.999984 -130.999992)
					(mid 2.999994 -135.999982)
					(end 7.999984 -140.999972)
				)
				(arc
					(start 29.99994 -140.999972)
					(mid 34.99993 -135.999982)
					(end 29.99994 -130.999992)
				)
			)
		)
		(polygon
			(pts
				(arc
					(start 29.99994 -134.500112)
					(mid 31.500064 -136.000236)
					(end 29.99994 -137.500106)
				)
				(xy 26.999946 -137.500106)
				(arc
					(start 8.13181 -138.496548)
					(mid 5.49994 -135.999982)
					(end 8.13181 -133.503416)
				)
				(xy 26.999946 -134.500112)
			)
		)
	)
	(zone
		(layer "F.Cu")
		(hatch none 0.5)
		(connect_pads
			(clearance 0)
		)
		(min_thickness 0.25)
		(keepout
			(tracks allowed)
			(vias allowed)
			(pads allowed)
			(copperpour allowed)
			(footprints not_allowed)
		)
		(placement
			(enabled no)
			(sheetname "")
		)
		(fill
			(thermal_gap 0.5)
			(thermal_bridge_width 0.5)
			(island_removal_mode 0)
		)
		(polygon
			(pts
				(xy 163.135056 -23.839678) (xy 163.135056 -44.41952) (xy 254.724916 -44.41952) (xy 254.724916 -23.839678)
			)
		)
	)
	(zone
		(layer "F.Cu")
		(hatch none 0.5)
		(connect_pads
			(clearance 0)
		)
		(min_thickness 0.25)
		(keepout
			(tracks not_allowed)
			(vias allowed)
			(pads allowed)
			(copperpour not_allowed)
			(footprints allowed)
		)
		(placement
			(enabled no)
			(sheetname "")
		)
		(fill
			(thermal_gap 0.5)
			(thermal_bridge_width 0.5)
			(island_removal_mode 0)
		)
		(polygon
			(pts
				(xy 10.100056 -128.729994) (xy 32.599884 -128.729994) (xy 32.599884 -116.229892) (xy 10.100056 -116.229892)
			)
		)
	)
	(zone
		(layer "F.Cu")
		(hatch none 0.5)
		(connect_pads
			(clearance 0)
		)
		(min_thickness 0.25)
		(keepout
			(tracks allowed)
			(vias allowed)
			(pads allowed)
			(copperpour allowed)
			(footprints not_allowed)
		)
		(placement
			(enabled no)
			(sheetname "")
		)
		(fill
			(thermal_gap 0.5)
			(thermal_bridge_width 0.5)
			(island_removal_mode 0)
		)
		(polygon
			(pts
				(arc
					(start 108.000038 -6.999986)
					(mid 103.000048 -11.999976)
					(end 108.000038 -16.999966)
				)
				(arc
					(start 129.999994 -16.999966)
					(mid 134.999984 -11.999976)
					(end 129.999994 -6.999986)
				)
			)
		)
		(polygon
			(pts
				(arc
					(start 129.999994 -10.500106)
					(mid 131.500118 -12.00023)
					(end 129.999994 -13.5001)
				)
				(xy 127 -13.5001)
				(arc
					(start 108.131864 -14.496542)
					(mid 105.499994 -11.999976)
					(end 108.131864 -9.50341)
				)
				(xy 127 -10.500106)
			)
		)
	)
	(zone
		(layer "F.Cu")
		(hatch none 0.5)
		(connect_pads
			(clearance 0)
		)
		(min_thickness 0.25)
		(keepout
			(tracks allowed)
			(vias allowed)
			(pads allowed)
			(copperpour allowed)
			(footprints not_allowed)
		)
		(placement
			(enabled no)
			(sheetname "")
		)
		(fill
			(thermal_gap 0.5)
			(thermal_bridge_width 0.5)
			(island_removal_mode 0)
		)
		(polygon
			(pts
				(arc
					(start 315.410088 -44.304966)
					(mid 311.410096 -48.304958)
					(end 307.410104 -44.304966)
				)
				(arc
					(start 307.410104 -44.304966)
					(mid 311.410096 -40.304974)
					(end 315.410088 -44.304966)
				)
			)
		)
		(polygon
			(pts
				(arc
					(start 309.300118 -44.304966)
					(mid 311.410096 -42.194988)
					(end 313.520074 -44.304966)
				)
				(arc
					(start 313.520074 -44.304966)
					(mid 311.410096 -46.414944)
					(end 309.300118 -44.304966)
				)
			)
		)
	)
	(zone
		(layer "F.Cu")
		(hatch none 0.5)
		(connect_pads
			(clearance 0)
		)
		(min_thickness 0.25)
		(keepout
			(tracks allowed)
			(vias allowed)
			(pads allowed)
			(copperpour allowed)
			(footprints not_allowed)
		)
		(placement
			(enabled no)
			(sheetname "")
		)
		(fill
			(thermal_gap 0.5)
			(thermal_bridge_width 0.5)
			(island_removal_mode 0)
		)
		(polygon
			(pts
				(arc
					(start 239.750092 -132.78993)
					(mid 234.750102 -137.78992)
					(end 239.750092 -142.78991)
				)
				(arc
					(start 261.750048 -142.78991)
					(mid 266.750038 -137.78992)
					(end 261.750048 -132.78993)
				)
			)
		)
	)
	(zone
		(layer "F.Cu")
		(hatch none 0.5)
		(connect_pads
			(clearance 0)
		)
		(min_thickness 0.25)
		(keepout
			(tracks allowed)
			(vias allowed)
			(pads allowed)
			(copperpour allowed)
			(footprints not_allowed)
		)
		(placement
			(enabled no)
			(sheetname "")
		)
		(fill
			(thermal_gap 0.5)
			(thermal_bridge_width 0.5)
			(island_removal_mode 0)
		)
		(polygon
			(pts
				(xy 35.450018 -145.999962)
				(arc
					(start 4.99999 -145.999962)
					(mid 2.171569 -144.828391)
					(end 0.999998 -141.99997)
				)
				(arc
					(start 0.999998 -131.729988)
					(mid 1.585783 -130.315777)
					(end 2.999994 -129.729992)
				)
				(arc
					(start 9.59993 -129.729992)
					(mid 10.660662 -129.29078)
					(end 11.100054 -128.230122)
				)
				(arc
					(start 11.100054 -116.730018)
					(mid 10.660678 -115.66927)
					(end 9.59993 -115.229894)
				)
				(arc
					(start 2.999994 -115.229894)
					(mid 1.585783 -114.644109)
					(end 0.999998 -113.229898)
				)
				(arc
					(start 0.999998 -34.569908)
					(mid 1.585783 -33.155697)
					(end 2.999994 -32.569912)
				)
				(arc
					(start 9.59993 -32.569912)
					(mid 10.660662 -32.1307)
					(end 11.100054 -31.070042)
				)
				(arc
					(start 11.100054 -19.569938)
					(mid 10.660573 -18.509444)
					(end 9.59993 -18.070068)
				)
				(arc
					(start 2.999994 -18.070068)
					(mid 1.585783 -17.484283)
					(end 0.999998 -16.070072)
				)
				(arc
					(start 0.999998 -4.99999)
					(mid 2.171569 -2.171569)
					(end 4.99999 -0.999998)
				)
				(xy 35.450018 -0.999998) (xy 35.450018 -11.500104)
				(arc
					(start 34.975038 -11.500104)
					(mid 33.354117 -8.291966)
					(end 29.99994 -6.999986)
				)
				(arc
					(start 7.999984 -6.999986)
					(mid 2.999994 -11.999976)
					(end 7.999984 -16.999966)
				)
				(arc
					(start 29.99994 -16.999966)
					(mid 33.354145 -15.708198)
					(end 34.975038 -12.500102)
				)
				(xy 35.450018 -12.500102) (xy 35.450018 -40.649906) (xy 15.260066 -40.649906) (xy 15.260066 -107.1499)
				(xy 35.450018 -107.1499) (xy 35.450018 -135.50011)
				(arc
					(start 34.975038 -135.50011)
					(mid 33.354117 -132.291972)
					(end 29.99994 -130.999992)
				)
				(arc
					(start 7.999984 -130.999992)
					(mid 2.999994 -135.999982)
					(end 7.999984 -140.999972)
				)
				(arc
					(start 29.99994 -140.999972)
					(mid 33.354145 -139.708204)
					(end 34.975038 -136.500108)
				)
				(xy 35.450018 -136.500108)
			)
		)
	)
	(zone
		(layer "F.Cu")
		(hatch none 0.5)
		(connect_pads
			(clearance 0)
		)
		(min_thickness 0.25)
		(keepout
			(tracks allowed)
			(vias allowed)
			(pads allowed)
			(copperpour allowed)
			(footprints not_allowed)
		)
		(placement
			(enabled no)
			(sheetname "")
		)
		(fill
			(thermal_gap 0.5)
			(thermal_bridge_width 0.5)
			(island_removal_mode 0)
		)
		(polygon
			(pts
				(arc
					(start 208.000092 -6.999986)
					(mid 203.000102 -11.999976)
					(end 208.000092 -16.999966)
				)
				(arc
					(start 230.000048 -16.999966)
					(mid 235.000038 -11.999976)
					(end 230.000048 -6.999986)
				)
			)
		)
		(polygon
			(pts
				(arc
					(start 230.000048 -10.500106)
					(mid 231.500172 -12.00023)
					(end 230.000048 -13.5001)
				)
				(xy 227.000054 -13.5001)
				(arc
					(start 208.131918 -14.496542)
					(mid 205.500048 -11.999976)
					(end 208.131918 -9.50341)
				)
				(xy 227.000054 -10.500106)
			)
		)
	)
	(zone
		(layer "F.Cu")
		(hatch none 0.5)
		(connect_pads
			(clearance 0)
		)
		(min_thickness 0.25)
		(keepout
			(tracks not_allowed)
			(vias allowed)
			(pads allowed)
			(copperpour not_allowed)
			(footprints allowed)
		)
		(placement
			(enabled no)
			(sheetname "")
		)
		(fill
			(thermal_gap 0.5)
			(thermal_bridge_width 0.5)
			(island_removal_mode 0)
		)
		(polygon
			(pts
				(arc
					(start 251.079 -64.817244)
					(mid 257.98399 -57.912254)
					(end 251.079 -51.007264)
				)
				(arc
					(start 229.079044 -51.007264)
					(mid 222.174054 -57.912254)
					(end 229.079044 -64.817244)
				)
			)
		)
	)
	(zone
		(layer "F.Cu")
		(hatch none 0.5)
		(connect_pads
			(clearance 0)
		)
		(min_thickness 0.25)
		(keepout
			(tracks not_allowed)
			(vias allowed)
			(pads allowed)
			(copperpour not_allowed)
			(footprints allowed)
		)
		(placement
			(enabled no)
			(sheetname "")
		)
		(fill
			(thermal_gap 0.5)
			(thermal_bridge_width 0.5)
			(island_removal_mode 0)
		)
		(polygon
			(pts
				(arc
					(start 261.747 -144.69999)
					(mid 268.65199 -137.795)
					(end 261.747 -130.89001)
				)
				(arc
					(start 239.747044 -130.89001)
					(mid 232.842054 -137.795)
					(end 239.747044 -144.69999)
				)
			)
		)
	)
	(zone
		(layer "F.Cu")
		(hatch none 0.5)
		(connect_pads
			(clearance 0)
		)
		(min_thickness 0.25)
		(keepout
			(tracks allowed)
			(vias allowed)
			(pads allowed)
			(copperpour allowed)
			(footprints not_allowed)
		)
		(placement
			(enabled no)
			(sheetname "")
		)
		(fill
			(thermal_gap 0.5)
			(thermal_bridge_width 0.5)
			(island_removal_mode 0)
		)
		(polygon
			(pts
				(xy 35.450018 -126.810008) (xy 198.250048 -126.810008) (xy 198.250048 -119.260112) (xy 50.690018 -119.260112)
				(xy 50.690018 -103.17099) (xy 71.5899 -103.17099) (xy 71.5899 -118.770908) (xy 90.689938 -118.770908)
				(xy 90.689938 -103.17099) (xy 111.590074 -103.17099) (xy 111.590074 -118.770908) (xy 130.690112 -118.770908)
				(xy 130.690112 -103.17099) (xy 151.589994 -103.17099) (xy 151.589994 -118.770908) (xy 170.690032 -118.770908)
				(xy 170.690032 -103.17099) (xy 191.589914 -103.17099) (xy 191.589914 -118.759986) (xy 198.250048 -118.759986)
				(xy 198.250048 -63.719964) (xy 35.450018 -63.719964)
			)
		)
	)
	(zone
		(layer "F.Cu")
		(hatch none 0.5)
		(connect_pads
			(clearance 0)
		)
		(min_thickness 0.25)
		(keepout
			(tracks allowed)
			(vias allowed)
			(pads allowed)
			(copperpour allowed)
			(footprints not_allowed)
		)
		(placement
			(enabled no)
			(sheetname "")
		)
		(fill
			(thermal_gap 0.5)
			(thermal_bridge_width 0.5)
			(island_removal_mode 0)
		)
		(polygon
			(pts
				(xy 195.000118 -130.50012) (xy 195.000118 -142.500096) (xy 38.999922 -142.500096) (xy 38.999922 -130.50012)
			)
		)
	)
	(zone
		(layer "F.Cu")
		(hatch none 0.5)
		(connect_pads
			(clearance 0)
		)
		(min_thickness 0.25)
		(keepout
			(tracks allowed)
			(vias allowed)
			(pads allowed)
			(copperpour allowed)
			(footprints not_allowed)
		)
		(placement
			(enabled no)
			(sheetname "")
		)
		(fill
			(thermal_gap 0.5)
			(thermal_bridge_width 0.5)
			(island_removal_mode 0)
		)
		(polygon
			(pts
				(arc
					(start 320.079878 -14.649958)
					(mid 309.91252 -14.59992)
					(end 320.079878 -14.549882)
				)
				(arc
					(start 327.49998 -14.549882)
					(mid 302.48088 -14.59992)
					(end 327.49998 -14.649958)
				)
			)
		)
	)
	(zone
		(layer "F.Cu")
		(hatch none 0.5)
		(connect_pads
			(clearance 0)
		)
		(min_thickness 0.25)
		(keepout
			(tracks allowed)
			(vias allowed)
			(pads allowed)
			(copperpour allowed)
			(footprints not_allowed)
		)
		(placement
			(enabled no)
			(sheetname "")
		)
		(fill
			(thermal_gap 0.5)
			(thermal_bridge_width 0.5)
			(island_removal_mode 0)
		)
		(polygon
			(pts
				(arc
					(start 229.100126 -52.900072)
					(mid 224.100136 -57.900062)
					(end 229.100126 -62.900052)
				)
				(arc
					(start 251.100082 -62.900052)
					(mid 256.100072 -57.900062)
					(end 251.100082 -52.900072)
				)
			)
		)
		(polygon
			(pts
				(arc
					(start 251.100082 -56.399938)
					(mid 252.600206 -57.900062)
					(end 251.100082 -59.399932)
				)
				(xy 248.100088 -59.399932)
				(arc
					(start 229.231952 -60.396628)
					(mid 226.600082 -57.900062)
					(end 229.231952 -55.403496)
				)
				(xy 248.100088 -56.399938)
			)
		)
	)
	(zone
		(layer "F.Cu")
		(hatch none 0.5)
		(connect_pads
			(clearance 0)
		)
		(min_thickness 0.25)
		(keepout
			(tracks not_allowed)
			(vias allowed)
			(pads allowed)
			(copperpour not_allowed)
			(footprints allowed)
		)
		(placement
			(enabled no)
			(sheetname "")
		)
		(fill
			(thermal_gap 0.5)
			(thermal_bridge_width 0.5)
			(island_removal_mode 0)
		)
		(polygon
			(pts
				(arc
					(start 309.919878 -14.59992)
					(mid 314.999878 -9.51992)
					(end 320.079878 -14.59992)
				)
				(arc
					(start 320.079878 -14.59992)
					(mid 314.999878 -19.67992)
					(end 309.919878 -14.59992)
				)
			)
		)
	)
	(zone
		(layer "F.Cu")
		(hatch none 0.5)
		(connect_pads
			(clearance 0)
		)
		(min_thickness 0.25)
		(keepout
			(tracks allowed)
			(vias allowed)
			(pads allowed)
			(copperpour allowed)
			(footprints not_allowed)
		)
		(placement
			(enabled no)
			(sheetname "")
		)
		(fill
			(thermal_gap 0.5)
			(thermal_bridge_width 0.5)
			(island_removal_mode 0)
		)
		(polygon
			(pts
				(xy 38.999922 -63.719964) (xy 215.000078 -63.719964) (xy 215.000078 -50.71999) (xy 38.999922 -50.71999)
			)
		)
	)
	(zone
		(layer "F.Cu")
		(hatch none 0.5)
		(connect_pads
			(clearance 0)
		)
		(min_thickness 0.25)
		(keepout
			(tracks not_allowed)
			(vias allowed)
			(pads allowed)
			(copperpour not_allowed)
			(footprints allowed)
		)
		(placement
			(enabled no)
			(sheetname "")
		)
		(fill
			(thermal_gap 0.5)
			(thermal_bridge_width 0.5)
			(island_removal_mode 0)
		)
		(polygon
			(pts
				(xy 10.100056 -19.070066) (xy 32.599884 -19.070066) (xy 32.599884 -31.569914) (xy 10.100056 -31.569914)
			)
		)
	)
	(zone
		(layers "F.Cu" "B.Cu" "In1.Cu" "In2.Cu" "In3.Cu" "In4.Cu" "In5.Cu" "In6.Cu"
			"In7.Cu" "In8.Cu"
		)
		(hatch none 0.5)
		(connect_pads
			(clearance 0)
		)
		(min_thickness 0.25)
		(keepout
			(tracks not_allowed)
			(vias allowed)
			(pads allowed)
			(copperpour not_allowed)
			(footprints allowed)
		)
		(placement
			(enabled no)
			(sheetname "")
		)
		(fill
			(thermal_gap 0.5)
			(thermal_bridge_width 0.5)
			(island_removal_mode 0)
		)
		(polygon
			(pts
				(xy 315.500004 -0.199898) (xy 320.499994 -0.199898) (xy 320.195194 -0.504698) (xy 315.804804 -0.504698)
			)
		)
	)
	(zone
		(layers "F.Cu" "B.Cu" "In1.Cu" "In2.Cu" "In3.Cu" "In4.Cu" "In5.Cu" "In6.Cu"
			"In7.Cu" "In8.Cu"
		)
		(hatch none 0.5)
		(connect_pads
			(clearance 0)
		)
		(min_thickness 0.25)
		(keepout
			(tracks not_allowed)
			(vias allowed)
			(pads allowed)
			(copperpour not_allowed)
			(footprints allowed)
		)
		(placement
			(enabled no)
			(sheetname "")
		)
		(fill
			(thermal_gap 0.5)
			(thermal_bridge_width 0.5)
			(island_removal_mode 0)
		)
		(polygon
			(pts
				(xy 320.499994 2.199894) (xy 315.500004 2.199894) (xy 315.804804 2.504694) (xy 320.195194 2.504694)
			)
		)
	)
	(zone
		(layers "F.Cu" "B.Cu" "In1.Cu" "In2.Cu" "In3.Cu" "In4.Cu" "In5.Cu" "In6.Cu"
			"In7.Cu" "In8.Cu"
		)
		(hatch none 0.5)
		(connect_pads
			(clearance 0)
		)
		(min_thickness 0.25)
		(keepout
			(tracks not_allowed)
			(vias allowed)
			(pads allowed)
			(copperpour not_allowed)
			(footprints allowed)
		)
		(placement
			(enabled no)
			(sheetname "")
		)
		(fill
			(thermal_gap 0.5)
			(thermal_bridge_width 0.5)
			(island_removal_mode 0)
		)
		(polygon
			(pts
				(arc
					(start 315.042296 -44.304966)
					(mid 307.777896 -44.304966)
					(end 315.042296 -44.304966)
				)
			)
		)
	)
	(zone
		(layers "F.Cu" "B.Cu" "In1.Cu" "In2.Cu" "In3.Cu" "In4.Cu" "In5.Cu" "In6.Cu"
			"In7.Cu" "In8.Cu"
		)
		(name "Package Keepin")
		(hatch none 0.5)
		(connect_pads
			(clearance 0)
		)
		(min_thickness 0.25)
		(keepout
			(tracks allowed)
			(vias allowed)
			(pads allowed)
			(copperpour allowed)
			(footprints allowed)
		)
		(placement
			(enabled no)
			(sheetname "")
		)
		(fill
			(thermal_gap 0.5)
			(thermal_bridge_width 0.5)
			(island_removal_mode 0)
		)
		(polygon
			(pts
				(arc
					(start 2.999994 -129.745994)
					(mid 1.597098 -130.327092)
					(end 1.016 -131.729988)
				)
				(arc
					(start 1.016 -141.99997)
					(mid 2.182884 -144.817076)
					(end 4.99999 -145.98396)
				)
				(xy 266.194286 -145.98396) (xy 266.194286 -148.984208) (xy 265.974576 -149.203918) (xy 153.913586 -149.203918)
				(xy 152.63622 -150.481284) (xy 152.63622 -165.356794) (xy 153.825194 -166.545768) (xy 326.556624 -166.545768)
				(xy 327.745598 -165.356794) (xy 327.745598 -150.425404) (xy 326.644254 -149.32406) (xy 267.019786 -149.32406)
				(xy 266.81049 -149.114764) (xy 266.81049 -145.98396)
				(arc
					(start 323.000116 -145.98396)
					(mid 325.817222 -144.817076)
					(end 326.984106 -141.99997)
				)
				(arc
					(start 326.984106 -4.99999)
					(mid 325.817222 -2.182884)
					(end 323.000116 -1.016)
				)
				(arc
					(start 4.99999 -1.016)
					(mid 2.182884 -2.182884)
					(end 1.016 -4.99999)
				)
				(arc
					(start 1.016 -16.070072)
					(mid 1.597098 -17.472968)
					(end 2.999994 -18.054066)
				)
				(arc
					(start 9.600184 -18.054066)
					(mid 10.672157 -18.498039)
					(end 11.116056 -19.569938)
				)
				(arc
					(start 11.116056 -31.070042)
					(mid 10.671993 -32.141851)
					(end 9.600184 -32.585914)
				)
				(arc
					(start 2.999994 -32.585914)
					(mid 1.597098 -33.167012)
					(end 1.016 -34.569908)
				)
				(arc
					(start 1.016 -113.229898)
					(mid 1.597098 -114.632794)
					(end 2.999994 -115.213892)
				)
				(arc
					(start 9.59993 -115.213892)
					(mid 10.671993 -115.657955)
					(end 11.116056 -116.730018)
				)
				(arc
					(start 11.116056 -128.230122)
					(mid 10.672067 -129.302005)
					(end 9.600184 -129.745994)
				)
			)
		)
	)
	(zone
		(layers "F.Cu" "B.Cu" "In1.Cu" "In2.Cu" "In3.Cu" "In4.Cu" "In5.Cu" "In6.Cu"
			"In7.Cu" "In8.Cu"
		)
		(hatch none 0.5)
		(connect_pads
			(clearance 0)
		)
		(min_thickness 0.25)
		(keepout
			(tracks not_allowed)
			(vias allowed)
			(pads allowed)
			(copperpour not_allowed)
			(footprints allowed)
		)
		(placement
			(enabled no)
			(sheetname "")
		)
		(fill
			(thermal_gap 0.5)
			(thermal_bridge_width 0.5)
			(island_removal_mode 0)
		)
		(polygon
			(pts
				(xy 12.500102 2.199894) (xy 7.500112 2.199894) (xy 7.804912 2.504694) (xy 12.195302 2.504694)
			)
		)
	)
	(zone
		(layers "F.Cu" "B.Cu" "In1.Cu" "In2.Cu" "In3.Cu" "In4.Cu" "In5.Cu" "In6.Cu"
			"In7.Cu" "In8.Cu"
		)
		(name "Route Keepin")
		(hatch none 0.5)
		(connect_pads
			(clearance 0)
		)
		(min_thickness 0.25)
		(keepout
			(tracks allowed)
			(vias allowed)
			(pads allowed)
			(copperpour allowed)
			(footprints allowed)
		)
		(placement
			(enabled no)
			(sheetname "")
		)
		(fill
			(thermal_gap 0.5)
			(thermal_bridge_width 0.5)
			(island_removal_mode 0)
		)
		(polygon
			(pts
				(arc
					(start 10.608056 -128.230122)
					(mid 10.312857 -128.942795)
					(end 9.600184 -129.237994)
				)
				(arc
					(start 2.999994 -129.237994)
					(mid 1.237888 -129.967882)
					(end 0.508 -131.729988)
				)
				(arc
					(start 0.508 -141.99997)
					(mid 1.823673 -145.176287)
					(end 4.99999 -146.49196)
				)
				(xy 266.331954 -146.49196) (xy 266.331954 -149.200616) (xy 153.896822 -149.200616) (xy 152.729692 -150.367746)
				(xy 152.729692 -165.342824) (xy 154.028648 -166.64178) (xy 326.462898 -166.64178) (xy 327.630282 -165.474396)
				(xy 327.630282 -150.367238) (xy 326.37476 -149.111716) (xy 266.667488 -149.111716) (xy 266.667488 -146.49196)
				(arc
					(start 323.000116 -146.49196)
					(mid 326.176433 -145.176287)
					(end 327.492106 -141.99997)
				)
				(arc
					(start 327.492106 -4.99999)
					(mid 326.176433 -1.823673)
					(end 323.000116 -0.508)
				)
				(arc
					(start 4.99999 -0.508)
					(mid 1.823673 -1.823673)
					(end 0.508 -4.99999)
				)
				(arc
					(start 0.508 -16.070072)
					(mid 1.237888 -17.832178)
					(end 2.999994 -18.562066)
				)
				(arc
					(start 9.600184 -18.562066)
					(mid 10.312947 -18.857249)
					(end 10.608056 -19.569938)
				)
				(arc
					(start 10.608056 -31.070042)
					(mid 10.312783 -31.782641)
					(end 9.600184 -32.077914)
				)
				(arc
					(start 2.999994 -32.077914)
					(mid 1.237888 -32.807802)
					(end 0.508 -34.569908)
				)
				(arc
					(start 0.508 -113.229898)
					(mid 1.237888 -114.992004)
					(end 2.999994 -115.721892)
				)
				(arc
					(start 9.59993 -115.721892)
					(mid 10.312783 -116.017165)
					(end 10.608056 -116.730018)
				)
			)
		)
	)
	(zone
		(layers "F.Cu" "B.Cu" "In1.Cu" "In2.Cu" "In3.Cu" "In4.Cu" "In5.Cu" "In6.Cu"
			"In7.Cu" "In8.Cu"
		)
		(hatch none 0.5)
		(connect_pads
			(clearance 0)
		)
		(min_thickness 0.25)
		(keepout
			(tracks not_allowed)
			(vias allowed)
			(pads allowed)
			(copperpour not_allowed)
			(footprints allowed)
		)
		(placement
			(enabled no)
			(sheetname "")
		)
		(fill
			(thermal_gap 0.5)
			(thermal_bridge_width 0.5)
			(island_removal_mode 0)
		)
		(polygon
			(pts
				(xy 7.500112 -0.199898) (xy 12.500102 -0.199898) (xy 12.195302 -0.504698) (xy 7.804912 -0.504698)
			)
		)
	)
	(zone
		(layer "B.Cu")
		(hatch none 0.5)
		(connect_pads
			(clearance 0)
		)
		(min_thickness 0.25)
		(keepout
			(tracks not_allowed)
			(vias allowed)
			(pads allowed)
			(copperpour not_allowed)
			(footprints allowed)
		)
		(placement
			(enabled no)
			(sheetname "")
		)
		(fill
			(thermal_gap 0.5)
			(thermal_bridge_width 0.5)
			(island_removal_mode 0)
		)
		(polygon
			(pts
				(xy 32.599884 -128.729994) (xy 32.599884 -116.229892) (xy 10.100056 -116.229892) (xy 10.100056 -128.729994)
			)
		)
	)
	(zone
		(layer "B.Cu")
		(hatch none 0.5)
		(connect_pads
			(clearance 0)
		)
		(min_thickness 0.25)
		(keepout
			(tracks allowed)
			(vias allowed)
			(pads allowed)
			(copperpour allowed)
			(footprints not_allowed)
		)
		(placement
			(enabled no)
			(sheetname "")
		)
		(fill
			(thermal_gap 0.5)
			(thermal_bridge_width 0.5)
			(island_removal_mode 0)
		)
		(polygon
			(pts
				(arc
					(start 98.000058 -12.050014)
					(mid 100.946609 -19.088787)
					(end 108.000038 -21.999956)
				)
				(arc
					(start 129.999994 -21.999956)
					(mid 139.999974 -11.999976)
					(end 129.999994 -1.999996)
				)
				(arc
					(start 108.000038 -1.999996)
					(mid 100.946697 -4.911254)
					(end 98.000058 -11.949938)
				)
				(arc
					(start 103.000302 -11.949938)
					(mid 104.482249 -8.446805)
					(end 108.000038 -6.999986)
				)
				(arc
					(start 129.999994 -6.999986)
					(mid 134.999984 -11.999976)
					(end 129.999994 -16.999966)
				)
				(arc
					(start 108.000038 -16.999966)
					(mid 104.482247 -15.55315)
					(end 103.000302 -12.050014)
				)
			)
		)
	)
	(zone
		(layer "B.Cu")
		(hatch none 0.5)
		(connect_pads
			(clearance 0)
		)
		(min_thickness 0.25)
		(keepout
			(tracks allowed)
			(vias allowed)
			(pads allowed)
			(copperpour allowed)
			(footprints not_allowed)
		)
		(placement
			(enabled no)
			(sheetname "")
		)
		(fill
			(thermal_gap 0.5)
			(thermal_bridge_width 0.5)
			(island_removal_mode 0)
		)
		(polygon
			(pts
				(arc
					(start 7.999984 -130.999992)
					(mid 2.999994 -135.999982)
					(end 7.999984 -140.999972)
				)
				(arc
					(start 29.99994 -140.999972)
					(mid 34.99993 -135.999982)
					(end 29.99994 -130.999992)
				)
			)
		)
		(polygon
			(pts
				(arc
					(start 8.13181 -133.503416)
					(mid 5.49994 -135.999982)
					(end 8.13181 -138.496548)
				)
				(xy 26.999946 -137.500106)
				(arc
					(start 29.99994 -137.500106)
					(mid 31.49981 -136.000236)
					(end 29.99994 -134.500112)
				)
				(xy 26.999946 -134.500112)
			)
		)
	)
	(zone
		(layer "B.Cu")
		(hatch none 0.5)
		(connect_pads
			(clearance 0)
		)
		(min_thickness 0.25)
		(keepout
			(tracks not_allowed)
			(vias allowed)
			(pads allowed)
			(copperpour not_allowed)
			(footprints allowed)
		)
		(placement
			(enabled no)
			(sheetname "")
		)
		(fill
			(thermal_gap 0.5)
			(thermal_bridge_width 0.5)
			(island_removal_mode 0)
		)
		(polygon
			(pts
				(arc
					(start 8.000238 -4.500118)
					(mid 0.500126 -12.00023)
					(end 8.000238 -19.500088)
				)
				(arc
					(start 30.000194 -19.500088)
					(mid 37.500052 -12.00023)
					(end 30.000194 -4.500118)
				)
			)
		)
		(polygon
			(pts
				(arc
					(start 8.113776 -9.502648)
					(mid 5.50033 -11.999976)
					(end 8.113776 -14.497304)
				)
				(arc
					(start 30.068266 -13.498576)
					(mid 31.500086 -12.000224)
					(end 30.068266 -10.50163)
				)
			)
		)
	)
	(zone
		(layer "B.Cu")
		(hatch none 0.5)
		(connect_pads
			(clearance 0)
		)
		(min_thickness 0.25)
		(keepout
			(tracks allowed)
			(vias allowed)
			(pads allowed)
			(copperpour allowed)
			(footprints not_allowed)
		)
		(placement
			(enabled no)
			(sheetname "")
		)
		(fill
			(thermal_gap 0.5)
			(thermal_bridge_width 0.5)
			(island_removal_mode 0)
		)
		(polygon
			(pts
				(arc
					(start 314.999878 -137.48004)
					(mid 320.079878 -132.40004)
					(end 314.999878 -127.32004)
				)
				(arc
					(start 292.999922 -127.32004)
					(mid 287.919922 -132.40004)
					(end 292.999922 -137.48004)
				)
			)
		)
		(polygon
			(pts
				(arc
					(start 311.799986 -132.40004)
					(mid 315.000132 -135.600186)
					(end 318.200024 -132.40004)
				)
				(arc
					(start 318.200024 -132.40004)
					(mid 315.000132 -129.200148)
					(end 311.799986 -132.40004)
				)
			)
		)
	)
	(zone
		(layer "B.Cu")
		(hatch none 0.5)
		(connect_pads
			(clearance 0)
		)
		(min_thickness 0.25)
		(keepout
			(tracks allowed)
			(vias allowed)
			(pads allowed)
			(copperpour allowed)
			(footprints not_allowed)
		)
		(placement
			(enabled no)
			(sheetname "")
		)
		(fill
			(thermal_gap 0.5)
			(thermal_bridge_width 0.5)
			(island_removal_mode 0)
		)
		(polygon
			(pts
				(arc
					(start 0.999998 -4.99999)
					(mid 2.171569 -2.171569)
					(end 4.99999 -0.999998)
				)
				(xy 35.450018 -0.999998) (xy 35.450018 -11.500104)
				(arc
					(start 34.975038 -11.500104)
					(mid 33.354117 -8.291966)
					(end 29.99994 -6.999986)
				)
				(arc
					(start 7.999984 -6.999986)
					(mid 2.999994 -11.999976)
					(end 7.999984 -16.999966)
				)
				(arc
					(start 29.99994 -16.999966)
					(mid 33.354145 -15.708198)
					(end 34.975038 -12.500102)
				)
				(xy 35.450018 -12.500102) (xy 35.450018 -40.649906) (xy 15.260066 -40.649906) (xy 15.260066 -107.1499)
				(xy 35.450018 -107.1499) (xy 35.450018 -135.50011)
				(arc
					(start 34.975038 -135.50011)
					(mid 33.354117 -132.291972)
					(end 29.99994 -130.999992)
				)
				(arc
					(start 7.999984 -130.999992)
					(mid 2.999994 -135.999982)
					(end 7.999984 -140.999972)
				)
				(arc
					(start 29.99994 -140.999972)
					(mid 33.354145 -139.708204)
					(end 34.975038 -136.500108)
				)
				(xy 35.450018 -136.500108) (xy 35.450018 -145.999962)
				(arc
					(start 4.99999 -145.999962)
					(mid 2.171569 -144.828391)
					(end 0.999998 -141.99997)
				)
				(arc
					(start 0.999998 -131.729988)
					(mid 1.585783 -130.315777)
					(end 2.999994 -129.729992)
				)
				(arc
					(start 9.59993 -129.729992)
					(mid 10.660662 -129.29078)
					(end 11.100054 -128.230122)
				)
				(arc
					(start 11.100054 -116.730018)
					(mid 10.660678 -115.66927)
					(end 9.59993 -115.229894)
				)
				(arc
					(start 2.999994 -115.229894)
					(mid 1.585783 -114.644109)
					(end 0.999998 -113.229898)
				)
				(arc
					(start 0.999998 -34.569908)
					(mid 1.585783 -33.155697)
					(end 2.999994 -32.569912)
				)
				(arc
					(start 9.59993 -32.569912)
					(mid 10.660662 -32.1307)
					(end 11.100054 -31.070042)
				)
				(arc
					(start 11.100054 -19.569938)
					(mid 10.660573 -18.509444)
					(end 9.59993 -18.070068)
				)
				(arc
					(start 2.999994 -18.070068)
					(mid 1.585783 -17.484283)
					(end 0.999998 -16.070072)
				)
			)
		)
	)
	(zone
		(layer "B.Cu")
		(hatch none 0.5)
		(connect_pads
			(clearance 0)
		)
		(min_thickness 0.25)
		(keepout
			(tracks allowed)
			(vias allowed)
			(pads allowed)
			(copperpour allowed)
			(footprints not_allowed)
		)
		(placement
			(enabled no)
			(sheetname "")
		)
		(fill
			(thermal_gap 0.5)
			(thermal_bridge_width 0.5)
			(island_removal_mode 0)
		)
		(polygon
			(pts
				(arc
					(start 208.000092 -6.999986)
					(mid 203.000102 -11.999976)
					(end 208.000092 -16.999966)
				)
				(arc
					(start 230.000048 -16.999966)
					(mid 235.000038 -11.999976)
					(end 230.000048 -6.999986)
				)
			)
		)
		(polygon
			(pts
				(arc
					(start 208.131918 -9.50341)
					(mid 205.500048 -11.999976)
					(end 208.131918 -14.496542)
				)
				(xy 227.000054 -13.5001)
				(arc
					(start 230.000048 -13.5001)
					(mid 231.499918 -12.00023)
					(end 230.000048 -10.500106)
				)
				(xy 227.000054 -10.500106)
			)
		)
	)
	(zone
		(layer "B.Cu")
		(hatch none 0.5)
		(connect_pads
			(clearance 0)
		)
		(min_thickness 0.25)
		(keepout
			(tracks allowed)
			(vias allowed)
			(pads allowed)
			(copperpour allowed)
			(footprints not_allowed)
		)
		(placement
			(enabled no)
			(sheetname "")
		)
		(fill
			(thermal_gap 0.5)
			(thermal_bridge_width 0.5)
			(island_removal_mode 0)
		)
		(polygon
			(pts
				(xy 35.450018 -54.619906) (xy 198.250048 -54.619906) (xy 198.250048 -128.009904) (xy 35.450018 -128.009904)
			)
		)
		(polygon
			(pts
				(arc
					(start 49.230026 -120.40997)
					(mid 48.429926 -121.21007)
					(end 49.230026 -122.009916)
				)
				(arc
					(start 49.230026 -122.009916)
					(mid 50.029872 -121.21007)
					(end 49.230026 -120.40997)
				)
			)
		)
		(polygon
			(pts
				(arc
					(start 56.850026 -120.40997)
					(mid 56.049926 -121.21007)
					(end 56.850026 -122.009916)
				)
				(arc
					(start 56.850026 -122.009916)
					(mid 57.649872 -121.21007)
					(end 56.850026 -120.40997)
				)
			)
		)
		(polygon
			(pts
				(arc
					(start 64.470026 -120.40997)
					(mid 63.669926 -121.21007)
					(end 64.470026 -122.009916)
				)
				(arc
					(start 64.470026 -122.009916)
					(mid 65.269872 -121.21007)
					(end 64.470026 -120.40997)
				)
			)
		)
		(polygon
			(pts
				(arc
					(start 89.229946 -120.40997)
					(mid 88.429846 -121.21007)
					(end 89.229946 -122.009916)
				)
				(arc
					(start 89.229946 -122.009916)
					(mid 90.029792 -121.21007)
					(end 89.229946 -120.40997)
				)
			)
		)
		(polygon
			(pts
				(arc
					(start 96.849946 -120.40997)
					(mid 96.049846 -121.21007)
					(end 96.849946 -122.009916)
				)
				(arc
					(start 96.849946 -122.009916)
					(mid 97.649792 -121.21007)
					(end 96.849946 -120.40997)
				)
			)
		)
		(polygon
			(pts
				(arc
					(start 104.469946 -120.40997)
					(mid 103.669846 -121.21007)
					(end 104.469946 -122.009916)
				)
				(arc
					(start 104.469946 -122.009916)
					(mid 105.269792 -121.21007)
					(end 104.469946 -120.40997)
				)
			)
		)
		(polygon
			(pts
				(arc
					(start 129.23012 -120.40997)
					(mid 128.43002 -121.21007)
					(end 129.23012 -122.009916)
				)
				(arc
					(start 129.23012 -122.009916)
					(mid 130.029966 -121.21007)
					(end 129.23012 -120.40997)
				)
			)
		)
		(polygon
			(pts
				(arc
					(start 136.85012 -120.40997)
					(mid 136.05002 -121.21007)
					(end 136.85012 -122.009916)
				)
				(arc
					(start 136.85012 -122.009916)
					(mid 137.649966 -121.21007)
					(end 136.85012 -120.40997)
				)
			)
		)
		(polygon
			(pts
				(arc
					(start 144.47012 -120.40997)
					(mid 143.67002 -121.21007)
					(end 144.47012 -122.009916)
				)
				(arc
					(start 144.47012 -122.009916)
					(mid 145.269966 -121.21007)
					(end 144.47012 -120.40997)
				)
			)
		)
		(polygon
			(pts
				(arc
					(start 169.23004 -120.40997)
					(mid 168.42994 -121.21007)
					(end 169.23004 -122.009916)
				)
				(arc
					(start 169.23004 -122.009916)
					(mid 170.029886 -121.21007)
					(end 169.23004 -120.40997)
				)
			)
		)
		(polygon
			(pts
				(arc
					(start 176.85004 -120.40997)
					(mid 176.04994 -121.21007)
					(end 176.85004 -122.009916)
				)
				(arc
					(start 176.85004 -122.009916)
					(mid 177.649886 -121.21007)
					(end 176.85004 -120.40997)
				)
			)
		)
		(polygon
			(pts
				(arc
					(start 184.47004 -120.40997)
					(mid 183.66994 -121.21007)
					(end 184.47004 -122.009916)
				)
				(arc
					(start 184.47004 -122.009916)
					(mid 185.269886 -121.21007)
					(end 184.47004 -120.40997)
				)
			)
		)
		(polygon
			(pts
				(arc
					(start 165.42004 -69.360034)
					(mid 164.370004 -70.41007)
					(end 165.42004 -71.460106)
				)
				(arc
					(start 165.42004 -71.460106)
					(mid 166.470076 -70.41007)
					(end 165.42004 -69.360034)
				)
			)
		)
		(polygon
			(pts
				(arc
					(start 169.23004 -69.360034)
					(mid 168.180004 -70.41007)
					(end 169.23004 -71.460106)
				)
				(arc
					(start 169.23004 -71.460106)
					(mid 170.280076 -70.41007)
					(end 169.23004 -69.360034)
				)
			)
		)
		(polygon
			(pts
				(arc
					(start 184.47004 -69.360034)
					(mid 183.420004 -70.41007)
					(end 184.47004 -71.460106)
				)
				(arc
					(start 184.47004 -71.460106)
					(mid 185.520076 -70.41007)
					(end 184.47004 -69.360034)
				)
			)
		)
		(polygon
			(pts
				(arc
					(start 188.28004 -69.360034)
					(mid 187.230004 -70.41007)
					(end 188.28004 -71.460106)
				)
				(arc
					(start 188.28004 -71.460106)
					(mid 189.330076 -70.41007)
					(end 188.28004 -69.360034)
				)
			)
		)
		(polygon
			(pts
				(arc
					(start 148.28012 -71.460106)
					(mid 149.330156 -70.41007)
					(end 148.28012 -69.360034)
				)
				(arc
					(start 148.28012 -69.360034)
					(mid 147.230084 -70.41007)
					(end 148.28012 -71.460106)
				)
			)
		)
		(polygon
			(pts
				(arc
					(start 144.47012 -71.460106)
					(mid 145.520156 -70.41007)
					(end 144.47012 -69.360034)
				)
				(arc
					(start 144.47012 -69.360034)
					(mid 143.420084 -70.41007)
					(end 144.47012 -71.460106)
				)
			)
		)
		(polygon
			(pts
				(arc
					(start 129.23012 -71.460106)
					(mid 130.280156 -70.41007)
					(end 129.23012 -69.360034)
				)
				(arc
					(start 129.23012 -69.360034)
					(mid 128.180084 -70.41007)
					(end 129.23012 -71.460106)
				)
			)
		)
		(polygon
			(pts
				(arc
					(start 125.42012 -71.460106)
					(mid 126.470156 -70.41007)
					(end 125.42012 -69.360034)
				)
				(arc
					(start 125.42012 -69.360034)
					(mid 124.370084 -70.41007)
					(end 125.42012 -71.460106)
				)
			)
		)
		(polygon
			(pts
				(arc
					(start 108.279946 -69.360034)
					(mid 107.22991 -70.41007)
					(end 108.279946 -71.460106)
				)
				(arc
					(start 108.279946 -71.460106)
					(mid 109.329982 -70.41007)
					(end 108.279946 -69.360034)
				)
			)
		)
		(polygon
			(pts
				(arc
					(start 104.469946 -71.460106)
					(mid 105.519982 -70.41007)
					(end 104.469946 -69.360034)
				)
				(arc
					(start 104.469946 -69.360034)
					(mid 103.41991 -70.41007)
					(end 104.469946 -71.460106)
				)
			)
		)
		(polygon
			(pts
				(arc
					(start 89.229946 -71.460106)
					(mid 90.279982 -70.41007)
					(end 89.229946 -69.360034)
				)
				(arc
					(start 89.229946 -69.360034)
					(mid 88.17991 -70.41007)
					(end 89.229946 -71.460106)
				)
			)
		)
		(polygon
			(pts
				(arc
					(start 85.419946 -71.460106)
					(mid 86.469982 -70.41007)
					(end 85.419946 -69.360034)
				)
				(arc
					(start 85.419946 -69.360034)
					(mid 84.36991 -70.41007)
					(end 85.419946 -71.460106)
				)
			)
		)
		(polygon
			(pts
				(arc
					(start 68.280026 -71.460106)
					(mid 69.330062 -70.41007)
					(end 68.280026 -69.360034)
				)
				(arc
					(start 68.280026 -69.360034)
					(mid 67.22999 -70.41007)
					(end 68.280026 -71.460106)
				)
			)
		)
		(polygon
			(pts
				(arc
					(start 64.470026 -71.460106)
					(mid 65.520062 -70.41007)
					(end 64.470026 -69.360034)
				)
				(arc
					(start 64.470026 -69.360034)
					(mid 63.41999 -70.41007)
					(end 64.470026 -71.460106)
				)
			)
		)
		(polygon
			(pts
				(arc
					(start 49.230026 -71.460106)
					(mid 50.280062 -70.41007)
					(end 49.230026 -69.360034)
				)
				(arc
					(start 49.230026 -69.360034)
					(mid 48.17999 -70.41007)
					(end 49.230026 -71.460106)
				)
			)
		)
		(polygon
			(pts
				(arc
					(start 45.420026 -69.360034)
					(mid 44.36999 -70.41007)
					(end 45.420026 -71.460106)
				)
				(arc
					(start 45.420026 -71.460106)
					(mid 46.470062 -70.41007)
					(end 45.420026 -69.360034)
				)
			)
		)
	)
	(zone
		(layer "B.Cu")
		(hatch none 0.5)
		(connect_pads
			(clearance 0)
		)
		(min_thickness 0.25)
		(keepout
			(tracks allowed)
			(vias allowed)
			(pads allowed)
			(copperpour allowed)
			(footprints not_allowed)
		)
		(placement
			(enabled no)
			(sheetname "")
		)
		(fill
			(thermal_gap 0.5)
			(thermal_bridge_width 0.5)
			(island_removal_mode 0)
		)
		(polygon
			(pts
				(xy 254.674878 -23.64994) (xy 163.185094 -23.64994) (xy 163.185094 -44.630086) (xy 254.674878 -44.630086)
			)
		)
	)
	(zone
		(layer "B.Cu")
		(hatch none 0.5)
		(connect_pads
			(clearance 0)
		)
		(min_thickness 0.25)
		(keepout
			(tracks allowed)
			(vias allowed)
			(pads allowed)
			(copperpour allowed)
			(footprints not_allowed)
		)
		(placement
			(enabled no)
			(sheetname "")
		)
		(fill
			(thermal_gap 0.5)
			(thermal_bridge_width 0.5)
			(island_removal_mode 0)
		)
		(polygon
			(pts
				(arc
					(start 229.750112 -137.839958)
					(mid 232.696663 -144.878731)
					(end 239.750092 -147.7899)
				)
				(arc
					(start 261.750048 -147.7899)
					(mid 271.750028 -137.78992)
					(end 261.750048 -127.78994)
				)
				(arc
					(start 239.750092 -127.78994)
					(mid 232.696751 -130.701198)
					(end 229.750112 -137.739882)
				)
				(arc
					(start 234.750356 -137.739882)
					(mid 236.232303 -134.236749)
					(end 239.750092 -132.78993)
				)
				(arc
					(start 261.750048 -132.78993)
					(mid 266.750038 -137.78992)
					(end 261.750048 -142.78991)
				)
				(arc
					(start 239.750092 -142.78991)
					(mid 236.232301 -141.343094)
					(end 234.750356 -137.839958)
				)
			)
		)
	)
	(zone
		(layer "B.Cu")
		(hatch none 0.5)
		(connect_pads
			(clearance 0)
		)
		(min_thickness 0.25)
		(keepout
			(tracks allowed)
			(vias allowed)
			(pads allowed)
			(copperpour allowed)
			(footprints not_allowed)
		)
		(placement
			(enabled no)
			(sheetname "")
		)
		(fill
			(thermal_gap 0.5)
			(thermal_bridge_width 0.5)
			(island_removal_mode 0)
		)
		(polygon
			(pts
				(arc
					(start -1.999996 -136.05002)
					(mid 0.946555 -143.088793)
					(end 7.999984 -145.999962)
				)
				(arc
					(start 29.99994 -145.999962)
					(mid 39.99992 -135.999982)
					(end 29.99994 -126.000002)
				)
				(arc
					(start 7.999984 -126.000002)
					(mid 0.946643 -128.91126)
					(end -1.999996 -135.949944)
				)
				(arc
					(start 3.000248 -135.949944)
					(mid 4.482195 -132.446811)
					(end 7.999984 -130.999992)
				)
				(arc
					(start 29.99994 -130.999992)
					(mid 34.99993 -135.999982)
					(end 29.99994 -140.999972)
				)
				(arc
					(start 7.999984 -140.999972)
					(mid 4.482193 -139.553156)
					(end 3.000248 -136.05002)
				)
			)
		)
	)
	(zone
		(layer "B.Cu")
		(hatch none 0.5)
		(connect_pads
			(clearance 0)
		)
		(min_thickness 0.25)
		(keepout
			(tracks allowed)
			(vias allowed)
			(pads allowed)
			(copperpour allowed)
			(footprints not_allowed)
		)
		(placement
			(enabled no)
			(sheetname "")
		)
		(fill
			(thermal_gap 0.5)
			(thermal_bridge_width 0.5)
			(island_removal_mode 0)
		)
		(polygon
			(pts
				(arc
					(start 7.999984 -6.999986)
					(mid 2.999994 -11.999976)
					(end 7.999984 -16.999966)
				)
				(arc
					(start 29.99994 -16.999966)
					(mid 34.99993 -11.999976)
					(end 29.99994 -6.999986)
				)
			)
		)
		(polygon
			(pts
				(arc
					(start 8.13181 -9.50341)
					(mid 5.49994 -11.999976)
					(end 8.13181 -14.496542)
				)
				(xy 26.999946 -13.5001)
				(arc
					(start 29.99994 -13.5001)
					(mid 31.49981 -12.00023)
					(end 29.99994 -10.500106)
				)
				(xy 26.999946 -10.500106)
			)
		)
	)
	(zone
		(layer "B.Cu")
		(hatch none 0.5)
		(connect_pads
			(clearance 0)
		)
		(min_thickness 0.25)
		(keepout
			(tracks allowed)
			(vias allowed)
			(pads allowed)
			(copperpour allowed)
			(footprints not_allowed)
		)
		(placement
			(enabled no)
			(sheetname "")
		)
		(fill
			(thermal_gap 0.5)
			(thermal_bridge_width 0.5)
			(island_removal_mode 0)
		)
		(polygon
			(pts
				(xy 140.1699 -26.260044) (xy 57.570116 -26.260044) (xy 57.570116 -47.239936) (xy 140.1699 -47.239936)
			)
		)
	)
	(zone
		(layer "B.Cu")
		(hatch none 0.5)
		(connect_pads
			(clearance 0)
		)
		(min_thickness 0.25)
		(keepout
			(tracks allowed)
			(vias allowed)
			(pads allowed)
			(copperpour allowed)
			(footprints not_allowed)
		)
		(placement
			(enabled no)
			(sheetname "")
		)
		(fill
			(thermal_gap 0.5)
			(thermal_bridge_width 0.5)
			(island_removal_mode 0)
		)
		(polygon
			(pts
				(xy 327.000108 -38.515036) (xy 304.939954 -38.515036) (xy 304.939954 -107.244896) (xy 327.000108 -107.244896)
				(arc
					(start 327.000108 -141.99997)
					(mid 325.828537 -144.828391)
					(end 323.000116 -145.999962)
				)
				(arc
					(start 267.459206 -145.999962)
					(mid 271.292045 -134.798336)
					(end 261.750048 -127.78994)
				)
				(arc
					(start 239.750092 -127.78994)
					(mid 230.208111 -134.798231)
					(end 234.04068 -145.999962)
				)
				(xy 36.281106 -145.999962)
				(arc
					(start 36.281106 -143.781272)
					(mid 39.99867 -135.83023)
					(end 36.01339 -128.009904)
				)
				(xy 198.250048 -128.009904) (xy 198.250048 -54.619906) (xy 36.281106 -54.619906)
				(arc
					(start 36.281106 -19.781266)
					(mid 40.00011 -11.999976)
					(end 36.281106 -4.218686)
				)
				(xy 36.281106 -0.999998)
				(arc
					(start 323.000116 -0.999998)
					(mid 325.828537 -2.171569)
					(end 327.000108 -4.99999)
				)
			)
		)
		(polygon
			(pts
				(arc
					(start 251.100082 -67.900042)
					(mid 261.100062 -57.900062)
					(end 251.100082 -47.900082)
				)
				(arc
					(start 229.100126 -47.900082)
					(mid 219.100146 -57.900062)
					(end 229.100126 -67.900042)
				)
			)
		)
		(polygon
			(pts
				(arc
					(start 314.999878 -142.40002)
					(mid 324.999858 -132.40004)
					(end 314.999878 -122.40006)
				)
				(arc
					(start 292.999922 -122.40006)
					(mid 282.999942 -132.40004)
					(end 292.999922 -142.40002)
				)
			)
		)
		(polygon
			(pts
				(arc
					(start 292.999922 -4.59994)
					(mid 282.999942 -14.59992)
					(end 292.999922 -24.5999)
				)
				(arc
					(start 314.999878 -24.5999)
					(mid 324.999858 -14.59992)
					(end 314.999878 -4.59994)
				)
			)
		)
		(polygon
			(pts
				(arc
					(start 230.000048 -21.999956)
					(mid 240.000028 -11.999976)
					(end 230.000048 -1.999996)
				)
				(arc
					(start 208.000092 -1.999996)
					(mid 198.000112 -11.999976)
					(end 208.000092 -21.999956)
				)
			)
		)
		(polygon
			(pts
				(arc
					(start 129.999994 -21.999956)
					(mid 139.999974 -11.999976)
					(end 129.999994 -1.999996)
				)
				(arc
					(start 108.000038 -1.999996)
					(mid 98.000058 -11.999976)
					(end 108.000038 -21.999956)
				)
			)
		)
		(polygon
			(pts
				(xy 255.505966 -23.64994) (xy 164.015928 -23.64994) (xy 164.015928 -44.630086) (xy 255.505966 -44.630086)
			)
		)
		(polygon
			(pts
				(xy 141.000988 -26.260044) (xy 58.40095 -26.260044) (xy 58.40095 -47.239936) (xy 141.000988 -47.239936)
			)
		)
	)
	(zone
		(layer "B.Cu")
		(hatch none 0.5)
		(connect_pads
			(clearance 0)
		)
		(min_thickness 0.25)
		(keepout
			(tracks allowed)
			(vias allowed)
			(pads allowed)
			(copperpour allowed)
			(footprints not_allowed)
		)
		(placement
			(enabled no)
			(sheetname "")
		)
		(fill
			(thermal_gap 0.5)
			(thermal_bridge_width 0.5)
			(island_removal_mode 0)
		)
		(polygon
			(pts
				(arc
					(start 108.000038 -6.999986)
					(mid 103.000048 -11.999976)
					(end 108.000038 -16.999966)
				)
				(arc
					(start 129.999994 -16.999966)
					(mid 134.999984 -11.999976)
					(end 129.999994 -6.999986)
				)
			)
		)
		(polygon
			(pts
				(arc
					(start 108.131864 -9.50341)
					(mid 105.499994 -11.999976)
					(end 108.131864 -14.496542)
				)
				(xy 127 -13.5001)
				(arc
					(start 129.999994 -13.5001)
					(mid 131.499864 -12.00023)
					(end 129.999994 -10.500106)
				)
				(xy 127 -10.500106)
			)
		)
	)
	(zone
		(layer "B.Cu")
		(hatch none 0.5)
		(connect_pads
			(clearance 0)
		)
		(min_thickness 0.25)
		(keepout
			(tracks allowed)
			(vias allowed)
			(pads allowed)
			(copperpour allowed)
			(footprints not_allowed)
		)
		(placement
			(enabled no)
			(sheetname "")
		)
		(fill
			(thermal_gap 0.5)
			(thermal_bridge_width 0.5)
			(island_removal_mode 0)
		)
		(polygon
			(pts
				(xy 304.939954 -38.515036) (xy 327.000108 -38.515036) (xy 327.000108 -107.244896) (xy 304.939954 -107.244896)
			)
		)
	)
	(zone
		(layer "B.Cu")
		(hatch none 0.5)
		(connect_pads
			(clearance 0)
		)
		(min_thickness 0.25)
		(keepout
			(tracks allowed)
			(vias allowed)
			(pads allowed)
			(copperpour allowed)
			(footprints not_allowed)
		)
		(placement
			(enabled no)
			(sheetname "")
		)
		(fill
			(thermal_gap 0.5)
			(thermal_bridge_width 0.5)
			(island_removal_mode 0)
		)
		(polygon
			(pts
				(arc
					(start 198.000112 -12.050014)
					(mid 200.946663 -19.088787)
					(end 208.000092 -21.999956)
				)
				(arc
					(start 230.000048 -21.999956)
					(mid 240.000028 -11.999976)
					(end 230.000048 -1.999996)
				)
				(arc
					(start 208.000092 -1.999996)
					(mid 200.946751 -4.911254)
					(end 198.000112 -11.949938)
				)
				(arc
					(start 203.000356 -11.949938)
					(mid 204.482303 -8.446805)
					(end 208.000092 -6.999986)
				)
				(arc
					(start 230.000048 -6.999986)
					(mid 235.000038 -11.999976)
					(end 230.000048 -16.999966)
				)
				(arc
					(start 208.000092 -16.999966)
					(mid 204.482301 -15.55315)
					(end 203.000356 -12.050014)
				)
			)
		)
	)
	(zone
		(layer "B.Cu")
		(hatch none 0.5)
		(connect_pads
			(clearance 0)
		)
		(min_thickness 0.25)
		(keepout
			(tracks allowed)
			(vias allowed)
			(pads allowed)
			(copperpour allowed)
			(footprints not_allowed)
		)
		(placement
			(enabled no)
			(sheetname "")
		)
		(fill
			(thermal_gap 0.5)
			(thermal_bridge_width 0.5)
			(island_removal_mode 0)
		)
		(polygon
			(pts
				(arc
					(start 219.100146 -57.9501)
					(mid 222.046697 -64.988873)
					(end 229.100126 -67.900042)
				)
				(arc
					(start 251.100082 -67.900042)
					(mid 261.100062 -57.900062)
					(end 251.100082 -47.900082)
				)
				(arc
					(start 229.100126 -47.900082)
					(mid 222.046785 -50.81134)
					(end 219.100146 -57.850024)
				)
				(arc
					(start 224.100136 -57.850024)
					(mid 225.582174 -54.346801)
					(end 229.100126 -52.900072)
				)
				(arc
					(start 251.100082 -52.900072)
					(mid 256.100072 -57.900062)
					(end 251.100082 -62.900052)
				)
				(arc
					(start 229.100126 -62.900052)
					(mid 225.582171 -61.453325)
					(end 224.100136 -57.9501)
				)
			)
		)
	)
	(zone
		(layer "B.Cu")
		(hatch none 0.5)
		(connect_pads
			(clearance 0)
		)
		(min_thickness 0.25)
		(keepout
			(tracks allowed)
			(vias allowed)
			(pads allowed)
			(copperpour allowed)
			(footprints not_allowed)
		)
		(placement
			(enabled no)
			(sheetname "")
		)
		(fill
			(thermal_gap 0.5)
			(thermal_bridge_width 0.5)
			(island_removal_mode 0)
		)
		(polygon
			(pts
				(arc
					(start -1.999996 -12.050014)
					(mid 0.946555 -19.088787)
					(end 7.999984 -21.999956)
				)
				(arc
					(start 29.99994 -21.999956)
					(mid 39.99992 -11.999976)
					(end 29.99994 -1.999996)
				)
				(arc
					(start 7.999984 -1.999996)
					(mid 0.946643 -4.911254)
					(end -1.999996 -11.949938)
				)
				(arc
					(start 3.000248 -11.949938)
					(mid 4.482195 -8.446805)
					(end 7.999984 -6.999986)
				)
				(arc
					(start 29.99994 -6.999986)
					(mid 34.99993 -11.999976)
					(end 29.99994 -16.999966)
				)
				(arc
					(start 7.999984 -16.999966)
					(mid 4.482193 -15.55315)
					(end 3.000248 -12.050014)
				)
			)
		)
	)
	(zone
		(layer "B.Cu")
		(hatch none 0.5)
		(connect_pads
			(clearance 0)
		)
		(min_thickness 0.25)
		(keepout
			(tracks allowed)
			(vias allowed)
			(pads allowed)
			(copperpour allowed)
			(footprints not_allowed)
		)
		(placement
			(enabled no)
			(sheetname "")
		)
		(fill
			(thermal_gap 0.5)
			(thermal_bridge_width 0.5)
			(island_removal_mode 0)
		)
		(polygon
			(pts
				(arc
					(start 314.999878 -19.67992)
					(mid 320.079878 -14.59992)
					(end 314.999878 -9.51992)
				)
				(arc
					(start 292.999922 -9.51992)
					(mid 287.919922 -14.59992)
					(end 292.999922 -19.67992)
				)
			)
		)
		(polygon
			(pts
				(arc
					(start 311.799986 -14.59992)
					(mid 315.000132 -17.800066)
					(end 318.200024 -14.59992)
				)
				(arc
					(start 318.200024 -14.59992)
					(mid 315.000132 -11.400028)
					(end 311.799986 -14.59992)
				)
			)
		)
	)
	(zone
		(layer "B.Cu")
		(hatch none 0.5)
		(connect_pads
			(clearance 0)
		)
		(min_thickness 0.25)
		(keepout
			(tracks allowed)
			(vias allowed)
			(pads allowed)
			(copperpour allowed)
			(footprints not_allowed)
		)
		(placement
			(enabled no)
			(sheetname "")
		)
		(fill
			(thermal_gap 0.5)
			(thermal_bridge_width 0.5)
			(island_removal_mode 0)
		)
		(polygon
			(pts
				(arc
					(start 229.100126 -52.900072)
					(mid 224.100136 -57.900062)
					(end 229.100126 -62.900052)
				)
				(arc
					(start 251.100082 -62.900052)
					(mid 256.100072 -57.900062)
					(end 251.100082 -52.900072)
				)
			)
		)
		(polygon
			(pts
				(arc
					(start 229.231952 -55.403496)
					(mid 226.600082 -57.900062)
					(end 229.231952 -60.396628)
				)
				(xy 248.100088 -59.399932)
				(arc
					(start 251.100082 -59.399932)
					(mid 252.599952 -57.900062)
					(end 251.100082 -56.399938)
				)
				(xy 248.100088 -56.399938)
			)
		)
	)
	(zone
		(layer "B.Cu")
		(hatch none 0.5)
		(connect_pads
			(clearance 0)
		)
		(min_thickness 0.25)
		(keepout
			(tracks allowed)
			(vias allowed)
			(pads allowed)
			(copperpour allowed)
			(footprints not_allowed)
		)
		(placement
			(enabled no)
			(sheetname "")
		)
		(fill
			(thermal_gap 0.5)
			(thermal_bridge_width 0.5)
			(island_removal_mode 0)
		)
		(polygon
			(pts
				(xy 15.260066 -40.649906) (xy 35.450018 -40.649906) (xy 35.450018 -107.1499) (xy 15.260066 -107.1499)
			)
		)
	)
	(zone
		(layer "B.Cu")
		(hatch none 0.5)
		(connect_pads
			(clearance 0)
		)
		(min_thickness 0.25)
		(keepout
			(tracks allowed)
			(vias allowed)
			(pads allowed)
			(copperpour allowed)
			(footprints not_allowed)
		)
		(placement
			(enabled no)
			(sheetname "")
		)
		(fill
			(thermal_gap 0.5)
			(thermal_bridge_width 0.5)
			(island_removal_mode 0)
		)
		(polygon
			(pts
				(arc
					(start 239.750092 -132.78993)
					(mid 234.750102 -137.78992)
					(end 239.750092 -142.78991)
				)
				(arc
					(start 261.750048 -142.78991)
					(mid 266.750038 -137.78992)
					(end 261.750048 -132.78993)
				)
			)
		)
		(polygon
			(pts
				(arc
					(start 239.881918 -135.293354)
					(mid 237.250048 -137.78992)
					(end 239.881918 -140.286486)
				)
				(xy 258.750054 -139.290044)
				(arc
					(start 261.750048 -139.290044)
					(mid 263.249918 -137.790174)
					(end 261.750048 -136.29005)
				)
				(xy 258.750054 -136.29005)
			)
		)
	)
	(zone
		(layer "In1.Cu")
		(hatch none 0.5)
		(connect_pads
			(clearance 0)
		)
		(min_thickness 0.25)
		(keepout
			(tracks not_allowed)
			(vias allowed)
			(pads allowed)
			(copperpour not_allowed)
			(footprints allowed)
		)
		(placement
			(enabled no)
			(sheetname "")
		)
		(fill
			(thermal_gap 0.5)
			(thermal_bridge_width 0.5)
			(island_removal_mode 0)
		)
		(polygon
			(pts
				(arc
					(start 200.039986 -38.536626)
					(mid 200.556261 -39.128343)
					(end 201.309986 -39.348664)
				)
				(arc
					(start 201.309986 -39.348664)
					(mid 202.299251 -38.938897)
					(end 202.709018 -37.949632)
				)
				(arc
					(start 202.709018 -37.949632)
					(mid 202.488646 -37.19594)
					(end 201.89698 -36.679632)
				)
				(arc
					(start 201.89698 -36.679632)
					(mid 202.488697 -36.163357)
					(end 202.709018 -35.409632)
				)
				(arc
					(start 202.709018 -35.409632)
					(mid 202.488584 -34.655843)
					(end 201.896726 -34.139632)
				)
				(arc
					(start 201.896726 -34.139632)
					(mid 202.488546 -33.623397)
					(end 202.709018 -32.869632)
				)
				(arc
					(start 202.709018 -32.869632)
					(mid 202.488646 -32.11594)
					(end 201.89698 -31.599632)
				)
				(arc
					(start 201.89698 -31.599632)
					(mid 202.488697 -31.083357)
					(end 202.709018 -30.329632)
				)
				(arc
					(start 202.709018 -30.329632)
					(mid 202.299251 -29.340367)
					(end 201.309986 -28.9306)
				)
				(arc
					(start 201.309986 -28.9306)
					(mid 200.556294 -29.150972)
					(end 200.039986 -29.742638)
				)
				(arc
					(start 200.039986 -29.742638)
					(mid 199.523711 -29.150921)
					(end 198.769986 -28.9306)
				)
				(arc
					(start 198.769986 -28.9306)
					(mid 197.780721 -29.340367)
					(end 197.370954 -30.329632)
				)
				(arc
					(start 197.370954 -30.329632)
					(mid 197.591388 -31.083421)
					(end 198.183246 -31.599632)
				)
				(arc
					(start 198.183246 -31.599632)
					(mid 197.591426 -32.115867)
					(end 197.370954 -32.869632)
				)
				(arc
					(start 197.370954 -32.869632)
					(mid 197.591388 -33.623421)
					(end 198.183246 -34.139632)
				)
				(arc
					(start 198.183246 -34.139632)
					(mid 197.591426 -34.655867)
					(end 197.370954 -35.409632)
				)
				(arc
					(start 197.370954 -35.409632)
					(mid 197.591326 -36.163324)
					(end 198.182992 -36.679632)
				)
				(arc
					(start 198.182992 -36.679632)
					(mid 197.591275 -37.195907)
					(end 197.370954 -37.949632)
				)
				(arc
					(start 197.370954 -37.949632)
					(mid 197.780721 -38.938897)
					(end 198.769986 -39.348664)
				)
				(arc
					(start 198.769986 -39.348664)
					(mid 199.523678 -39.128292)
					(end 200.039986 -38.536626)
				)
			)
		)
	)
	(zone
		(layer "In1.Cu")
		(hatch none 0.5)
		(connect_pads
			(clearance 0)
		)
		(min_thickness 0.25)
		(keepout
			(tracks not_allowed)
			(vias allowed)
			(pads allowed)
			(copperpour not_allowed)
			(footprints allowed)
		)
		(placement
			(enabled no)
			(sheetname "")
		)
		(fill
			(thermal_gap 0.5)
			(thermal_bridge_width 0.5)
			(island_removal_mode 0)
		)
		(polygon
			(pts
				(arc
					(start 103.315008 -41.14673)
					(mid 103.831243 -41.73855)
					(end 104.585008 -41.959022)
				)
				(arc
					(start 104.585008 -41.959022)
					(mid 105.574273 -41.549255)
					(end 105.98404 -40.55999)
				)
				(arc
					(start 105.98404 -40.55999)
					(mid 105.763606 -39.806201)
					(end 105.171748 -39.28999)
				)
				(arc
					(start 105.171748 -39.28999)
					(mid 105.763568 -38.773755)
					(end 105.98404 -38.01999)
				)
				(arc
					(start 105.98404 -38.01999)
					(mid 105.763606 -37.266201)
					(end 105.171748 -36.74999)
				)
				(arc
					(start 105.171748 -36.74999)
					(mid 105.763568 -36.233755)
					(end 105.98404 -35.47999)
				)
				(arc
					(start 105.98404 -35.47999)
					(mid 105.763606 -34.726201)
					(end 105.171748 -34.20999)
				)
				(arc
					(start 105.171748 -34.20999)
					(mid 105.763568 -33.693755)
					(end 105.98404 -32.93999)
				)
				(arc
					(start 105.98404 -32.93999)
					(mid 105.574273 -31.950725)
					(end 104.585008 -31.540958)
				)
				(arc
					(start 104.585008 -31.540958)
					(mid 103.831219 -31.761392)
					(end 103.315008 -32.35325)
				)
				(arc
					(start 103.315008 -32.35325)
					(mid 102.798773 -31.76143)
					(end 102.045008 -31.540958)
				)
				(arc
					(start 102.045008 -31.540958)
					(mid 101.055743 -31.950725)
					(end 100.645976 -32.93999)
				)
				(arc
					(start 100.645976 -32.93999)
					(mid 100.86641 -33.693779)
					(end 101.458268 -34.20999)
				)
				(arc
					(start 101.458268 -34.20999)
					(mid 100.866448 -34.726225)
					(end 100.645976 -35.47999)
				)
				(arc
					(start 100.645976 -35.47999)
					(mid 100.86641 -36.233779)
					(end 101.458268 -36.74999)
				)
				(arc
					(start 101.458268 -36.74999)
					(mid 100.646021 -38.01999)
					(end 101.458268 -39.28999)
				)
				(arc
					(start 101.458268 -39.28999)
					(mid 100.866448 -39.806225)
					(end 100.645976 -40.55999)
				)
				(arc
					(start 100.645976 -40.55999)
					(mid 101.055743 -41.549255)
					(end 102.045008 -41.959022)
				)
				(arc
					(start 102.045008 -41.959022)
					(mid 102.798797 -41.738588)
					(end 103.315008 -41.14673)
				)
			)
		)
	)
	(zone
		(layer "In1.Cu")
		(hatch none 0.5)
		(connect_pads
			(clearance 0)
		)
		(min_thickness 0.25)
		(keepout
			(tracks not_allowed)
			(vias allowed)
			(pads allowed)
			(copperpour not_allowed)
			(footprints allowed)
		)
		(placement
			(enabled no)
			(sheetname "")
		)
		(fill
			(thermal_gap 0.5)
			(thermal_bridge_width 0.5)
			(island_removal_mode 0)
		)
		(polygon
			(pts
				(arc
					(start 121.095008 -41.14673)
					(mid 121.611243 -41.73855)
					(end 122.365008 -41.959022)
				)
				(arc
					(start 122.365008 -41.959022)
					(mid 123.354273 -41.549255)
					(end 123.76404 -40.55999)
				)
				(arc
					(start 123.76404 -40.55999)
					(mid 123.543668 -39.806298)
					(end 122.952002 -39.28999)
				)
				(arc
					(start 122.952002 -39.28999)
					(mid 123.543719 -38.773715)
					(end 123.76404 -38.01999)
				)
				(arc
					(start 123.76404 -38.01999)
					(mid 123.543606 -37.266201)
					(end 122.951748 -36.74999)
				)
				(arc
					(start 122.951748 -36.74999)
					(mid 123.543568 -36.233755)
					(end 123.76404 -35.47999)
				)
				(arc
					(start 123.76404 -35.47999)
					(mid 123.543668 -34.726298)
					(end 122.952002 -34.20999)
				)
				(arc
					(start 122.952002 -34.20999)
					(mid 123.543719 -33.693715)
					(end 123.76404 -32.93999)
				)
				(arc
					(start 123.76404 -32.93999)
					(mid 123.354273 -31.950725)
					(end 122.365008 -31.540958)
				)
				(arc
					(start 122.365008 -31.540958)
					(mid 121.611316 -31.76133)
					(end 121.095008 -32.352996)
				)
				(arc
					(start 121.095008 -32.352996)
					(mid 120.578733 -31.761279)
					(end 119.825008 -31.540958)
				)
				(arc
					(start 119.825008 -31.540958)
					(mid 118.835743 -31.950725)
					(end 118.425976 -32.93999)
				)
				(arc
					(start 118.425976 -32.93999)
					(mid 118.64641 -33.693779)
					(end 119.238268 -34.20999)
				)
				(arc
					(start 119.238268 -34.20999)
					(mid 118.426021 -35.47999)
					(end 119.238268 -36.74999)
				)
				(arc
					(start 119.238268 -36.74999)
					(mid 118.426021 -38.01999)
					(end 119.238268 -39.28999)
				)
				(arc
					(start 119.238268 -39.28999)
					(mid 118.646448 -39.806225)
					(end 118.425976 -40.55999)
				)
				(arc
					(start 118.425976 -40.55999)
					(mid 118.835743 -41.549255)
					(end 119.825008 -41.959022)
				)
				(arc
					(start 119.825008 -41.959022)
					(mid 120.578797 -41.738588)
					(end 121.095008 -41.14673)
				)
			)
		)
	)
	(zone
		(layer "In1.Cu")
		(hatch none 0.5)
		(connect_pads
			(clearance 0)
		)
		(min_thickness 0.25)
		(keepout
			(tracks not_allowed)
			(vias allowed)
			(pads allowed)
			(copperpour not_allowed)
			(footprints allowed)
		)
		(placement
			(enabled no)
			(sheetname "")
		)
		(fill
			(thermal_gap 0.5)
			(thermal_bridge_width 0.5)
			(island_removal_mode 0)
		)
		(polygon
			(pts
				(arc
					(start 191.149986 -38.536626)
					(mid 191.666261 -39.128343)
					(end 192.419986 -39.348664)
				)
				(arc
					(start 192.419986 -39.348664)
					(mid 193.409251 -38.938897)
					(end 193.819018 -37.949632)
				)
				(arc
					(start 193.819018 -37.949632)
					(mid 193.598584 -37.195843)
					(end 193.006726 -36.679632)
				)
				(arc
					(start 193.006726 -36.679632)
					(mid 193.598546 -36.163397)
					(end 193.819018 -35.409632)
				)
				(arc
					(start 193.819018 -35.409632)
					(mid 193.598646 -34.65594)
					(end 193.00698 -34.139632)
				)
				(arc
					(start 193.00698 -34.139632)
					(mid 193.598697 -33.623357)
					(end 193.819018 -32.869632)
				)
				(arc
					(start 193.819018 -32.869632)
					(mid 193.598584 -32.115843)
					(end 193.006726 -31.599632)
				)
				(arc
					(start 193.006726 -31.599632)
					(mid 193.598546 -31.083397)
					(end 193.819018 -30.329632)
				)
				(arc
					(start 193.819018 -30.329632)
					(mid 193.409251 -29.340367)
					(end 192.419986 -28.9306)
				)
				(arc
					(start 192.419986 -28.9306)
					(mid 191.666197 -29.151034)
					(end 191.149986 -29.742892)
				)
				(arc
					(start 191.149986 -29.742892)
					(mid 190.633751 -29.151072)
					(end 189.879986 -28.9306)
				)
				(arc
					(start 189.879986 -28.9306)
					(mid 188.890721 -29.340367)
					(end 188.480954 -30.329632)
				)
				(arc
					(start 188.480954 -30.329632)
					(mid 188.701388 -31.083421)
					(end 189.293246 -31.599632)
				)
				(arc
					(start 189.293246 -31.599632)
					(mid 188.480999 -32.869632)
					(end 189.293246 -34.139632)
				)
				(arc
					(start 189.293246 -34.139632)
					(mid 188.480999 -35.409632)
					(end 189.293246 -36.679632)
				)
				(arc
					(start 189.293246 -36.679632)
					(mid 188.701426 -37.195867)
					(end 188.480954 -37.949632)
				)
				(arc
					(start 188.480954 -37.949632)
					(mid 188.890721 -38.938897)
					(end 189.879986 -39.348664)
				)
				(arc
					(start 189.879986 -39.348664)
					(mid 190.633678 -39.128292)
					(end 191.149986 -38.536626)
				)
			)
		)
	)
	(zone
		(layer "In1.Cu")
		(hatch none 0.5)
		(connect_pads
			(clearance 0)
		)
		(min_thickness 0.25)
		(keepout
			(tracks not_allowed)
			(vias allowed)
			(pads allowed)
			(copperpour not_allowed)
			(footprints allowed)
		)
		(placement
			(enabled no)
			(sheetname "")
		)
		(fill
			(thermal_gap 0.5)
			(thermal_bridge_width 0.5)
			(island_removal_mode 0)
		)
		(polygon
			(pts
				(arc
					(start 112.205008 -41.14673)
					(mid 112.721243 -41.73855)
					(end 113.475008 -41.959022)
				)
				(arc
					(start 113.475008 -41.959022)
					(mid 114.464273 -41.549255)
					(end 114.87404 -40.55999)
				)
				(arc
					(start 114.87404 -40.55999)
					(mid 114.653606 -39.806201)
					(end 114.061748 -39.28999)
				)
				(arc
					(start 114.061748 -39.28999)
					(mid 114.873995 -38.01999)
					(end 114.061748 -36.74999)
				)
				(arc
					(start 114.061748 -36.74999)
					(mid 114.653568 -36.233755)
					(end 114.87404 -35.47999)
				)
				(arc
					(start 114.87404 -35.47999)
					(mid 114.653606 -34.726201)
					(end 114.061748 -34.20999)
				)
				(arc
					(start 114.061748 -34.20999)
					(mid 114.653568 -33.693755)
					(end 114.87404 -32.93999)
				)
				(arc
					(start 114.87404 -32.93999)
					(mid 114.464273 -31.950725)
					(end 113.475008 -31.540958)
				)
				(arc
					(start 113.475008 -31.540958)
					(mid 112.721219 -31.761392)
					(end 112.205008 -32.35325)
				)
				(arc
					(start 112.205008 -32.35325)
					(mid 111.688773 -31.76143)
					(end 110.935008 -31.540958)
				)
				(arc
					(start 110.935008 -31.540958)
					(mid 109.945743 -31.950725)
					(end 109.535976 -32.93999)
				)
				(arc
					(start 109.535976 -32.93999)
					(mid 109.75641 -33.693779)
					(end 110.348268 -34.20999)
				)
				(arc
					(start 110.348268 -34.20999)
					(mid 109.756448 -34.726225)
					(end 109.535976 -35.47999)
				)
				(arc
					(start 109.535976 -35.47999)
					(mid 109.75641 -36.233779)
					(end 110.348268 -36.74999)
				)
				(arc
					(start 110.348268 -36.74999)
					(mid 109.536021 -38.01999)
					(end 110.348268 -39.28999)
				)
				(arc
					(start 110.348268 -39.28999)
					(mid 109.756448 -39.806225)
					(end 109.535976 -40.55999)
				)
				(arc
					(start 109.535976 -40.55999)
					(mid 109.945743 -41.549255)
					(end 110.935008 -41.959022)
				)
				(arc
					(start 110.935008 -41.959022)
					(mid 111.688797 -41.738588)
					(end 112.205008 -41.14673)
				)
			)
		)
	)
	(zone
		(layer "In1.Cu")
		(hatch none 0.5)
		(connect_pads
			(clearance 0)
		)
		(min_thickness 0.25)
		(keepout
			(tracks not_allowed)
			(vias allowed)
			(pads allowed)
			(copperpour not_allowed)
			(footprints allowed)
		)
		(placement
			(enabled no)
			(sheetname "")
		)
		(fill
			(thermal_gap 0.5)
			(thermal_bridge_width 0.5)
			(island_removal_mode 0)
		)
		(polygon
			(pts
				(arc
					(start 182.259986 -38.536372)
					(mid 182.776221 -39.128192)
					(end 183.529986 -39.348664)
				)
				(arc
					(start 183.529986 -39.348664)
					(mid 184.519251 -38.938897)
					(end 184.929018 -37.949632)
				)
				(arc
					(start 184.929018 -37.949632)
					(mid 184.708584 -37.195843)
					(end 184.116726 -36.679632)
				)
				(arc
					(start 184.116726 -36.679632)
					(mid 184.928973 -35.409632)
					(end 184.116726 -34.139632)
				)
				(arc
					(start 184.116726 -34.139632)
					(mid 184.928973 -32.869632)
					(end 184.116726 -31.599632)
				)
				(arc
					(start 184.116726 -31.599632)
					(mid 184.708546 -31.083397)
					(end 184.929018 -30.329632)
				)
				(arc
					(start 184.929018 -30.329632)
					(mid 184.519251 -29.340367)
					(end 183.529986 -28.9306)
				)
				(arc
					(start 183.529986 -28.9306)
					(mid 182.776197 -29.151034)
					(end 182.259986 -29.742892)
				)
				(arc
					(start 182.259986 -29.742892)
					(mid 181.743751 -29.151072)
					(end 180.989986 -28.9306)
				)
				(arc
					(start 180.989986 -28.9306)
					(mid 180.000721 -29.340367)
					(end 179.590954 -30.329632)
				)
				(arc
					(start 179.590954 -30.329632)
					(mid 179.811388 -31.083421)
					(end 180.403246 -31.599632)
				)
				(arc
					(start 180.403246 -31.599632)
					(mid 179.590999 -32.869632)
					(end 180.403246 -34.139632)
				)
				(arc
					(start 180.403246 -34.139632)
					(mid 179.590999 -35.409632)
					(end 180.403246 -36.679632)
				)
				(arc
					(start 180.403246 -36.679632)
					(mid 179.811426 -37.195867)
					(end 179.590954 -37.949632)
				)
				(arc
					(start 179.590954 -37.949632)
					(mid 180.000721 -38.938897)
					(end 180.989986 -39.348664)
				)
				(arc
					(start 180.989986 -39.348664)
					(mid 181.743775 -39.12823)
					(end 182.259986 -38.536372)
				)
			)
		)
	)
	(zone
		(layers "In1.Cu" "In3.Cu" "In4.Cu" "In5.Cu" "In6.Cu")
		(hatch none 0.5)
		(connect_pads
			(clearance 0)
		)
		(min_thickness 0.25)
		(keepout
			(tracks not_allowed)
			(vias allowed)
			(pads allowed)
			(copperpour not_allowed)
			(footprints allowed)
		)
		(placement
			(enabled no)
			(sheetname "")
		)
		(fill yes
			(thermal_gap 0.5)
			(thermal_bridge_width 0.5)
			(island_removal_mode 0)
		)
		(polygon
			(pts
				(arc
					(start 13.66012 -83.749896)
					(mid 11.12012 -83.749896)
					(end 13.66012 -83.749896)
				)
			)
		)
	)
	(zone
		(layers "In1.Cu" "In3.Cu" "In4.Cu" "In5.Cu" "In6.Cu")
		(hatch none 0.5)
		(connect_pads
			(clearance 0)
		)
		(min_thickness 0.25)
		(keepout
			(tracks not_allowed)
			(vias allowed)
			(pads allowed)
			(copperpour not_allowed)
			(footprints allowed)
		)
		(placement
			(enabled no)
			(sheetname "")
		)
		(fill yes
			(thermal_gap 0.5)
			(thermal_bridge_width 0.5)
			(island_removal_mode 0)
		)
		(polygon
			(pts
				(arc
					(start 13.66012 -88.829896)
					(mid 11.12012 -88.829896)
					(end 13.66012 -88.829896)
				)
			)
		)
	)
	(zone
		(layers "In1.Cu" "In3.Cu" "In4.Cu" "In5.Cu" "In6.Cu")
		(hatch none 0.5)
		(connect_pads
			(clearance 0)
		)
		(min_thickness 0.25)
		(keepout
			(tracks not_allowed)
			(vias allowed)
			(pads allowed)
			(copperpour not_allowed)
			(footprints allowed)
		)
		(placement
			(enabled no)
			(sheetname "")
		)
		(fill yes
			(thermal_gap 0.5)
			(thermal_bridge_width 0.5)
			(island_removal_mode 0)
		)
		(polygon
			(pts
				(arc
					(start 12.39012 -87.559896)
					(mid 9.85012 -87.559896)
					(end 12.39012 -87.559896)
				)
			)
		)
	)
	(zone
		(layers "In1.Cu" "In3.Cu" "In4.Cu" "In5.Cu" "In6.Cu" "In8.Cu")
		(hatch none 0.5)
		(connect_pads
			(clearance 0)
		)
		(min_thickness 0.25)
		(keepout
			(tracks not_allowed)
			(vias allowed)
			(pads allowed)
			(copperpour not_allowed)
			(footprints allowed)
		)
		(placement
			(enabled no)
			(sheetname "")
		)
		(fill yes
			(thermal_gap 0.5)
			(thermal_bridge_width 0.5)
			(island_removal_mode 0)
		)
		(polygon
			(pts
				(arc
					(start 40.21836 -62.16142)
					(mid 38.44036 -62.16142)
					(end 40.21836 -62.16142)
				)
			)
		)
	)
	(zone
		(layers "In1.Cu" "In3.Cu" "In4.Cu" "In5.Cu" "In6.Cu" "In8.Cu")
		(hatch none 0.5)
		(connect_pads
			(clearance 0)
		)
		(min_thickness 0.25)
		(keepout
			(tracks not_allowed)
			(vias allowed)
			(pads allowed)
			(copperpour not_allowed)
			(footprints allowed)
		)
		(placement
			(enabled no)
			(sheetname "")
		)
		(fill yes
			(thermal_gap 0.5)
			(thermal_bridge_width 0.5)
			(island_removal_mode 0)
		)
		(polygon
			(pts
				(arc
					(start 293.695374 -42.092626)
					(mid 291.917374 -42.092626)
					(end 293.695374 -42.092626)
				)
			)
		)
	)
	(zone
		(layers "In1.Cu" "In3.Cu" "In4.Cu" "In5.Cu" "In6.Cu" "In8.Cu")
		(hatch none 0.5)
		(connect_pads
			(clearance 0)
		)
		(min_thickness 0.25)
		(keepout
			(tracks not_allowed)
			(vias allowed)
			(pads allowed)
			(copperpour not_allowed)
			(footprints allowed)
		)
		(placement
			(enabled no)
			(sheetname "")
		)
		(fill yes
			(thermal_gap 0.5)
			(thermal_bridge_width 0.5)
			(island_removal_mode 0)
		)
		(polygon
			(pts
				(arc
					(start 39.581836 -57.547002)
					(mid 37.803836 -57.547002)
					(end 39.581836 -57.547002)
				)
			)
		)
	)
	(zone
		(layers "In1.Cu" "In3.Cu" "In4.Cu" "In5.Cu" "In6.Cu" "In8.Cu")
		(hatch none 0.5)
		(connect_pads
			(clearance 0)
		)
		(min_thickness 0.25)
		(keepout
			(tracks not_allowed)
			(vias allowed)
			(pads allowed)
			(copperpour not_allowed)
			(footprints allowed)
		)
		(placement
			(enabled no)
			(sheetname "")
		)
		(fill yes
			(thermal_gap 0.5)
			(thermal_bridge_width 0.5)
			(island_removal_mode 0)
		)
		(polygon
			(pts
				(arc
					(start 39.581836 -58.436002)
					(mid 37.803836 -58.436002)
					(end 39.581836 -58.436002)
				)
			)
		)
	)
	(zone
		(layers "In1.Cu" "In3.Cu" "In4.Cu" "In5.Cu" "In6.Cu" "In8.Cu")
		(hatch none 0.5)
		(connect_pads
			(clearance 0)
		)
		(min_thickness 0.25)
		(keepout
			(tracks not_allowed)
			(vias allowed)
			(pads allowed)
			(copperpour not_allowed)
			(footprints allowed)
		)
		(placement
			(enabled no)
			(sheetname "")
		)
		(fill yes
			(thermal_gap 0.5)
			(thermal_bridge_width 0.5)
			(island_removal_mode 0)
		)
		(polygon
			(pts
				(arc
					(start 39.150036 -55.642002)
					(mid 37.372036 -55.642002)
					(end 39.150036 -55.642002)
				)
			)
		)
	)
	(zone
		(layers "In1.Cu" "In3.Cu" "In4.Cu" "In5.Cu" "In6.Cu" "In8.Cu")
		(hatch none 0.5)
		(connect_pads
			(clearance 0)
		)
		(min_thickness 0.25)
		(keepout
			(tracks not_allowed)
			(vias allowed)
			(pads allowed)
			(copperpour not_allowed)
			(footprints allowed)
		)
		(placement
			(enabled no)
			(sheetname "")
		)
		(fill yes
			(thermal_gap 0.5)
			(thermal_bridge_width 0.5)
			(island_removal_mode 0)
		)
		(polygon
			(pts
				(arc
					(start 28.4734 -64.91224)
					(mid 26.6954 -64.91224)
					(end 28.4734 -64.91224)
				)
			)
		)
	)
	(zone
		(layers "In1.Cu" "In3.Cu" "In4.Cu" "In5.Cu" "In6.Cu" "In8.Cu")
		(hatch none 0.5)
		(connect_pads
			(clearance 0)
		)
		(min_thickness 0.25)
		(keepout
			(tracks not_allowed)
			(vias allowed)
			(pads allowed)
			(copperpour not_allowed)
			(footprints allowed)
		)
		(placement
			(enabled no)
			(sheetname "")
		)
		(fill yes
			(thermal_gap 0.5)
			(thermal_bridge_width 0.5)
			(island_removal_mode 0)
		)
		(polygon
			(pts
				(arc
					(start 290.534344 -46.62424)
					(mid 288.756344 -46.62424)
					(end 290.534344 -46.62424)
				)
			)
		)
	)
	(zone
		(layers "In1.Cu" "In3.Cu" "In4.Cu" "In5.Cu" "In6.Cu" "In8.Cu")
		(hatch none 0.5)
		(connect_pads
			(clearance 0)
		)
		(min_thickness 0.25)
		(keepout
			(tracks not_allowed)
			(vias allowed)
			(pads allowed)
			(copperpour not_allowed)
			(footprints allowed)
		)
		(placement
			(enabled no)
			(sheetname "")
		)
		(fill yes
			(thermal_gap 0.5)
			(thermal_bridge_width 0.5)
			(island_removal_mode 0)
		)
		(polygon
			(pts
				(arc
					(start 312.809128 -72.879966)
					(mid 310.011064 -72.879966)
					(end 312.809128 -72.879966)
				)
			)
		)
	)
	(zone
		(layers "In1.Cu" "In3.Cu" "In4.Cu" "In5.Cu" "In6.Cu" "In8.Cu")
		(hatch none 0.5)
		(connect_pads
			(clearance 0)
		)
		(min_thickness 0.25)
		(keepout
			(tracks not_allowed)
			(vias allowed)
			(pads allowed)
			(copperpour not_allowed)
			(footprints allowed)
		)
		(placement
			(enabled no)
			(sheetname "")
		)
		(fill yes
			(thermal_gap 0.5)
			(thermal_bridge_width 0.5)
			(island_removal_mode 0)
		)
		(polygon
			(pts
				(arc
					(start 143.739108 -77.71765)
					(mid 141.961108 -77.71765)
					(end 143.739108 -77.71765)
				)
			)
		)
	)
	(zone
		(layers "In1.Cu" "In3.Cu" "In4.Cu" "In5.Cu" "In6.Cu" "In8.Cu")
		(hatch none 0.5)
		(connect_pads
			(clearance 0)
		)
		(min_thickness 0.25)
		(keepout
			(tracks not_allowed)
			(vias allowed)
			(pads allowed)
			(copperpour not_allowed)
			(footprints allowed)
		)
		(placement
			(enabled no)
			(sheetname "")
		)
		(fill yes
			(thermal_gap 0.5)
			(thermal_bridge_width 0.5)
			(island_removal_mode 0)
		)
		(polygon
			(pts
				(arc
					(start 28.4734 -66.43624)
					(mid 26.6954 -66.43624)
					(end 28.4734 -66.43624)
				)
			)
		)
	)
	(zone
		(layers "In1.Cu" "In3.Cu" "In4.Cu" "In5.Cu" "In6.Cu" "In8.Cu")
		(hatch none 0.5)
		(connect_pads
			(clearance 0)
		)
		(min_thickness 0.25)
		(keepout
			(tracks not_allowed)
			(vias allowed)
			(pads allowed)
			(copperpour not_allowed)
			(footprints allowed)
		)
		(placement
			(enabled no)
			(sheetname "")
		)
		(fill yes
			(thermal_gap 0.5)
			(thermal_bridge_width 0.5)
			(island_removal_mode 0)
		)
		(polygon
			(pts
				(arc
					(start 260.477 -43.4848)
					(mid 258.699 -43.4848)
					(end 260.477 -43.4848)
				)
			)
		)
	)
	(zone
		(layers "In1.Cu" "In3.Cu" "In4.Cu" "In5.Cu" "In6.Cu" "In8.Cu")
		(hatch none 0.5)
		(connect_pads
			(clearance 0)
		)
		(min_thickness 0.25)
		(keepout
			(tracks not_allowed)
			(vias allowed)
			(pads allowed)
			(copperpour not_allowed)
			(footprints allowed)
		)
		(placement
			(enabled no)
			(sheetname "")
		)
		(fill yes
			(thermal_gap 0.5)
			(thermal_bridge_width 0.5)
			(island_removal_mode 0)
		)
		(polygon
			(pts
				(arc
					(start 162.9918 -11.811)
					(mid 161.2138 -11.811)
					(end 162.9918 -11.811)
				)
			)
		)
	)
	(zone
		(layers "In1.Cu" "In3.Cu" "In4.Cu" "In5.Cu" "In6.Cu" "In8.Cu")
		(hatch none 0.5)
		(connect_pads
			(clearance 0)
		)
		(min_thickness 0.25)
		(keepout
			(tracks not_allowed)
			(vias allowed)
			(pads allowed)
			(copperpour not_allowed)
			(footprints allowed)
		)
		(placement
			(enabled no)
			(sheetname "")
		)
		(fill yes
			(thermal_gap 0.5)
			(thermal_bridge_width 0.5)
			(island_removal_mode 0)
		)
		(polygon
			(pts
				(arc
					(start 29.2354 -66.43624)
					(mid 27.4574 -66.43624)
					(end 29.2354 -66.43624)
				)
			)
		)
	)
	(zone
		(layers "In1.Cu" "In3.Cu" "In4.Cu" "In5.Cu" "In6.Cu" "In8.Cu")
		(hatch none 0.5)
		(connect_pads
			(clearance 0)
		)
		(min_thickness 0.25)
		(keepout
			(tracks not_allowed)
			(vias allowed)
			(pads allowed)
			(copperpour not_allowed)
			(footprints allowed)
		)
		(placement
			(enabled no)
			(sheetname "")
		)
		(fill yes
			(thermal_gap 0.5)
			(thermal_bridge_width 0.5)
			(island_removal_mode 0)
		)
		(polygon
			(pts
				(arc
					(start 29.2354 -65.67424)
					(mid 27.4574 -65.67424)
					(end 29.2354 -65.67424)
				)
			)
		)
	)
	(zone
		(layers "In1.Cu" "In3.Cu" "In4.Cu" "In5.Cu" "In6.Cu" "In8.Cu")
		(hatch none 0.5)
		(connect_pads
			(clearance 0)
		)
		(min_thickness 0.25)
		(keepout
			(tracks not_allowed)
			(vias allowed)
			(pads allowed)
			(copperpour not_allowed)
			(footprints allowed)
		)
		(placement
			(enabled no)
			(sheetname "")
		)
		(fill yes
			(thermal_gap 0.5)
			(thermal_bridge_width 0.5)
			(island_removal_mode 0)
		)
		(polygon
			(pts
				(arc
					(start 259.72516 -39.95674)
					(mid 257.94716 -39.95674)
					(end 259.72516 -39.95674)
				)
			)
		)
	)
	(zone
		(layers "In1.Cu" "In3.Cu" "In4.Cu" "In5.Cu" "In6.Cu" "In8.Cu")
		(hatch none 0.5)
		(connect_pads
			(clearance 0)
		)
		(min_thickness 0.25)
		(keepout
			(tracks not_allowed)
			(vias allowed)
			(pads allowed)
			(copperpour not_allowed)
			(footprints allowed)
		)
		(placement
			(enabled no)
			(sheetname "")
		)
		(fill yes
			(thermal_gap 0.5)
			(thermal_bridge_width 0.5)
			(island_removal_mode 0)
		)
		(polygon
			(pts
				(arc
					(start 103.738934 -77.71765)
					(mid 101.960934 -77.71765)
					(end 103.738934 -77.71765)
				)
			)
		)
	)
	(zone
		(layers "In1.Cu" "In3.Cu" "In4.Cu" "In5.Cu" "In6.Cu" "In8.Cu")
		(hatch none 0.5)
		(connect_pads
			(clearance 0)
		)
		(min_thickness 0.25)
		(keepout
			(tracks not_allowed)
			(vias allowed)
			(pads allowed)
			(copperpour not_allowed)
			(footprints allowed)
		)
		(placement
			(enabled no)
			(sheetname "")
		)
		(fill yes
			(thermal_gap 0.5)
			(thermal_bridge_width 0.5)
			(island_removal_mode 0)
		)
		(polygon
			(pts
				(arc
					(start 183.739282 -77.71765)
					(mid 181.961282 -77.71765)
					(end 183.739282 -77.71765)
				)
			)
		)
	)
	(zone
		(layers "In1.Cu" "In3.Cu" "In4.Cu" "In5.Cu" "In6.Cu" "In8.Cu")
		(hatch none 0.5)
		(connect_pads
			(clearance 0)
		)
		(min_thickness 0.25)
		(keepout
			(tracks not_allowed)
			(vias allowed)
			(pads allowed)
			(copperpour not_allowed)
			(footprints allowed)
		)
		(placement
			(enabled no)
			(sheetname "")
		)
		(fill yes
			(thermal_gap 0.5)
			(thermal_bridge_width 0.5)
			(island_removal_mode 0)
		)
		(polygon
			(pts
				(arc
					(start 259.72262 -40.72382)
					(mid 257.94462 -40.72382)
					(end 259.72262 -40.72382)
				)
			)
		)
	)
	(zone
		(layers "In1.Cu" "In3.Cu" "In4.Cu" "In5.Cu" "In6.Cu" "In8.Cu")
		(hatch none 0.5)
		(connect_pads
			(clearance 0)
		)
		(min_thickness 0.25)
		(keepout
			(tracks not_allowed)
			(vias allowed)
			(pads allowed)
			(copperpour not_allowed)
			(footprints allowed)
		)
		(placement
			(enabled no)
			(sheetname "")
		)
		(fill yes
			(thermal_gap 0.5)
			(thermal_bridge_width 0.5)
			(island_removal_mode 0)
		)
		(polygon
			(pts
				(arc
					(start 259.108956 -47.565818)
					(mid 257.330956 -47.565818)
					(end 259.108956 -47.565818)
				)
			)
		)
	)
	(zone
		(layers "In1.Cu" "In3.Cu" "In4.Cu" "In5.Cu" "In6.Cu" "In8.Cu")
		(hatch none 0.5)
		(connect_pads
			(clearance 0)
		)
		(min_thickness 0.25)
		(keepout
			(tracks not_allowed)
			(vias allowed)
			(pads allowed)
			(copperpour not_allowed)
			(footprints allowed)
		)
		(placement
			(enabled no)
			(sheetname "")
		)
		(fill yes
			(thermal_gap 0.5)
			(thermal_bridge_width 0.5)
			(island_removal_mode 0)
		)
		(polygon
			(pts
				(arc
					(start 259.108956 -48.327818)
					(mid 257.330956 -48.327818)
					(end 259.108956 -48.327818)
				)
			)
		)
	)
	(zone
		(layers "In1.Cu" "In3.Cu" "In4.Cu" "In5.Cu" "In6.Cu" "In8.Cu")
		(hatch none 0.5)
		(connect_pads
			(clearance 0)
		)
		(min_thickness 0.25)
		(keepout
			(tracks not_allowed)
			(vias allowed)
			(pads allowed)
			(copperpour not_allowed)
			(footprints allowed)
		)
		(placement
			(enabled no)
			(sheetname "")
		)
		(fill yes
			(thermal_gap 0.5)
			(thermal_bridge_width 0.5)
			(island_removal_mode 0)
		)
		(polygon
			(pts
				(arc
					(start 290.449 -43.7642)
					(mid 288.671 -43.7642)
					(end 290.449 -43.7642)
				)
			)
		)
	)
	(zone
		(layers "In1.Cu" "In3.Cu" "In4.Cu" "In5.Cu" "In6.Cu" "In8.Cu")
		(hatch none 0.5)
		(connect_pads
			(clearance 0)
		)
		(min_thickness 0.25)
		(keepout
			(tracks not_allowed)
			(vias allowed)
			(pads allowed)
			(copperpour not_allowed)
			(footprints allowed)
		)
		(placement
			(enabled no)
			(sheetname "")
		)
		(fill yes
			(thermal_gap 0.5)
			(thermal_bridge_width 0.5)
			(island_removal_mode 0)
		)
		(polygon
			(pts
				(arc
					(start 260.519672 -41.092882)
					(mid 258.741672 -41.092882)
					(end 260.519672 -41.092882)
				)
			)
		)
	)
	(zone
		(layers "In1.Cu" "In3.Cu" "In4.Cu" "In5.Cu" "In6.Cu" "In8.Cu")
		(hatch none 0.5)
		(connect_pads
			(clearance 0)
		)
		(min_thickness 0.25)
		(keepout
			(tracks not_allowed)
			(vias allowed)
			(pads allowed)
			(copperpour not_allowed)
			(footprints allowed)
		)
		(placement
			(enabled no)
			(sheetname "")
		)
		(fill yes
			(thermal_gap 0.5)
			(thermal_bridge_width 0.5)
			(island_removal_mode 0)
		)
		(polygon
			(pts
				(arc
					(start 259.8928 -42.3164)
					(mid 258.1148 -42.3164)
					(end 259.8928 -42.3164)
				)
			)
		)
	)
	(zone
		(layers "In1.Cu" "In3.Cu" "In4.Cu" "In5.Cu" "In6.Cu" "In8.Cu")
		(hatch none 0.5)
		(connect_pads
			(clearance 0)
		)
		(min_thickness 0.25)
		(keepout
			(tracks not_allowed)
			(vias allowed)
			(pads allowed)
			(copperpour not_allowed)
			(footprints allowed)
		)
		(placement
			(enabled no)
			(sheetname "")
		)
		(fill yes
			(thermal_gap 0.5)
			(thermal_bridge_width 0.5)
			(island_removal_mode 0)
		)
		(polygon
			(pts
				(arc
					(start 29.2354 -64.91224)
					(mid 27.4574 -64.91224)
					(end 29.2354 -64.91224)
				)
			)
		)
	)
	(zone
		(layers "In1.Cu" "In3.Cu" "In4.Cu" "In5.Cu" "In6.Cu" "In8.Cu")
		(hatch none 0.5)
		(connect_pads
			(clearance 0)
		)
		(min_thickness 0.25)
		(keepout
			(tracks not_allowed)
			(vias allowed)
			(pads allowed)
			(copperpour not_allowed)
			(footprints allowed)
		)
		(placement
			(enabled no)
			(sheetname "")
		)
		(fill yes
			(thermal_gap 0.5)
			(thermal_bridge_width 0.5)
			(island_removal_mode 0)
		)
		(polygon
			(pts
				(arc
					(start 40.267636 -57.928002)
					(mid 38.489636 -57.928002)
					(end 40.267636 -57.928002)
				)
			)
		)
	)
	(zone
		(layers "In1.Cu" "In3.Cu" "In4.Cu" "In5.Cu" "In6.Cu" "In8.Cu")
		(hatch none 0.5)
		(connect_pads
			(clearance 0)
		)
		(min_thickness 0.25)
		(keepout
			(tracks not_allowed)
			(vias allowed)
			(pads allowed)
			(copperpour not_allowed)
			(footprints allowed)
		)
		(placement
			(enabled no)
			(sheetname "")
		)
		(fill yes
			(thermal_gap 0.5)
			(thermal_bridge_width 0.5)
			(island_removal_mode 0)
		)
		(polygon
			(pts
				(arc
					(start 40.267636 -57.039002)
					(mid 38.489636 -57.039002)
					(end 40.267636 -57.039002)
				)
			)
		)
	)
	(zone
		(layers "In1.Cu" "In3.Cu" "In4.Cu" "In5.Cu" "In6.Cu" "In8.Cu")
		(hatch none 0.5)
		(connect_pads
			(clearance 0)
		)
		(min_thickness 0.25)
		(keepout
			(tracks not_allowed)
			(vias allowed)
			(pads allowed)
			(copperpour not_allowed)
			(footprints allowed)
		)
		(placement
			(enabled no)
			(sheetname "")
		)
		(fill yes
			(thermal_gap 0.5)
			(thermal_bridge_width 0.5)
			(island_removal_mode 0)
		)
		(polygon
			(pts
				(arc
					(start 163.6776 -10.7442)
					(mid 161.8996 -10.7442)
					(end 163.6776 -10.7442)
				)
			)
		)
	)
	(zone
		(layers "In1.Cu" "In3.Cu" "In4.Cu" "In5.Cu" "In6.Cu" "In8.Cu")
		(hatch none 0.5)
		(connect_pads
			(clearance 0)
		)
		(min_thickness 0.25)
		(keepout
			(tracks not_allowed)
			(vias allowed)
			(pads allowed)
			(copperpour not_allowed)
			(footprints allowed)
		)
		(placement
			(enabled no)
			(sheetname "")
		)
		(fill yes
			(thermal_gap 0.5)
			(thermal_bridge_width 0.5)
			(island_removal_mode 0)
		)
		(polygon
			(pts
				(arc
					(start 162.9918 -11.176)
					(mid 161.2138 -11.176)
					(end 162.9918 -11.176)
				)
			)
		)
	)
	(zone
		(layers "In1.Cu" "In3.Cu" "In4.Cu" "In5.Cu" "In6.Cu" "In8.Cu")
		(hatch none 0.5)
		(connect_pads
			(clearance 0)
		)
		(min_thickness 0.25)
		(keepout
			(tracks not_allowed)
			(vias allowed)
			(pads allowed)
			(copperpour not_allowed)
			(footprints allowed)
		)
		(placement
			(enabled no)
			(sheetname "")
		)
		(fill yes
			(thermal_gap 0.5)
			(thermal_bridge_width 0.5)
			(island_removal_mode 0)
		)
		(polygon
			(pts
				(arc
					(start 259.108956 -50.232818)
					(mid 257.330956 -50.232818)
					(end 259.108956 -50.232818)
				)
			)
		)
	)
	(zone
		(layers "In1.Cu" "In3.Cu" "In4.Cu" "In5.Cu" "In6.Cu" "In8.Cu")
		(hatch none 0.5)
		(connect_pads
			(clearance 0)
		)
		(min_thickness 0.25)
		(keepout
			(tracks not_allowed)
			(vias allowed)
			(pads allowed)
			(copperpour not_allowed)
			(footprints allowed)
		)
		(placement
			(enabled no)
			(sheetname "")
		)
		(fill yes
			(thermal_gap 0.5)
			(thermal_bridge_width 0.5)
			(island_removal_mode 0)
		)
		(polygon
			(pts
				(arc
					(start 39.581836 -56.658002)
					(mid 37.803836 -56.658002)
					(end 39.581836 -56.658002)
				)
			)
		)
	)
	(zone
		(layers "In1.Cu" "In3.Cu" "In4.Cu" "In5.Cu" "In6.Cu" "In8.Cu")
		(hatch none 0.5)
		(connect_pads
			(clearance 0)
		)
		(min_thickness 0.25)
		(keepout
			(tracks not_allowed)
			(vias allowed)
			(pads allowed)
			(copperpour not_allowed)
			(footprints allowed)
		)
		(placement
			(enabled no)
			(sheetname "")
		)
		(fill yes
			(thermal_gap 0.5)
			(thermal_bridge_width 0.5)
			(island_removal_mode 0)
		)
		(polygon
			(pts
				(arc
					(start 261.07136 -37.2364)
					(mid 259.29336 -37.2364)
					(end 261.07136 -37.2364)
				)
			)
		)
	)
	(zone
		(layers "In1.Cu" "In3.Cu" "In4.Cu" "In5.Cu" "In6.Cu" "In8.Cu")
		(hatch none 0.5)
		(connect_pads
			(clearance 0)
		)
		(min_thickness 0.25)
		(keepout
			(tracks not_allowed)
			(vias allowed)
			(pads allowed)
			(copperpour not_allowed)
			(footprints allowed)
		)
		(placement
			(enabled no)
			(sheetname "")
		)
		(fill yes
			(thermal_gap 0.5)
			(thermal_bridge_width 0.5)
			(island_removal_mode 0)
		)
		(polygon
			(pts
				(arc
					(start 63.739014 -77.71765)
					(mid 61.961014 -77.71765)
					(end 63.739014 -77.71765)
				)
			)
		)
	)
	(zone
		(layers "In1.Cu" "In3.Cu" "In4.Cu" "In5.Cu" "In6.Cu" "In8.Cu")
		(hatch none 0.5)
		(connect_pads
			(clearance 0)
		)
		(min_thickness 0.25)
		(keepout
			(tracks not_allowed)
			(vias allowed)
			(pads allowed)
			(copperpour not_allowed)
			(footprints allowed)
		)
		(placement
			(enabled no)
			(sheetname "")
		)
		(fill yes
			(thermal_gap 0.5)
			(thermal_bridge_width 0.5)
			(island_removal_mode 0)
		)
		(polygon
			(pts
				(arc
					(start 64.145414 -67.869816)
					(mid 61.554614 -67.869816)
					(end 64.145414 -67.869816)
				)
			)
		)
	)
	(zone
		(layers "In1.Cu" "In3.Cu" "In4.Cu" "In5.Cu" "In6.Cu" "In8.Cu")
		(hatch none 0.5)
		(connect_pads
			(clearance 0)
		)
		(min_thickness 0.25)
		(keepout
			(tracks not_allowed)
			(vias allowed)
			(pads allowed)
			(copperpour not_allowed)
			(footprints allowed)
		)
		(placement
			(enabled no)
			(sheetname "")
		)
		(fill yes
			(thermal_gap 0.5)
			(thermal_bridge_width 0.5)
			(island_removal_mode 0)
		)
		(polygon
			(pts
				(arc
					(start 163.7284 -12.2174)
					(mid 161.9504 -12.2174)
					(end 163.7284 -12.2174)
				)
			)
		)
	)
	(zone
		(layers "In1.Cu" "In3.Cu" "In4.Cu" "In5.Cu" "In6.Cu" "In8.Cu")
		(hatch none 0.5)
		(connect_pads
			(clearance 0)
		)
		(min_thickness 0.25)
		(keepout
			(tracks not_allowed)
			(vias allowed)
			(pads allowed)
			(copperpour not_allowed)
			(footprints allowed)
		)
		(placement
			(enabled no)
			(sheetname "")
		)
		(fill yes
			(thermal_gap 0.5)
			(thermal_bridge_width 0.5)
			(island_removal_mode 0)
		)
		(polygon
			(pts
				(arc
					(start 289.5092 -43.7642)
					(mid 287.7312 -43.7642)
					(end 289.5092 -43.7642)
				)
			)
		)
	)
	(zone
		(layers "In1.Cu" "In3.Cu" "In4.Cu" "In5.Cu" "In6.Cu" "In8.Cu")
		(hatch none 0.5)
		(connect_pads
			(clearance 0)
		)
		(min_thickness 0.25)
		(keepout
			(tracks not_allowed)
			(vias allowed)
			(pads allowed)
			(copperpour not_allowed)
			(footprints allowed)
		)
		(placement
			(enabled no)
			(sheetname "")
		)
		(fill yes
			(thermal_gap 0.5)
			(thermal_bridge_width 0.5)
			(island_removal_mode 0)
		)
		(polygon
			(pts
				(arc
					(start 260.519672 -39.592758)
					(mid 258.741672 -39.592758)
					(end 260.519672 -39.592758)
				)
			)
		)
	)
	(zone
		(layers "In1.Cu" "In3.Cu" "In4.Cu" "In5.Cu" "In6.Cu" "In8.Cu")
		(hatch none 0.5)
		(connect_pads
			(clearance 0)
		)
		(min_thickness 0.25)
		(keepout
			(tracks not_allowed)
			(vias allowed)
			(pads allowed)
			(copperpour not_allowed)
			(footprints allowed)
		)
		(placement
			(enabled no)
			(sheetname "")
		)
		(fill yes
			(thermal_gap 0.5)
			(thermal_bridge_width 0.5)
			(island_removal_mode 0)
		)
		(polygon
			(pts
				(arc
					(start 259.419598 -39.18712)
					(mid 257.641598 -39.18712)
					(end 259.419598 -39.18712)
				)
			)
		)
	)
	(zone
		(layers "In1.Cu" "In3.Cu" "In4.Cu" "In5.Cu" "In6.Cu" "In8.Cu")
		(hatch none 0.5)
		(connect_pads
			(clearance 0)
		)
		(min_thickness 0.25)
		(keepout
			(tracks not_allowed)
			(vias allowed)
			(pads allowed)
			(copperpour not_allowed)
			(footprints allowed)
		)
		(placement
			(enabled no)
			(sheetname "")
		)
		(fill yes
			(thermal_gap 0.5)
			(thermal_bridge_width 0.5)
			(island_removal_mode 0)
		)
		(polygon
			(pts
				(arc
					(start 295.021 -45.466)
					(mid 293.243 -45.466)
					(end 295.021 -45.466)
				)
			)
		)
	)
	(zone
		(layers "In1.Cu" "In3.Cu" "In4.Cu" "In5.Cu" "In6.Cu" "In8.Cu")
		(hatch none 0.5)
		(connect_pads
			(clearance 0)
		)
		(min_thickness 0.25)
		(keepout
			(tracks not_allowed)
			(vias allowed)
			(pads allowed)
			(copperpour not_allowed)
			(footprints allowed)
		)
		(placement
			(enabled no)
			(sheetname "")
		)
		(fill yes
			(thermal_gap 0.5)
			(thermal_bridge_width 0.5)
			(island_removal_mode 0)
		)
		(polygon
			(pts
				(arc
					(start 28.4734 -65.67424)
					(mid 26.6954 -65.67424)
					(end 28.4734 -65.67424)
				)
			)
		)
	)
	(zone
		(layers "In1.Cu" "In3.Cu" "In4.Cu" "In5.Cu" "In6.Cu" "In8.Cu")
		(hatch none 0.5)
		(connect_pads
			(clearance 0)
		)
		(min_thickness 0.25)
		(keepout
			(tracks not_allowed)
			(vias allowed)
			(pads allowed)
			(copperpour not_allowed)
			(footprints allowed)
		)
		(placement
			(enabled no)
			(sheetname "")
		)
		(fill yes
			(thermal_gap 0.5)
			(thermal_bridge_width 0.5)
			(island_removal_mode 0)
		)
		(polygon
			(pts
				(arc
					(start 259.437886 -38.461696)
					(mid 257.659886 -38.461696)
					(end 259.437886 -38.461696)
				)
			)
		)
	)
	(zone
		(layers "In1.Cu" "In3.Cu" "In4.Cu" "In5.Cu" "In6.Cu" "In8.Cu")
		(hatch none 0.5)
		(connect_pads
			(clearance 0)
		)
		(min_thickness 0.25)
		(keepout
			(tracks not_allowed)
			(vias allowed)
			(pads allowed)
			(copperpour not_allowed)
			(footprints allowed)
		)
		(placement
			(enabled no)
			(sheetname "")
		)
		(fill yes
			(thermal_gap 0.5)
			(thermal_bridge_width 0.5)
			(island_removal_mode 0)
		)
		(polygon
			(pts
				(arc
					(start 290.449 -40.9194)
					(mid 288.671 -40.9194)
					(end 290.449 -40.9194)
				)
			)
		)
	)
	(zone
		(layers "In1.Cu" "In3.Cu" "In4.Cu" "In5.Cu" "In6.Cu" "In8.Cu")
		(hatch none 0.5)
		(connect_pads
			(clearance 0)
		)
		(min_thickness 0.25)
		(keepout
			(tracks not_allowed)
			(vias allowed)
			(pads allowed)
			(copperpour not_allowed)
			(footprints allowed)
		)
		(placement
			(enabled no)
			(sheetname "")
		)
		(fill yes
			(thermal_gap 0.5)
			(thermal_bridge_width 0.5)
			(island_removal_mode 0)
		)
		(polygon
			(pts
				(arc
					(start 40.267636 -58.817002)
					(mid 38.489636 -58.817002)
					(end 40.267636 -58.817002)
				)
			)
		)
	)
	(zone
		(layers "In1.Cu" "In3.Cu" "In4.Cu" "In5.Cu" "In6.Cu" "In8.Cu")
		(hatch none 0.5)
		(connect_pads
			(clearance 0)
		)
		(min_thickness 0.25)
		(keepout
			(tracks not_allowed)
			(vias allowed)
			(pads allowed)
			(copperpour not_allowed)
			(footprints allowed)
		)
		(placement
			(enabled no)
			(sheetname "")
		)
		(fill yes
			(thermal_gap 0.5)
			(thermal_bridge_width 0.5)
			(island_removal_mode 0)
		)
		(polygon
			(pts
				(arc
					(start 291.33546 -46.62424)
					(mid 289.55746 -46.62424)
					(end 291.33546 -46.62424)
				)
			)
		)
	)
	(zone
		(layers "In1.Cu" "In3.Cu" "In4.Cu" "In5.Cu" "In6.Cu" "In8.Cu")
		(hatch none 0.5)
		(connect_pads
			(clearance 0)
		)
		(min_thickness 0.25)
		(keepout
			(tracks not_allowed)
			(vias allowed)
			(pads allowed)
			(copperpour not_allowed)
			(footprints allowed)
		)
		(placement
			(enabled no)
			(sheetname "")
		)
		(fill yes
			(thermal_gap 0.5)
			(thermal_bridge_width 0.5)
			(island_removal_mode 0)
		)
		(polygon
			(pts
				(arc
					(start 289.5092 -40.9194)
					(mid 287.7312 -40.9194)
					(end 289.5092 -40.9194)
				)
			)
		)
	)
	(zone
		(layers "In1.Cu" "In3.Cu" "In4.Cu" "In6.Cu" "In8.Cu")
		(hatch none 0.5)
		(connect_pads
			(clearance 0)
		)
		(min_thickness 0.25)
		(keepout
			(tracks not_allowed)
			(vias allowed)
			(pads allowed)
			(copperpour not_allowed)
			(footprints allowed)
		)
		(placement
			(enabled no)
			(sheetname "")
		)
		(fill yes
			(thermal_gap 0.5)
			(thermal_bridge_width 0.5)
			(island_removal_mode 0)
		)
		(polygon
			(pts
				(arc
					(start 190.477394 -70.409816)
					(mid 186.083194 -70.409816)
					(end 190.477394 -70.409816)
				)
			)
		)
	)
	(zone
		(layers "In1.Cu" "In3.Cu" "In4.Cu" "In6.Cu" "In8.Cu")
		(hatch none 0.5)
		(connect_pads
			(clearance 0)
		)
		(min_thickness 0.25)
		(keepout
			(tracks not_allowed)
			(vias allowed)
			(pads allowed)
			(copperpour not_allowed)
			(footprints allowed)
		)
		(placement
			(enabled no)
			(sheetname "")
		)
		(fill yes
			(thermal_gap 0.5)
			(thermal_bridge_width 0.5)
			(island_removal_mode 0)
		)
		(polygon
			(pts
				(arc
					(start 113.283746 -69.897244)
					(mid 111.505746 -69.897244)
					(end 113.283746 -69.897244)
				)
			)
		)
	)
	(zone
		(layers "In1.Cu" "In3.Cu" "In4.Cu" "In6.Cu" "In8.Cu")
		(hatch none 0.5)
		(connect_pads
			(clearance 0)
		)
		(min_thickness 0.25)
		(keepout
			(tracks not_allowed)
			(vias allowed)
			(pads allowed)
			(copperpour not_allowed)
			(footprints allowed)
		)
		(placement
			(enabled no)
			(sheetname "")
		)
		(fill yes
			(thermal_gap 0.5)
			(thermal_bridge_width 0.5)
			(island_removal_mode 0)
		)
		(polygon
			(pts
				(arc
					(start 276.30755 -33.070038)
					(mid 274.52955 -33.070038)
					(end 276.30755 -33.070038)
				)
			)
		)
	)
	(zone
		(layers "In1.Cu" "In3.Cu" "In4.Cu" "In6.Cu" "In8.Cu")
		(hatch none 0.5)
		(connect_pads
			(clearance 0)
		)
		(min_thickness 0.25)
		(keepout
			(tracks not_allowed)
			(vias allowed)
			(pads allowed)
			(copperpour not_allowed)
			(footprints allowed)
		)
		(placement
			(enabled no)
			(sheetname "")
		)
		(fill yes
			(thermal_gap 0.5)
			(thermal_bridge_width 0.5)
			(island_removal_mode 0)
		)
		(polygon
			(pts
				(arc
					(start 273.4818 -23.0886)
					(mid 271.7038 -23.0886)
					(end 273.4818 -23.0886)
				)
			)
		)
	)
	(zone
		(layers "In1.Cu" "In3.Cu" "In4.Cu" "In6.Cu" "In8.Cu")
		(hatch none 0.5)
		(connect_pads
			(clearance 0)
		)
		(min_thickness 0.25)
		(keepout
			(tracks not_allowed)
			(vias allowed)
			(pads allowed)
			(copperpour not_allowed)
			(footprints allowed)
		)
		(placement
			(enabled no)
			(sheetname "")
		)
		(fill yes
			(thermal_gap 0.5)
			(thermal_bridge_width 0.5)
			(island_removal_mode 0)
		)
		(polygon
			(pts
				(arc
					(start 106.667046 -70.409816)
					(mid 102.272846 -70.409816)
					(end 106.667046 -70.409816)
				)
			)
		)
	)
	(zone
		(layers "In1.Cu" "In3.Cu" "In4.Cu" "In6.Cu" "In8.Cu")
		(hatch none 0.5)
		(connect_pads
			(clearance 0)
		)
		(min_thickness 0.25)
		(keepout
			(tracks not_allowed)
			(vias allowed)
			(pads allowed)
			(copperpour not_allowed)
			(footprints allowed)
		)
		(placement
			(enabled no)
			(sheetname "")
		)
		(fill yes
			(thermal_gap 0.5)
			(thermal_bridge_width 0.5)
			(island_removal_mode 0)
		)
		(polygon
			(pts
				(arc
					(start 274.4978 -23.0886)
					(mid 272.7198 -23.0886)
					(end 274.4978 -23.0886)
				)
			)
		)
	)
	(zone
		(layers "In1.Cu" "In3.Cu" "In4.Cu" "In6.Cu" "In8.Cu")
		(hatch none 0.5)
		(connect_pads
			(clearance 0)
		)
		(min_thickness 0.25)
		(keepout
			(tracks not_allowed)
			(vias allowed)
			(pads allowed)
			(copperpour not_allowed)
			(footprints allowed)
		)
		(placement
			(enabled no)
			(sheetname "")
		)
		(fill yes
			(thermal_gap 0.5)
			(thermal_bridge_width 0.5)
			(island_removal_mode 0)
		)
		(polygon
			(pts
				(arc
					(start 278.257 -20.955)
					(mid 276.479 -20.955)
					(end 278.257 -20.955)
				)
			)
		)
	)
	(zone
		(layers "In1.Cu" "In3.Cu" "In4.Cu" "In6.Cu" "In8.Cu")
		(hatch none 0.5)
		(connect_pads
			(clearance 0)
		)
		(min_thickness 0.25)
		(keepout
			(tracks not_allowed)
			(vias allowed)
			(pads allowed)
			(copperpour not_allowed)
			(footprints allowed)
		)
		(placement
			(enabled no)
			(sheetname "")
		)
		(fill yes
			(thermal_gap 0.5)
			(thermal_bridge_width 0.5)
			(island_removal_mode 0)
		)
		(polygon
			(pts
				(arc
					(start 112.267746 -68.881244)
					(mid 110.489746 -68.881244)
					(end 112.267746 -68.881244)
				)
			)
		)
	)
	(zone
		(layers "In1.Cu" "In3.Cu" "In4.Cu" "In6.Cu" "In8.Cu")
		(hatch none 0.5)
		(connect_pads
			(clearance 0)
		)
		(min_thickness 0.25)
		(keepout
			(tracks not_allowed)
			(vias allowed)
			(pads allowed)
			(copperpour not_allowed)
			(footprints allowed)
		)
		(placement
			(enabled no)
			(sheetname "")
		)
		(fill yes
			(thermal_gap 0.5)
			(thermal_bridge_width 0.5)
			(island_removal_mode 0)
		)
		(polygon
			(pts
				(arc
					(start 112.267746 -69.897244)
					(mid 110.489746 -69.897244)
					(end 112.267746 -69.897244)
				)
			)
		)
	)
	(zone
		(layers "In1.Cu" "In3.Cu" "In4.Cu" "In6.Cu" "In8.Cu")
		(hatch none 0.5)
		(connect_pads
			(clearance 0)
		)
		(min_thickness 0.25)
		(keepout
			(tracks not_allowed)
			(vias allowed)
			(pads allowed)
			(copperpour not_allowed)
			(footprints allowed)
		)
		(placement
			(enabled no)
			(sheetname "")
		)
		(fill yes
			(thermal_gap 0.5)
			(thermal_bridge_width 0.5)
			(island_removal_mode 0)
		)
		(polygon
			(pts
				(arc
					(start 111.251746 -70.913244)
					(mid 109.473746 -70.913244)
					(end 111.251746 -70.913244)
				)
			)
		)
	)
	(zone
		(layers "In1.Cu" "In3.Cu" "In4.Cu" "In6.Cu" "In8.Cu")
		(hatch none 0.5)
		(connect_pads
			(clearance 0)
		)
		(min_thickness 0.25)
		(keepout
			(tracks not_allowed)
			(vias allowed)
			(pads allowed)
			(copperpour not_allowed)
			(footprints allowed)
		)
		(placement
			(enabled no)
			(sheetname "")
		)
		(fill yes
			(thermal_gap 0.5)
			(thermal_bridge_width 0.5)
			(island_removal_mode 0)
		)
		(polygon
			(pts
				(arc
					(start 112.267746 -70.913244)
					(mid 110.489746 -70.913244)
					(end 112.267746 -70.913244)
				)
			)
		)
	)
	(zone
		(layers "In1.Cu" "In3.Cu" "In4.Cu" "In6.Cu" "In8.Cu")
		(hatch none 0.5)
		(connect_pads
			(clearance 0)
		)
		(min_thickness 0.25)
		(keepout
			(tracks not_allowed)
			(vias allowed)
			(pads allowed)
			(copperpour not_allowed)
			(footprints allowed)
		)
		(placement
			(enabled no)
			(sheetname "")
		)
		(fill yes
			(thermal_gap 0.5)
			(thermal_bridge_width 0.5)
			(island_removal_mode 0)
		)
		(polygon
			(pts
				(arc
					(start 110.477046 -70.409816)
					(mid 106.082846 -70.409816)
					(end 110.477046 -70.409816)
				)
			)
		)
	)
	(zone
		(layers "In1.Cu" "In3.Cu" "In4.Cu" "In6.Cu" "In8.Cu")
		(hatch none 0.5)
		(connect_pads
			(clearance 0)
		)
		(min_thickness 0.25)
		(keepout
			(tracks not_allowed)
			(vias allowed)
			(pads allowed)
			(copperpour not_allowed)
			(footprints allowed)
		)
		(placement
			(enabled no)
			(sheetname "")
		)
		(fill yes
			(thermal_gap 0.5)
			(thermal_bridge_width 0.5)
			(island_removal_mode 0)
		)
		(polygon
			(pts
				(arc
					(start 111.251746 -68.881244)
					(mid 109.473746 -68.881244)
					(end 111.251746 -68.881244)
				)
			)
		)
	)
	(zone
		(layers "In1.Cu" "In3.Cu" "In4.Cu" "In6.Cu" "In8.Cu")
		(hatch none 0.5)
		(connect_pads
			(clearance 0)
		)
		(min_thickness 0.25)
		(keepout
			(tracks not_allowed)
			(vias allowed)
			(pads allowed)
			(copperpour not_allowed)
			(footprints allowed)
		)
		(placement
			(enabled no)
			(sheetname "")
		)
		(fill yes
			(thermal_gap 0.5)
			(thermal_bridge_width 0.5)
			(island_removal_mode 0)
		)
		(polygon
			(pts
				(arc
					(start 111.251746 -71.929244)
					(mid 109.473746 -71.929244)
					(end 111.251746 -71.929244)
				)
			)
		)
	)
	(zone
		(layers "In1.Cu" "In3.Cu" "In4.Cu" "In6.Cu" "In8.Cu")
		(hatch none 0.5)
		(connect_pads
			(clearance 0)
		)
		(min_thickness 0.25)
		(keepout
			(tracks not_allowed)
			(vias allowed)
			(pads allowed)
			(copperpour not_allowed)
			(footprints allowed)
		)
		(placement
			(enabled no)
			(sheetname "")
		)
		(fill yes
			(thermal_gap 0.5)
			(thermal_bridge_width 0.5)
			(island_removal_mode 0)
		)
		(polygon
			(pts
				(arc
					(start 111.251746 -69.897244)
					(mid 109.473746 -69.897244)
					(end 111.251746 -69.897244)
				)
			)
		)
	)
	(zone
		(layers "In1.Cu" "In3.Cu" "In4.Cu" "In6.Cu" "In8.Cu")
		(hatch none 0.5)
		(connect_pads
			(clearance 0)
		)
		(min_thickness 0.25)
		(keepout
			(tracks not_allowed)
			(vias allowed)
			(pads allowed)
			(copperpour not_allowed)
			(footprints allowed)
		)
		(placement
			(enabled no)
			(sheetname "")
		)
		(fill yes
			(thermal_gap 0.5)
			(thermal_bridge_width 0.5)
			(island_removal_mode 0)
		)
		(polygon
			(pts
				(arc
					(start 186.667394 -70.409816)
					(mid 182.273194 -70.409816)
					(end 186.667394 -70.409816)
				)
			)
		)
	)
	(zone
		(layers "In1.Cu" "In3.Cu" "In4.Cu" "In6.Cu" "In8.Cu")
		(hatch none 0.5)
		(connect_pads
			(clearance 0)
		)
		(min_thickness 0.25)
		(keepout
			(tracks not_allowed)
			(vias allowed)
			(pads allowed)
			(copperpour not_allowed)
			(footprints allowed)
		)
		(placement
			(enabled no)
			(sheetname "")
		)
		(fill yes
			(thermal_gap 0.5)
			(thermal_bridge_width 0.5)
			(island_removal_mode 0)
		)
		(polygon
			(pts
				(arc
					(start 113.283746 -68.881244)
					(mid 111.505746 -68.881244)
					(end 113.283746 -68.881244)
				)
			)
		)
	)
	(zone
		(layers "In1.Cu" "In3.Cu" "In4.Cu" "In6.Cu" "In8.Cu")
		(hatch none 0.5)
		(connect_pads
			(clearance 0)
		)
		(min_thickness 0.25)
		(keepout
			(tracks not_allowed)
			(vias allowed)
			(pads allowed)
			(copperpour not_allowed)
			(footprints allowed)
		)
		(placement
			(enabled no)
			(sheetname "")
		)
		(fill yes
			(thermal_gap 0.5)
			(thermal_bridge_width 0.5)
			(island_removal_mode 0)
		)
		(polygon
			(pts
				(arc
					(start 112.267746 -71.929244)
					(mid 110.489746 -71.929244)
					(end 112.267746 -71.929244)
				)
			)
		)
	)
	(zone
		(layers "In1.Cu" "In3.Cu" "In4.Cu" "In6.Cu" "In8.Cu")
		(hatch none 0.5)
		(connect_pads
			(clearance 0)
		)
		(min_thickness 0.25)
		(keepout
			(tracks not_allowed)
			(vias allowed)
			(pads allowed)
			(copperpour not_allowed)
			(footprints allowed)
		)
		(placement
			(enabled no)
			(sheetname "")
		)
		(fill yes
			(thermal_gap 0.5)
			(thermal_bridge_width 0.5)
			(island_removal_mode 0)
		)
		(polygon
			(pts
				(arc
					(start 150.47722 -70.409816)
					(mid 146.08302 -70.409816)
					(end 150.47722 -70.409816)
				)
			)
		)
	)
	(zone
		(layers "In1.Cu" "In3.Cu" "In4.Cu" "In6.Cu" "In8.Cu")
		(hatch none 0.5)
		(connect_pads
			(clearance 0)
		)
		(min_thickness 0.25)
		(keepout
			(tracks not_allowed)
			(vias allowed)
			(pads allowed)
			(copperpour not_allowed)
			(footprints allowed)
		)
		(placement
			(enabled no)
			(sheetname "")
		)
		(fill yes
			(thermal_gap 0.5)
			(thermal_bridge_width 0.5)
			(island_removal_mode 0)
		)
		(polygon
			(pts
				(arc
					(start 146.66722 -70.409816)
					(mid 142.27302 -70.409816)
					(end 146.66722 -70.409816)
				)
			)
		)
	)
	(zone
		(layers "In1.Cu" "In3.Cu" "In4.Cu" "In6.Cu" "In8.Cu")
		(hatch none 0.5)
		(connect_pads
			(clearance 0)
		)
		(min_thickness 0.25)
		(keepout
			(tracks not_allowed)
			(vias allowed)
			(pads allowed)
			(copperpour not_allowed)
			(footprints allowed)
		)
		(placement
			(enabled no)
			(sheetname "")
		)
		(fill yes
			(thermal_gap 0.5)
			(thermal_bridge_width 0.5)
			(island_removal_mode 0)
		)
		(polygon
			(pts
				(arc
					(start 295.0718 -34.9758)
					(mid 293.2938 -34.9758)
					(end 295.0718 -34.9758)
				)
			)
		)
	)
	(zone
		(layers "In1.Cu" "In3.Cu" "In4.Cu" "In6.Cu" "In8.Cu")
		(hatch none 0.5)
		(connect_pads
			(clearance 0)
		)
		(min_thickness 0.25)
		(keepout
			(tracks not_allowed)
			(vias allowed)
			(pads allowed)
			(copperpour not_allowed)
			(footprints allowed)
		)
		(placement
			(enabled no)
			(sheetname "")
		)
		(fill yes
			(thermal_gap 0.5)
			(thermal_bridge_width 0.5)
			(island_removal_mode 0)
		)
		(polygon
			(pts
				(arc
					(start 113.283746 -70.913244)
					(mid 111.505746 -70.913244)
					(end 113.283746 -70.913244)
				)
			)
		)
	)
	(zone
		(layers "In1.Cu" "In3.Cu" "In4.Cu" "In6.Cu" "In8.Cu")
		(hatch none 0.5)
		(connect_pads
			(clearance 0)
		)
		(min_thickness 0.25)
		(keepout
			(tracks not_allowed)
			(vias allowed)
			(pads allowed)
			(copperpour not_allowed)
			(footprints allowed)
		)
		(placement
			(enabled no)
			(sheetname "")
		)
		(fill yes
			(thermal_gap 0.5)
			(thermal_bridge_width 0.5)
			(island_removal_mode 0)
		)
		(polygon
			(pts
				(arc
					(start 113.283746 -71.929244)
					(mid 111.505746 -71.929244)
					(end 113.283746 -71.929244)
				)
			)
		)
	)
	(zone
		(layers "In1.Cu" "In3.Cu" "In5.Cu" "In6.Cu" "In8.Cu")
		(hatch none 0.5)
		(connect_pads
			(clearance 0)
		)
		(min_thickness 0.25)
		(keepout
			(tracks not_allowed)
			(vias allowed)
			(pads allowed)
			(copperpour not_allowed)
			(footprints allowed)
		)
		(placement
			(enabled no)
			(sheetname "")
		)
		(fill yes
			(thermal_gap 0.5)
			(thermal_bridge_width 0.5)
			(island_removal_mode 0)
		)
		(polygon
			(pts
				(arc
					(start 277.114 -51.054)
					(mid 275.336 -51.054)
					(end 277.114 -51.054)
				)
			)
		)
	)
	(zone
		(layers "In1.Cu" "In3.Cu" "In5.Cu" "In6.Cu" "In8.Cu")
		(hatch none 0.5)
		(connect_pads
			(clearance 0)
		)
		(min_thickness 0.25)
		(keepout
			(tracks not_allowed)
			(vias allowed)
			(pads allowed)
			(copperpour not_allowed)
			(footprints allowed)
		)
		(placement
			(enabled no)
			(sheetname "")
		)
		(fill yes
			(thermal_gap 0.5)
			(thermal_bridge_width 0.5)
			(island_removal_mode 0)
		)
		(polygon
			(pts
				(arc
					(start 144.145508 -67.869816)
					(mid 141.554708 -67.869816)
					(end 144.145508 -67.869816)
				)
			)
		)
	)
	(zone
		(layers "In1.Cu" "In3.Cu" "In5.Cu" "In6.Cu" "In8.Cu")
		(hatch none 0.5)
		(connect_pads
			(clearance 0)
		)
		(min_thickness 0.25)
		(keepout
			(tracks not_allowed)
			(vias allowed)
			(pads allowed)
			(copperpour not_allowed)
			(footprints allowed)
		)
		(placement
			(enabled no)
			(sheetname "")
		)
		(fill yes
			(thermal_gap 0.5)
			(thermal_bridge_width 0.5)
			(island_removal_mode 0)
		)
		(polygon
			(pts
				(arc
					(start 104.145334 -67.869816)
					(mid 101.554534 -67.869816)
					(end 104.145334 -67.869816)
				)
			)
		)
	)
	(zone
		(layers "In1.Cu" "In3.Cu" "In5.Cu" "In6.Cu" "In8.Cu")
		(hatch none 0.5)
		(connect_pads
			(clearance 0)
		)
		(min_thickness 0.25)
		(keepout
			(tracks not_allowed)
			(vias allowed)
			(pads allowed)
			(copperpour not_allowed)
			(footprints allowed)
		)
		(placement
			(enabled no)
			(sheetname "")
		)
		(fill yes
			(thermal_gap 0.5)
			(thermal_bridge_width 0.5)
			(island_removal_mode 0)
		)
		(polygon
			(pts
				(arc
					(start 277.114 -50.292)
					(mid 275.336 -50.292)
					(end 277.114 -50.292)
				)
			)
		)
	)
	(zone
		(layers "In1.Cu" "In3.Cu" "In5.Cu" "In6.Cu" "In8.Cu")
		(hatch none 0.5)
		(connect_pads
			(clearance 0)
		)
		(min_thickness 0.25)
		(keepout
			(tracks not_allowed)
			(vias allowed)
			(pads allowed)
			(copperpour not_allowed)
			(footprints allowed)
		)
		(placement
			(enabled no)
			(sheetname "")
		)
		(fill yes
			(thermal_gap 0.5)
			(thermal_bridge_width 0.5)
			(island_removal_mode 0)
		)
		(polygon
			(pts
				(arc
					(start 184.145682 -67.869816)
					(mid 181.554882 -67.869816)
					(end 184.145682 -67.869816)
				)
			)
		)
	)
	(zone
		(layers "In1.Cu" "In3.Cu" "In6.Cu" "In8.Cu")
		(hatch none 0.5)
		(connect_pads
			(clearance 0)
		)
		(min_thickness 0.25)
		(keepout
			(tracks not_allowed)
			(vias allowed)
			(pads allowed)
			(copperpour not_allowed)
			(footprints allowed)
		)
		(placement
			(enabled no)
			(sheetname "")
		)
		(fill yes
			(thermal_gap 0.5)
			(thermal_bridge_width 0.5)
			(island_removal_mode 0)
		)
		(polygon
			(pts
				(arc
					(start 222.928688 -105.882948)
					(mid 221.150688 -105.882948)
					(end 222.928688 -105.882948)
				)
			)
		)
	)
	(zone
		(layers "In1.Cu" "In3.Cu" "In6.Cu" "In8.Cu")
		(hatch none 0.5)
		(connect_pads
			(clearance 0)
		)
		(min_thickness 0.25)
		(keepout
			(tracks not_allowed)
			(vias allowed)
			(pads allowed)
			(copperpour not_allowed)
			(footprints allowed)
		)
		(placement
			(enabled no)
			(sheetname "")
		)
		(fill yes
			(thermal_gap 0.5)
			(thermal_bridge_width 0.5)
			(island_removal_mode 0)
		)
		(polygon
			(pts
				(arc
					(start 270.5354 -91.349068)
					(mid 268.7574 -91.349068)
					(end 270.5354 -91.349068)
				)
			)
		)
	)
	(zone
		(layers "In1.Cu" "In3.Cu" "In6.Cu" "In8.Cu")
		(hatch none 0.5)
		(connect_pads
			(clearance 0)
		)
		(min_thickness 0.25)
		(keepout
			(tracks not_allowed)
			(vias allowed)
			(pads allowed)
			(copperpour not_allowed)
			(footprints allowed)
		)
		(placement
			(enabled no)
			(sheetname "")
		)
		(fill yes
			(thermal_gap 0.5)
			(thermal_bridge_width 0.5)
			(island_removal_mode 0)
		)
		(polygon
			(pts
				(arc
					(start 270.129 -122.047)
					(mid 268.351 -122.047)
					(end 270.129 -122.047)
				)
			)
		)
	)
	(zone
		(layers "In1.Cu" "In3.Cu" "In6.Cu" "In8.Cu")
		(hatch none 0.5)
		(connect_pads
			(clearance 0)
		)
		(min_thickness 0.25)
		(keepout
			(tracks not_allowed)
			(vias allowed)
			(pads allowed)
			(copperpour not_allowed)
			(footprints allowed)
		)
		(placement
			(enabled no)
			(sheetname "")
		)
		(fill yes
			(thermal_gap 0.5)
			(thermal_bridge_width 0.5)
			(island_removal_mode 0)
		)
		(polygon
			(pts
				(arc
					(start 148.1836 -131.572)
					(mid 146.4056 -131.572)
					(end 148.1836 -131.572)
				)
			)
		)
	)
	(zone
		(layers "In1.Cu" "In3.Cu" "In6.Cu" "In8.Cu")
		(hatch none 0.5)
		(connect_pads
			(clearance 0)
		)
		(min_thickness 0.25)
		(keepout
			(tracks not_allowed)
			(vias allowed)
			(pads allowed)
			(copperpour not_allowed)
			(footprints allowed)
		)
		(placement
			(enabled no)
			(sheetname "")
		)
		(fill yes
			(thermal_gap 0.5)
			(thermal_bridge_width 0.5)
			(island_removal_mode 0)
		)
		(polygon
			(pts
				(arc
					(start 203.2254 -105.121202)
					(mid 201.4474 -105.121202)
					(end 203.2254 -105.121202)
				)
			)
		)
	)
	(zone
		(layers "In1.Cu" "In3.Cu" "In6.Cu" "In8.Cu")
		(hatch none 0.5)
		(connect_pads
			(clearance 0)
		)
		(min_thickness 0.25)
		(keepout
			(tracks not_allowed)
			(vias allowed)
			(pads allowed)
			(copperpour not_allowed)
			(footprints allowed)
		)
		(placement
			(enabled no)
			(sheetname "")
		)
		(fill yes
			(thermal_gap 0.5)
			(thermal_bridge_width 0.5)
			(island_removal_mode 0)
		)
		(polygon
			(pts
				(arc
					(start 72.771 -50.419)
					(mid 70.993 -50.419)
					(end 72.771 -50.419)
				)
			)
		)
	)
	(zone
		(layers "In1.Cu" "In3.Cu" "In6.Cu" "In8.Cu")
		(hatch none 0.5)
		(connect_pads
			(clearance 0)
		)
		(min_thickness 0.25)
		(keepout
			(tracks not_allowed)
			(vias allowed)
			(pads allowed)
			(copperpour not_allowed)
			(footprints allowed)
		)
		(placement
			(enabled no)
			(sheetname "")
		)
		(fill yes
			(thermal_gap 0.5)
			(thermal_bridge_width 0.5)
			(island_removal_mode 0)
		)
		(polygon
			(pts
				(arc
					(start 271.653 -100.965)
					(mid 269.875 -100.965)
					(end 271.653 -100.965)
				)
			)
		)
	)
	(zone
		(layers "In1.Cu" "In3.Cu" "In6.Cu" "In8.Cu")
		(hatch none 0.5)
		(connect_pads
			(clearance 0)
		)
		(min_thickness 0.25)
		(keepout
			(tracks not_allowed)
			(vias allowed)
			(pads allowed)
			(copperpour not_allowed)
			(footprints allowed)
		)
		(placement
			(enabled no)
			(sheetname "")
		)
		(fill yes
			(thermal_gap 0.5)
			(thermal_bridge_width 0.5)
			(island_removal_mode 0)
		)
		(polygon
			(pts
				(arc
					(start 204.679042 -104.4321)
					(mid 202.901042 -104.4321)
					(end 204.679042 -104.4321)
				)
			)
		)
	)
	(zone
		(layers "In1.Cu" "In3.Cu" "In6.Cu" "In8.Cu")
		(hatch none 0.5)
		(connect_pads
			(clearance 0)
		)
		(min_thickness 0.25)
		(keepout
			(tracks not_allowed)
			(vias allowed)
			(pads allowed)
			(copperpour not_allowed)
			(footprints allowed)
		)
		(placement
			(enabled no)
			(sheetname "")
		)
		(fill yes
			(thermal_gap 0.5)
			(thermal_bridge_width 0.5)
			(island_removal_mode 0)
		)
		(polygon
			(pts
				(arc
					(start 232.480104 -127.300736)
					(mid 230.702104 -127.300736)
					(end 232.480104 -127.300736)
				)
			)
		)
	)
	(zone
		(layers "In1.Cu" "In3.Cu" "In6.Cu" "In8.Cu")
		(hatch none 0.5)
		(connect_pads
			(clearance 0)
		)
		(min_thickness 0.25)
		(keepout
			(tracks not_allowed)
			(vias allowed)
			(pads allowed)
			(copperpour not_allowed)
			(footprints allowed)
		)
		(placement
			(enabled no)
			(sheetname "")
		)
		(fill yes
			(thermal_gap 0.5)
			(thermal_bridge_width 0.5)
			(island_removal_mode 0)
		)
		(polygon
			(pts
				(arc
					(start 240.727738 -98.012758)
					(mid 238.949738 -98.012758)
					(end 240.727738 -98.012758)
				)
			)
		)
	)
	(zone
		(layers "In1.Cu" "In3.Cu" "In6.Cu" "In8.Cu")
		(hatch none 0.5)
		(connect_pads
			(clearance 0)
		)
		(min_thickness 0.25)
		(keepout
			(tracks not_allowed)
			(vias allowed)
			(pads allowed)
			(copperpour not_allowed)
			(footprints allowed)
		)
		(placement
			(enabled no)
			(sheetname "")
		)
		(fill yes
			(thermal_gap 0.5)
			(thermal_bridge_width 0.5)
			(island_removal_mode 0)
		)
		(polygon
			(pts
				(arc
					(start 163.799774 -131.572)
					(mid 162.021774 -131.572)
					(end 163.799774 -131.572)
				)
			)
		)
	)
	(zone
		(layers "In1.Cu" "In3.Cu" "In6.Cu" "In8.Cu")
		(hatch none 0.5)
		(connect_pads
			(clearance 0)
		)
		(min_thickness 0.25)
		(keepout
			(tracks not_allowed)
			(vias allowed)
			(pads allowed)
			(copperpour not_allowed)
			(footprints allowed)
		)
		(placement
			(enabled no)
			(sheetname "")
		)
		(fill yes
			(thermal_gap 0.5)
			(thermal_bridge_width 0.5)
			(island_removal_mode 0)
		)
		(polygon
			(pts
				(arc
					(start 242.97894 -98.012758)
					(mid 241.20094 -98.012758)
					(end 242.97894 -98.012758)
				)
			)
		)
	)
	(zone
		(layers "In1.Cu" "In3.Cu" "In6.Cu" "In8.Cu")
		(hatch none 0.5)
		(connect_pads
			(clearance 0)
		)
		(min_thickness 0.25)
		(keepout
			(tracks not_allowed)
			(vias allowed)
			(pads allowed)
			(copperpour not_allowed)
			(footprints allowed)
		)
		(placement
			(enabled no)
			(sheetname "")
		)
		(fill yes
			(thermal_gap 0.5)
			(thermal_bridge_width 0.5)
			(island_removal_mode 0)
		)
		(polygon
			(pts
				(arc
					(start 206.28737 -122.809762)
					(mid 204.50937 -122.809762)
					(end 206.28737 -122.809762)
				)
			)
		)
	)
	(zone
		(layers "In1.Cu" "In3.Cu" "In6.Cu" "In8.Cu")
		(hatch none 0.5)
		(connect_pads
			(clearance 0)
		)
		(min_thickness 0.25)
		(keepout
			(tracks not_allowed)
			(vias allowed)
			(pads allowed)
			(copperpour not_allowed)
			(footprints allowed)
		)
		(placement
			(enabled no)
			(sheetname "")
		)
		(fill yes
			(thermal_gap 0.5)
			(thermal_bridge_width 0.5)
			(island_removal_mode 0)
		)
		(polygon
			(pts
				(arc
					(start 276.86 -90.424)
					(mid 275.082 -90.424)
					(end 276.86 -90.424)
				)
			)
		)
	)
	(zone
		(layers "In1.Cu" "In3.Cu" "In6.Cu" "In8.Cu")
		(hatch none 0.5)
		(connect_pads
			(clearance 0)
		)
		(min_thickness 0.25)
		(keepout
			(tracks not_allowed)
			(vias allowed)
			(pads allowed)
			(copperpour not_allowed)
			(footprints allowed)
		)
		(placement
			(enabled no)
			(sheetname "")
		)
		(fill yes
			(thermal_gap 0.5)
			(thermal_bridge_width 0.5)
			(island_removal_mode 0)
		)
		(polygon
			(pts
				(arc
					(start 272.415 -65.532)
					(mid 270.637 -65.532)
					(end 272.415 -65.532)
				)
			)
		)
	)
	(zone
		(layers "In1.Cu" "In3.Cu" "In6.Cu" "In8.Cu")
		(hatch none 0.5)
		(connect_pads
			(clearance 0)
		)
		(min_thickness 0.25)
		(keepout
			(tracks not_allowed)
			(vias allowed)
			(pads allowed)
			(copperpour not_allowed)
			(footprints allowed)
		)
		(placement
			(enabled no)
			(sheetname "")
		)
		(fill yes
			(thermal_gap 0.5)
			(thermal_bridge_width 0.5)
			(island_removal_mode 0)
		)
		(polygon
			(pts
				(arc
					(start 132.588 -60.96)
					(mid 129.794 -60.96)
					(end 132.588 -60.96)
				)
			)
		)
	)
	(zone
		(layers "In1.Cu" "In3.Cu" "In6.Cu" "In8.Cu")
		(hatch none 0.5)
		(connect_pads
			(clearance 0)
		)
		(min_thickness 0.25)
		(keepout
			(tracks not_allowed)
			(vias allowed)
			(pads allowed)
			(copperpour not_allowed)
			(footprints allowed)
		)
		(placement
			(enabled no)
			(sheetname "")
		)
		(fill yes
			(thermal_gap 0.5)
			(thermal_bridge_width 0.5)
			(island_removal_mode 0)
		)
		(polygon
			(pts
				(arc
					(start 270.129 -88.138)
					(mid 268.351 -88.138)
					(end 270.129 -88.138)
				)
			)
		)
	)
	(zone
		(layers "In1.Cu" "In3.Cu" "In6.Cu" "In8.Cu")
		(hatch none 0.5)
		(connect_pads
			(clearance 0)
		)
		(min_thickness 0.25)
		(keepout
			(tracks not_allowed)
			(vias allowed)
			(pads allowed)
			(copperpour not_allowed)
			(footprints allowed)
		)
		(placement
			(enabled no)
			(sheetname "")
		)
		(fill yes
			(thermal_gap 0.5)
			(thermal_bridge_width 0.5)
			(island_removal_mode 0)
		)
		(polygon
			(pts
				(arc
					(start 220.685868 -102.9081)
					(mid 218.907868 -102.9081)
					(end 220.685868 -102.9081)
				)
			)
		)
	)
	(zone
		(layers "In1.Cu" "In3.Cu" "In6.Cu" "In8.Cu")
		(hatch none 0.5)
		(connect_pads
			(clearance 0)
		)
		(min_thickness 0.25)
		(keepout
			(tracks not_allowed)
			(vias allowed)
			(pads allowed)
			(copperpour not_allowed)
			(footprints allowed)
		)
		(placement
			(enabled no)
			(sheetname "")
		)
		(fill yes
			(thermal_gap 0.5)
			(thermal_bridge_width 0.5)
			(island_removal_mode 0)
		)
		(polygon
			(pts
				(arc
					(start 188.945774 -126.492)
					(mid 187.167774 -126.492)
					(end 188.945774 -126.492)
				)
			)
		)
	)
	(zone
		(layers "In1.Cu" "In3.Cu" "In6.Cu" "In8.Cu")
		(hatch none 0.5)
		(connect_pads
			(clearance 0)
		)
		(min_thickness 0.25)
		(keepout
			(tracks not_allowed)
			(vias allowed)
			(pads allowed)
			(copperpour not_allowed)
			(footprints allowed)
		)
		(placement
			(enabled no)
			(sheetname "")
		)
		(fill yes
			(thermal_gap 0.5)
			(thermal_bridge_width 0.5)
			(island_removal_mode 0)
		)
		(polygon
			(pts
				(arc
					(start 270.129 -86.614)
					(mid 268.351 -86.614)
					(end 270.129 -86.614)
				)
			)
		)
	)
	(zone
		(layers "In1.Cu" "In3.Cu" "In6.Cu" "In8.Cu")
		(hatch none 0.5)
		(connect_pads
			(clearance 0)
		)
		(min_thickness 0.25)
		(keepout
			(tracks not_allowed)
			(vias allowed)
			(pads allowed)
			(copperpour not_allowed)
			(footprints allowed)
		)
		(placement
			(enabled no)
			(sheetname "")
		)
		(fill yes
			(thermal_gap 0.5)
			(thermal_bridge_width 0.5)
			(island_removal_mode 0)
		)
		(polygon
			(pts
				(arc
					(start 203.2254 -103.656638)
					(mid 201.4474 -103.656638)
					(end 203.2254 -103.656638)
				)
			)
		)
	)
	(zone
		(layers "In1.Cu" "In3.Cu" "In6.Cu" "In8.Cu")
		(hatch none 0.5)
		(connect_pads
			(clearance 0)
		)
		(min_thickness 0.25)
		(keepout
			(tracks not_allowed)
			(vias allowed)
			(pads allowed)
			(copperpour not_allowed)
			(footprints allowed)
		)
		(placement
			(enabled no)
			(sheetname "")
		)
		(fill yes
			(thermal_gap 0.5)
			(thermal_bridge_width 0.5)
			(island_removal_mode 0)
		)
		(polygon
			(pts
				(arc
					(start 217.063828 -132.94614)
					(mid 215.285828 -132.94614)
					(end 217.063828 -132.94614)
				)
			)
		)
	)
	(zone
		(layers "In1.Cu" "In3.Cu" "In6.Cu" "In8.Cu")
		(hatch none 0.5)
		(connect_pads
			(clearance 0)
		)
		(min_thickness 0.25)
		(keepout
			(tracks not_allowed)
			(vias allowed)
			(pads allowed)
			(copperpour not_allowed)
			(footprints allowed)
		)
		(placement
			(enabled no)
			(sheetname "")
		)
		(fill yes
			(thermal_gap 0.5)
			(thermal_bridge_width 0.5)
			(island_removal_mode 0)
		)
		(polygon
			(pts
				(arc
					(start 205.441042 -105.896664)
					(mid 203.663042 -105.896664)
					(end 205.441042 -105.896664)
				)
			)
		)
	)
	(zone
		(layers "In1.Cu" "In3.Cu" "In6.Cu" "In8.Cu")
		(hatch none 0.5)
		(connect_pads
			(clearance 0)
		)
		(min_thickness 0.25)
		(keepout
			(tracks not_allowed)
			(vias allowed)
			(pads allowed)
			(copperpour not_allowed)
			(footprints allowed)
		)
		(placement
			(enabled no)
			(sheetname "")
		)
		(fill yes
			(thermal_gap 0.5)
			(thermal_bridge_width 0.5)
			(island_removal_mode 0)
		)
		(polygon
			(pts
				(arc
					(start 271.653 -88.9)
					(mid 269.875 -88.9)
					(end 271.653 -88.9)
				)
			)
		)
	)
	(zone
		(layers "In1.Cu" "In3.Cu" "In6.Cu" "In8.Cu")
		(hatch none 0.5)
		(connect_pads
			(clearance 0)
		)
		(min_thickness 0.25)
		(keepout
			(tracks not_allowed)
			(vias allowed)
			(pads allowed)
			(copperpour not_allowed)
			(footprints allowed)
		)
		(placement
			(enabled no)
			(sheetname "")
		)
		(fill yes
			(thermal_gap 0.5)
			(thermal_bridge_width 0.5)
			(island_removal_mode 0)
		)
		(polygon
			(pts
				(arc
					(start 272.415 -76.835)
					(mid 270.637 -76.835)
					(end 272.415 -76.835)
				)
			)
		)
	)
	(zone
		(layers "In1.Cu" "In3.Cu" "In6.Cu" "In8.Cu")
		(hatch none 0.5)
		(connect_pads
			(clearance 0)
		)
		(min_thickness 0.25)
		(keepout
			(tracks not_allowed)
			(vias allowed)
			(pads allowed)
			(copperpour not_allowed)
			(footprints allowed)
		)
		(placement
			(enabled no)
			(sheetname "")
		)
		(fill yes
			(thermal_gap 0.5)
			(thermal_bridge_width 0.5)
			(island_removal_mode 0)
		)
		(polygon
			(pts
				(arc
					(start 170.688 -60.96)
					(mid 167.894 -60.96)
					(end 170.688 -60.96)
				)
			)
		)
	)
	(zone
		(layers "In1.Cu" "In3.Cu" "In6.Cu" "In8.Cu")
		(hatch none 0.5)
		(connect_pads
			(clearance 0)
		)
		(min_thickness 0.25)
		(keepout
			(tracks not_allowed)
			(vias allowed)
			(pads allowed)
			(copperpour not_allowed)
			(footprints allowed)
		)
		(placement
			(enabled no)
			(sheetname "")
		)
		(fill yes
			(thermal_gap 0.5)
			(thermal_bridge_width 0.5)
			(island_removal_mode 0)
		)
		(polygon
			(pts
				(arc
					(start 176.753774 -131.572)
					(mid 174.975774 -131.572)
					(end 176.753774 -131.572)
				)
			)
		)
	)
	(zone
		(layers "In1.Cu" "In3.Cu" "In6.Cu" "In8.Cu")
		(hatch none 0.5)
		(connect_pads
			(clearance 0)
		)
		(min_thickness 0.25)
		(keepout
			(tracks not_allowed)
			(vias allowed)
			(pads allowed)
			(copperpour not_allowed)
			(footprints allowed)
		)
		(placement
			(enabled no)
			(sheetname "")
		)
		(fill yes
			(thermal_gap 0.5)
			(thermal_bridge_width 0.5)
			(island_removal_mode 0)
		)
		(polygon
			(pts
				(arc
					(start 208.445862 -105.120948)
					(mid 206.667862 -105.120948)
					(end 208.445862 -105.120948)
				)
			)
		)
	)
	(zone
		(layers "In1.Cu" "In3.Cu" "In6.Cu" "In8.Cu")
		(hatch none 0.5)
		(connect_pads
			(clearance 0)
		)
		(min_thickness 0.25)
		(keepout
			(tracks not_allowed)
			(vias allowed)
			(pads allowed)
			(copperpour not_allowed)
			(footprints allowed)
		)
		(placement
			(enabled no)
			(sheetname "")
		)
		(fill yes
			(thermal_gap 0.5)
			(thermal_bridge_width 0.5)
			(island_removal_mode 0)
		)
		(polygon
			(pts
				(arc
					(start 220.664278 -121.331736)
					(mid 218.886278 -121.331736)
					(end 220.664278 -121.331736)
				)
			)
		)
	)
	(zone
		(layers "In1.Cu" "In3.Cu" "In6.Cu" "In8.Cu")
		(hatch none 0.5)
		(connect_pads
			(clearance 0)
		)
		(min_thickness 0.25)
		(keepout
			(tracks not_allowed)
			(vias allowed)
			(pads allowed)
			(copperpour not_allowed)
			(footprints allowed)
		)
		(placement
			(enabled no)
			(sheetname "")
		)
		(fill yes
			(thermal_gap 0.5)
			(thermal_bridge_width 0.5)
			(island_removal_mode 0)
		)
		(polygon
			(pts
				(arc
					(start 270.891 -64.008)
					(mid 269.113 -64.008)
					(end 270.891 -64.008)
				)
			)
		)
	)
	(zone
		(layers "In1.Cu" "In3.Cu" "In6.Cu" "In8.Cu")
		(hatch none 0.5)
		(connect_pads
			(clearance 0)
		)
		(min_thickness 0.25)
		(keepout
			(tracks not_allowed)
			(vias allowed)
			(pads allowed)
			(copperpour not_allowed)
			(footprints allowed)
		)
		(placement
			(enabled no)
			(sheetname "")
		)
		(fill yes
			(thermal_gap 0.5)
			(thermal_bridge_width 0.5)
			(island_removal_mode 0)
		)
		(polygon
			(pts
				(arc
					(start 47.94504 -52.1589)
					(mid 46.16704 -52.1589)
					(end 47.94504 -52.1589)
				)
			)
		)
	)
	(zone
		(layers "In1.Cu" "In3.Cu" "In6.Cu" "In8.Cu")
		(hatch none 0.5)
		(connect_pads
			(clearance 0)
		)
		(min_thickness 0.25)
		(keepout
			(tracks not_allowed)
			(vias allowed)
			(pads allowed)
			(copperpour not_allowed)
			(footprints allowed)
		)
		(placement
			(enabled no)
			(sheetname "")
		)
		(fill yes
			(thermal_gap 0.5)
			(thermal_bridge_width 0.5)
			(island_removal_mode 0)
		)
		(polygon
			(pts
				(arc
					(start 219.923868 -105.134664)
					(mid 218.145868 -105.134664)
					(end 219.923868 -105.134664)
				)
			)
		)
	)
	(zone
		(layers "In1.Cu" "In3.Cu" "In6.Cu" "In8.Cu")
		(hatch none 0.5)
		(connect_pads
			(clearance 0)
		)
		(min_thickness 0.25)
		(keepout
			(tracks not_allowed)
			(vias allowed)
			(pads allowed)
			(copperpour not_allowed)
			(footprints allowed)
		)
		(placement
			(enabled no)
			(sheetname "")
		)
		(fill yes
			(thermal_gap 0.5)
			(thermal_bridge_width 0.5)
			(island_removal_mode 0)
		)
		(polygon
			(pts
				(arc
					(start 273.177 -61.722)
					(mid 271.399 -61.722)
					(end 273.177 -61.722)
				)
			)
		)
	)
	(zone
		(layers "In1.Cu" "In3.Cu" "In6.Cu" "In8.Cu")
		(hatch none 0.5)
		(connect_pads
			(clearance 0)
		)
		(min_thickness 0.25)
		(keepout
			(tracks not_allowed)
			(vias allowed)
			(pads allowed)
			(copperpour not_allowed)
			(footprints allowed)
		)
		(placement
			(enabled no)
			(sheetname "")
		)
		(fill yes
			(thermal_gap 0.5)
			(thermal_bridge_width 0.5)
			(island_removal_mode 0)
		)
		(polygon
			(pts
				(arc
					(start 135.9916 -131.572)
					(mid 134.2136 -131.572)
					(end 135.9916 -131.572)
				)
			)
		)
	)
	(zone
		(layers "In1.Cu" "In3.Cu" "In6.Cu" "In8.Cu")
		(hatch none 0.5)
		(connect_pads
			(clearance 0)
		)
		(min_thickness 0.25)
		(keepout
			(tracks not_allowed)
			(vias allowed)
			(pads allowed)
			(copperpour not_allowed)
			(footprints allowed)
		)
		(placement
			(enabled no)
			(sheetname "")
		)
		(fill yes
			(thermal_gap 0.5)
			(thermal_bridge_width 0.5)
			(island_removal_mode 0)
		)
		(polygon
			(pts
				(arc
					(start 100.076 -52.324)
					(mid 98.298 -52.324)
					(end 100.076 -52.324)
				)
			)
		)
	)
	(zone
		(layers "In1.Cu" "In3.Cu" "In6.Cu" "In8.Cu")
		(hatch none 0.5)
		(connect_pads
			(clearance 0)
		)
		(min_thickness 0.25)
		(keepout
			(tracks not_allowed)
			(vias allowed)
			(pads allowed)
			(copperpour not_allowed)
			(footprints allowed)
		)
		(placement
			(enabled no)
			(sheetname "")
		)
		(fill yes
			(thermal_gap 0.5)
			(thermal_bridge_width 0.5)
			(island_removal_mode 0)
		)
		(polygon
			(pts
				(arc
					(start 96.753426 -126.492)
					(mid 94.975426 -126.492)
					(end 96.753426 -126.492)
				)
			)
		)
	)
	(zone
		(layers "In1.Cu" "In3.Cu" "In6.Cu" "In8.Cu")
		(hatch none 0.5)
		(connect_pads
			(clearance 0)
		)
		(min_thickness 0.25)
		(keepout
			(tracks not_allowed)
			(vias allowed)
			(pads allowed)
			(copperpour not_allowed)
			(footprints allowed)
		)
		(placement
			(enabled no)
			(sheetname "")
		)
		(fill yes
			(thermal_gap 0.5)
			(thermal_bridge_width 0.5)
			(island_removal_mode 0)
		)
		(polygon
			(pts
				(arc
					(start 220.664278 -120.569736)
					(mid 218.886278 -120.569736)
					(end 220.664278 -120.569736)
				)
			)
		)
	)
	(zone
		(layers "In1.Cu" "In3.Cu" "In6.Cu" "In8.Cu")
		(hatch none 0.5)
		(connect_pads
			(clearance 0)
		)
		(min_thickness 0.25)
		(keepout
			(tracks not_allowed)
			(vias allowed)
			(pads allowed)
			(copperpour not_allowed)
			(footprints allowed)
		)
		(placement
			(enabled no)
			(sheetname "")
		)
		(fill yes
			(thermal_gap 0.5)
			(thermal_bridge_width 0.5)
			(island_removal_mode 0)
		)
		(polygon
			(pts
				(arc
					(start 233.958384 -131.829556)
					(mid 232.180384 -131.829556)
					(end 233.958384 -131.829556)
				)
			)
		)
	)
	(zone
		(layers "In1.Cu" "In3.Cu" "In6.Cu" "In8.Cu")
		(hatch none 0.5)
		(connect_pads
			(clearance 0)
		)
		(min_thickness 0.25)
		(keepout
			(tracks not_allowed)
			(vias allowed)
			(pads allowed)
			(copperpour not_allowed)
			(footprints allowed)
		)
		(placement
			(enabled no)
			(sheetname "")
		)
		(fill yes
			(thermal_gap 0.5)
			(thermal_bridge_width 0.5)
			(island_removal_mode 0)
		)
		(polygon
			(pts
				(arc
					(start 218.377262 -98.013012)
					(mid 216.599262 -98.013012)
					(end 218.377262 -98.013012)
				)
			)
		)
	)
	(zone
		(layers "In1.Cu" "In3.Cu" "In6.Cu" "In8.Cu")
		(hatch none 0.5)
		(connect_pads
			(clearance 0)
		)
		(min_thickness 0.25)
		(keepout
			(tracks not_allowed)
			(vias allowed)
			(pads allowed)
			(copperpour not_allowed)
			(footprints allowed)
		)
		(placement
			(enabled no)
			(sheetname "")
		)
		(fill yes
			(thermal_gap 0.5)
			(thermal_bridge_width 0.5)
			(island_removal_mode 0)
		)
		(polygon
			(pts
				(arc
					(start 276.86 -102.489)
					(mid 275.082 -102.489)
					(end 276.86 -102.489)
				)
			)
		)
	)
	(zone
		(layers "In1.Cu" "In3.Cu" "In6.Cu" "In8.Cu")
		(hatch none 0.5)
		(connect_pads
			(clearance 0)
		)
		(min_thickness 0.25)
		(keepout
			(tracks not_allowed)
			(vias allowed)
			(pads allowed)
			(copperpour not_allowed)
			(footprints allowed)
		)
		(placement
			(enabled no)
			(sheetname "")
		)
		(fill yes
			(thermal_gap 0.5)
			(thermal_bridge_width 0.5)
			(island_removal_mode 0)
		)
		(polygon
			(pts
				(arc
					(start 215.585802 -127.61214)
					(mid 213.807802 -127.61214)
					(end 215.585802 -127.61214)
				)
			)
		)
	)
	(zone
		(layers "In1.Cu" "In3.Cu" "In6.Cu" "In8.Cu")
		(hatch none 0.5)
		(connect_pads
			(clearance 0)
		)
		(min_thickness 0.25)
		(keepout
			(tracks not_allowed)
			(vias allowed)
			(pads allowed)
			(copperpour not_allowed)
			(footprints allowed)
		)
		(placement
			(enabled no)
			(sheetname "")
		)
		(fill yes
			(thermal_gap 0.5)
			(thermal_bridge_width 0.5)
			(island_removal_mode 0)
		)
		(polygon
			(pts
				(arc
					(start 232.49382 -131.829556)
					(mid 230.71582 -131.829556)
					(end 232.49382 -131.829556)
				)
			)
		)
	)
	(zone
		(layers "In1.Cu" "In3.Cu" "In6.Cu" "In8.Cu")
		(hatch none 0.5)
		(connect_pads
			(clearance 0)
		)
		(min_thickness 0.25)
		(keepout
			(tracks not_allowed)
			(vias allowed)
			(pads allowed)
			(copperpour not_allowed)
			(footprints allowed)
		)
		(placement
			(enabled no)
			(sheetname "")
		)
		(fill yes
			(thermal_gap 0.5)
			(thermal_bridge_width 0.5)
			(island_removal_mode 0)
		)
		(polygon
			(pts
				(arc
					(start 150.876 -51.562)
					(mid 149.098 -51.562)
					(end 150.876 -51.562)
				)
			)
		)
	)
	(zone
		(layers "In1.Cu" "In3.Cu" "In6.Cu" "In8.Cu")
		(hatch none 0.5)
		(connect_pads
			(clearance 0)
		)
		(min_thickness 0.25)
		(keepout
			(tracks not_allowed)
			(vias allowed)
			(pads allowed)
			(copperpour not_allowed)
			(footprints allowed)
		)
		(placement
			(enabled no)
			(sheetname "")
		)
		(fill yes
			(thermal_gap 0.5)
			(thermal_bridge_width 0.5)
			(island_removal_mode 0)
		)
		(polygon
			(pts
				(arc
					(start 233.242104 -129.586736)
					(mid 231.464104 -129.586736)
					(end 233.242104 -129.586736)
				)
			)
		)
	)
	(zone
		(layers "In1.Cu" "In3.Cu" "In6.Cu" "In8.Cu")
		(hatch none 0.5)
		(connect_pads
			(clearance 0)
		)
		(min_thickness 0.25)
		(keepout
			(tracks not_allowed)
			(vias allowed)
			(pads allowed)
			(copperpour not_allowed)
			(footprints allowed)
		)
		(placement
			(enabled no)
			(sheetname "")
		)
		(fill yes
			(thermal_gap 0.5)
			(thermal_bridge_width 0.5)
			(island_removal_mode 0)
		)
		(polygon
			(pts
				(arc
					(start 270.891 -112.268)
					(mid 269.113 -112.268)
					(end 270.891 -112.268)
				)
			)
		)
	)
	(zone
		(layers "In1.Cu" "In3.Cu" "In6.Cu" "In8.Cu")
		(hatch none 0.5)
		(connect_pads
			(clearance 0)
		)
		(min_thickness 0.25)
		(keepout
			(tracks not_allowed)
			(vias allowed)
			(pads allowed)
			(copperpour not_allowed)
			(footprints allowed)
		)
		(placement
			(enabled no)
			(sheetname "")
		)
		(fill yes
			(thermal_gap 0.5)
			(thermal_bridge_width 0.5)
			(island_removal_mode 0)
		)
		(polygon
			(pts
				(arc
					(start 272.415 -73.787)
					(mid 270.637 -73.787)
					(end 272.415 -73.787)
				)
			)
		)
	)
	(zone
		(layers "In1.Cu" "In3.Cu" "In6.Cu" "In8.Cu")
		(hatch none 0.5)
		(connect_pads
			(clearance 0)
		)
		(min_thickness 0.25)
		(keepout
			(tracks not_allowed)
			(vias allowed)
			(pads allowed)
			(copperpour not_allowed)
			(footprints allowed)
		)
		(placement
			(enabled no)
			(sheetname "")
		)
		(fill yes
			(thermal_gap 0.5)
			(thermal_bridge_width 0.5)
			(island_removal_mode 0)
		)
		(polygon
			(pts
				(arc
					(start 216.347802 -130.66014)
					(mid 214.569802 -130.66014)
					(end 216.347802 -130.66014)
				)
			)
		)
	)
	(zone
		(layers "In1.Cu" "In3.Cu" "In6.Cu" "In8.Cu")
		(hatch none 0.5)
		(connect_pads
			(clearance 0)
		)
		(min_thickness 0.25)
		(keepout
			(tracks not_allowed)
			(vias allowed)
			(pads allowed)
			(copperpour not_allowed)
			(footprints allowed)
		)
		(placement
			(enabled no)
			(sheetname "")
		)
		(fill yes
			(thermal_gap 0.5)
			(thermal_bridge_width 0.5)
			(island_removal_mode 0)
		)
		(polygon
			(pts
				(arc
					(start 270.891 -64.77)
					(mid 269.113 -64.77)
					(end 270.891 -64.77)
				)
			)
		)
	)
	(zone
		(layers "In1.Cu" "In3.Cu" "In6.Cu" "In8.Cu")
		(hatch none 0.5)
		(connect_pads
			(clearance 0)
		)
		(min_thickness 0.25)
		(keepout
			(tracks not_allowed)
			(vias allowed)
			(pads allowed)
			(copperpour not_allowed)
			(footprints allowed)
		)
		(placement
			(enabled no)
			(sheetname "")
		)
		(fill yes
			(thermal_gap 0.5)
			(thermal_bridge_width 0.5)
			(island_removal_mode 0)
		)
		(polygon
			(pts
				(arc
					(start 233.43235 -98.012758)
					(mid 231.65435 -98.012758)
					(end 233.43235 -98.012758)
				)
			)
		)
	)
	(zone
		(layers "In1.Cu" "In3.Cu" "In6.Cu" "In8.Cu")
		(hatch none 0.5)
		(connect_pads
			(clearance 0)
		)
		(min_thickness 0.25)
		(keepout
			(tracks not_allowed)
			(vias allowed)
			(pads allowed)
			(copperpour not_allowed)
			(footprints allowed)
		)
		(placement
			(enabled no)
			(sheetname "")
		)
		(fill yes
			(thermal_gap 0.5)
			(thermal_bridge_width 0.5)
			(island_removal_mode 0)
		)
		(polygon
			(pts
				(arc
					(start 220.685868 -104.4321)
					(mid 218.907868 -104.4321)
					(end 220.685868 -104.4321)
				)
			)
		)
	)
	(zone
		(layers "In1.Cu" "In3.Cu" "In6.Cu" "In8.Cu")
		(hatch none 0.5)
		(connect_pads
			(clearance 0)
		)
		(min_thickness 0.25)
		(keepout
			(tracks not_allowed)
			(vias allowed)
			(pads allowed)
			(copperpour not_allowed)
			(footprints allowed)
		)
		(placement
			(enabled no)
			(sheetname "")
		)
		(fill yes
			(thermal_gap 0.5)
			(thermal_bridge_width 0.5)
			(island_removal_mode 0)
		)
		(polygon
			(pts
				(arc
					(start 83.469226 -136.906)
					(mid 80.624426 -136.906)
					(end 83.469226 -136.906)
				)
			)
		)
	)
	(zone
		(layers "In1.Cu" "In3.Cu" "In6.Cu" "In8.Cu")
		(hatch none 0.5)
		(connect_pads
			(clearance 0)
		)
		(min_thickness 0.25)
		(keepout
			(tracks not_allowed)
			(vias allowed)
			(pads allowed)
			(copperpour not_allowed)
			(footprints allowed)
		)
		(placement
			(enabled no)
			(sheetname "")
		)
		(fill yes
			(thermal_gap 0.5)
			(thermal_bridge_width 0.5)
			(island_removal_mode 0)
		)
		(polygon
			(pts
				(arc
					(start 271.78 -137.414)
					(mid 270.002 -137.414)
					(end 271.78 -137.414)
				)
			)
		)
	)
	(zone
		(layers "In1.Cu" "In3.Cu" "In6.Cu" "In8.Cu")
		(hatch none 0.5)
		(connect_pads
			(clearance 0)
		)
		(min_thickness 0.25)
		(keepout
			(tracks not_allowed)
			(vias allowed)
			(pads allowed)
			(copperpour not_allowed)
			(footprints allowed)
		)
		(placement
			(enabled no)
			(sheetname "")
		)
		(fill yes
			(thermal_gap 0.5)
			(thermal_bridge_width 0.5)
			(island_removal_mode 0)
		)
		(polygon
			(pts
				(arc
					(start 206.28737 -120.569736)
					(mid 204.50937 -120.569736)
					(end 206.28737 -120.569736)
				)
			)
		)
	)
	(zone
		(layers "In1.Cu" "In3.Cu" "In6.Cu" "In8.Cu")
		(hatch none 0.5)
		(connect_pads
			(clearance 0)
		)
		(min_thickness 0.25)
		(keepout
			(tracks not_allowed)
			(vias allowed)
			(pads allowed)
			(copperpour not_allowed)
			(footprints allowed)
		)
		(placement
			(enabled no)
			(sheetname "")
		)
		(fill yes
			(thermal_gap 0.5)
			(thermal_bridge_width 0.5)
			(island_removal_mode 0)
		)
		(polygon
			(pts
				(arc
					(start 156.337 -52.197)
					(mid 154.559 -52.197)
					(end 156.337 -52.197)
				)
			)
		)
	)
	(zone
		(layers "In1.Cu" "In3.Cu" "In6.Cu" "In8.Cu")
		(hatch none 0.5)
		(connect_pads
			(clearance 0)
		)
		(min_thickness 0.25)
		(keepout
			(tracks not_allowed)
			(vias allowed)
			(pads allowed)
			(copperpour not_allowed)
			(footprints allowed)
		)
		(placement
			(enabled no)
			(sheetname "")
		)
		(fill yes
			(thermal_gap 0.5)
			(thermal_bridge_width 0.5)
			(island_removal_mode 0)
		)
		(polygon
			(pts
				(arc
					(start 270.129 -109.982)
					(mid 268.351 -109.982)
					(end 270.129 -109.982)
				)
			)
		)
	)
	(zone
		(layers "In1.Cu" "In3.Cu" "In6.Cu" "In8.Cu")
		(hatch none 0.5)
		(connect_pads
			(clearance 0)
		)
		(min_thickness 0.25)
		(keepout
			(tracks not_allowed)
			(vias allowed)
			(pads allowed)
			(copperpour not_allowed)
			(footprints allowed)
		)
		(placement
			(enabled no)
			(sheetname "")
		)
		(fill yes
			(thermal_gap 0.5)
			(thermal_bridge_width 0.5)
			(island_removal_mode 0)
		)
		(polygon
			(pts
				(arc
					(start 208.57337 -122.047762)
					(mid 206.79537 -122.047762)
					(end 208.57337 -122.047762)
				)
			)
		)
	)
	(zone
		(layers "In1.Cu" "In3.Cu" "In6.Cu" "In8.Cu")
		(hatch none 0.5)
		(connect_pads
			(clearance 0)
		)
		(min_thickness 0.25)
		(keepout
			(tracks not_allowed)
			(vias allowed)
			(pads allowed)
			(copperpour not_allowed)
			(footprints allowed)
		)
		(placement
			(enabled no)
			(sheetname "")
		)
		(fill yes
			(thermal_gap 0.5)
			(thermal_bridge_width 0.5)
			(island_removal_mode 0)
		)
		(polygon
			(pts
				(arc
					(start 13.76172 -69.239892)
					(mid 11.01852 -69.239892)
					(end 13.76172 -69.239892)
				)
			)
		)
	)
	(zone
		(layers "In1.Cu" "In3.Cu" "In6.Cu" "In8.Cu")
		(hatch none 0.5)
		(connect_pads
			(clearance 0)
		)
		(min_thickness 0.25)
		(keepout
			(tracks not_allowed)
			(vias allowed)
			(pads allowed)
			(copperpour not_allowed)
			(footprints allowed)
		)
		(placement
			(enabled no)
			(sheetname "")
		)
		(fill yes
			(thermal_gap 0.5)
			(thermal_bridge_width 0.5)
			(island_removal_mode 0)
		)
		(polygon
			(pts
				(arc
					(start 232.480104 -130.348736)
					(mid 230.702104 -130.348736)
					(end 232.480104 -130.348736)
				)
			)
		)
	)
	(zone
		(layers "In1.Cu" "In3.Cu" "In6.Cu" "In8.Cu")
		(hatch none 0.5)
		(connect_pads
			(clearance 0)
		)
		(min_thickness 0.25)
		(keepout
			(tracks not_allowed)
			(vias allowed)
			(pads allowed)
			(copperpour not_allowed)
			(footprints allowed)
		)
		(placement
			(enabled no)
			(sheetname "")
		)
		(fill yes
			(thermal_gap 0.5)
			(thermal_bridge_width 0.5)
			(island_removal_mode 0)
		)
		(polygon
			(pts
				(arc
					(start 215.585802 -131.42214)
					(mid 213.807802 -131.42214)
					(end 215.585802 -131.42214)
				)
			)
		)
	)
	(zone
		(layers "In1.Cu" "In3.Cu" "In6.Cu" "In8.Cu")
		(hatch none 0.5)
		(connect_pads
			(clearance 0)
		)
		(min_thickness 0.25)
		(keepout
			(tracks not_allowed)
			(vias allowed)
			(pads allowed)
			(copperpour not_allowed)
			(footprints allowed)
		)
		(placement
			(enabled no)
			(sheetname "")
		)
		(fill yes
			(thermal_gap 0.5)
			(thermal_bridge_width 0.5)
			(island_removal_mode 0)
		)
		(polygon
			(pts
				(arc
					(start 94.615 -50.419)
					(mid 92.837 -50.419)
					(end 94.615 -50.419)
				)
			)
		)
	)
	(zone
		(layers "In1.Cu" "In3.Cu" "In6.Cu" "In8.Cu")
		(hatch none 0.5)
		(connect_pads
			(clearance 0)
		)
		(min_thickness 0.25)
		(keepout
			(tracks not_allowed)
			(vias allowed)
			(pads allowed)
			(copperpour not_allowed)
			(footprints allowed)
		)
		(placement
			(enabled no)
			(sheetname "")
		)
		(fill yes
			(thermal_gap 0.5)
			(thermal_bridge_width 0.5)
			(island_removal_mode 0)
		)
		(polygon
			(pts
				(arc
					(start 270.891 -85.852)
					(mid 269.113 -85.852)
					(end 270.891 -85.852)
				)
			)
		)
	)
	(zone
		(layers "In1.Cu" "In3.Cu" "In6.Cu" "In8.Cu")
		(hatch none 0.5)
		(connect_pads
			(clearance 0)
		)
		(min_thickness 0.25)
		(keepout
			(tracks not_allowed)
			(vias allowed)
			(pads allowed)
			(copperpour not_allowed)
			(footprints allowed)
		)
		(placement
			(enabled no)
			(sheetname "")
		)
		(fill yes
			(thermal_gap 0.5)
			(thermal_bridge_width 0.5)
			(island_removal_mode 0)
		)
		(polygon
			(pts
				(arc
					(start 204.015086 -123.528328)
					(mid 202.237086 -123.528328)
					(end 204.015086 -123.528328)
				)
			)
		)
	)
	(zone
		(layers "In1.Cu" "In3.Cu" "In6.Cu" "In8.Cu")
		(hatch none 0.5)
		(connect_pads
			(clearance 0)
		)
		(min_thickness 0.25)
		(keepout
			(tracks not_allowed)
			(vias allowed)
			(pads allowed)
			(copperpour not_allowed)
			(footprints allowed)
		)
		(placement
			(enabled no)
			(sheetname "")
		)
		(fill yes
			(thermal_gap 0.5)
			(thermal_bridge_width 0.5)
			(island_removal_mode 0)
		)
		(polygon
			(pts
				(arc
					(start 106.286046 -121.209816)
					(mid 102.653846 -121.209816)
					(end 106.286046 -121.209816)
				)
			)
		)
	)
	(zone
		(layers "In1.Cu" "In3.Cu" "In6.Cu" "In8.Cu")
		(hatch none 0.5)
		(connect_pads
			(clearance 0)
		)
		(min_thickness 0.25)
		(keepout
			(tracks not_allowed)
			(vias allowed)
			(pads allowed)
			(copperpour not_allowed)
			(footprints allowed)
		)
		(placement
			(enabled no)
			(sheetname "")
		)
		(fill yes
			(thermal_gap 0.5)
			(thermal_bridge_width 0.5)
			(island_removal_mode 0)
		)
		(polygon
			(pts
				(arc
					(start 270.891 -100.965)
					(mid 269.113 -100.965)
					(end 270.891 -100.965)
				)
			)
		)
	)
	(zone
		(layers "In1.Cu" "In3.Cu" "In6.Cu" "In8.Cu")
		(hatch none 0.5)
		(connect_pads
			(clearance 0)
		)
		(min_thickness 0.25)
		(keepout
			(tracks not_allowed)
			(vias allowed)
			(pads allowed)
			(copperpour not_allowed)
			(footprints allowed)
		)
		(placement
			(enabled no)
			(sheetname "")
		)
		(fill yes
			(thermal_gap 0.5)
			(thermal_bridge_width 0.5)
			(island_removal_mode 0)
		)
		(polygon
			(pts
				(arc
					(start 270.891 -76.835)
					(mid 269.113 -76.835)
					(end 270.891 -76.835)
				)
			)
		)
	)
	(zone
		(layers "In1.Cu" "In3.Cu" "In6.Cu" "In8.Cu")
		(hatch none 0.5)
		(connect_pads
			(clearance 0)
		)
		(min_thickness 0.25)
		(keepout
			(tracks not_allowed)
			(vias allowed)
			(pads allowed)
			(copperpour not_allowed)
			(footprints allowed)
		)
		(placement
			(enabled no)
			(sheetname "")
		)
		(fill yes
			(thermal_gap 0.5)
			(thermal_bridge_width 0.5)
			(island_removal_mode 0)
		)
		(polygon
			(pts
				(arc
					(start 219.902278 -120.569736)
					(mid 218.124278 -120.569736)
					(end 219.902278 -120.569736)
				)
			)
		)
	)
	(zone
		(layers "In1.Cu" "In3.Cu" "In6.Cu" "In8.Cu")
		(hatch none 0.5)
		(connect_pads
			(clearance 0)
		)
		(min_thickness 0.25)
		(keepout
			(tracks not_allowed)
			(vias allowed)
			(pads allowed)
			(copperpour not_allowed)
			(footprints allowed)
		)
		(placement
			(enabled no)
			(sheetname "")
		)
		(fill yes
			(thermal_gap 0.5)
			(thermal_bridge_width 0.5)
			(island_removal_mode 0)
		)
		(polygon
			(pts
				(arc
					(start 218.378278 -120.569736)
					(mid 216.600278 -120.569736)
					(end 218.378278 -120.569736)
				)
			)
		)
	)
	(zone
		(layers "In1.Cu" "In3.Cu" "In6.Cu" "In8.Cu")
		(hatch none 0.5)
		(connect_pads
			(clearance 0)
		)
		(min_thickness 0.25)
		(keepout
			(tracks not_allowed)
			(vias allowed)
			(pads allowed)
			(copperpour not_allowed)
			(footprints allowed)
		)
		(placement
			(enabled no)
			(sheetname "")
		)
		(fill yes
			(thermal_gap 0.5)
			(thermal_bridge_width 0.5)
			(island_removal_mode 0)
		)
		(polygon
			(pts
				(arc
					(start 272.415 -64.77)
					(mid 270.637 -64.77)
					(end 272.415 -64.77)
				)
			)
		)
	)
	(zone
		(layers "In1.Cu" "In3.Cu" "In6.Cu" "In8.Cu")
		(hatch none 0.5)
		(connect_pads
			(clearance 0)
		)
		(min_thickness 0.25)
		(keepout
			(tracks not_allowed)
			(vias allowed)
			(pads allowed)
			(copperpour not_allowed)
			(footprints allowed)
		)
		(placement
			(enabled no)
			(sheetname "")
		)
		(fill yes
			(thermal_gap 0.5)
			(thermal_bridge_width 0.5)
			(island_removal_mode 0)
		)
		(polygon
			(pts
				(arc
					(start 222.209868 -105.896664)
					(mid 220.431868 -105.896664)
					(end 222.209868 -105.896664)
				)
			)
		)
	)
	(zone
		(layers "In1.Cu" "In3.Cu" "In6.Cu" "In8.Cu")
		(hatch none 0.5)
		(connect_pads
			(clearance 0)
		)
		(min_thickness 0.25)
		(keepout
			(tracks not_allowed)
			(vias allowed)
			(pads allowed)
			(copperpour not_allowed)
			(footprints allowed)
		)
		(placement
			(enabled no)
			(sheetname "")
		)
		(fill yes
			(thermal_gap 0.5)
			(thermal_bridge_width 0.5)
			(island_removal_mode 0)
		)
		(polygon
			(pts
				(arc
					(start 43.47464 -54.1147)
					(mid 41.69664 -54.1147)
					(end 43.47464 -54.1147)
				)
			)
		)
	)
	(zone
		(layers "In1.Cu" "In3.Cu" "In6.Cu" "In8.Cu")
		(hatch none 0.5)
		(connect_pads
			(clearance 0)
		)
		(min_thickness 0.25)
		(keepout
			(tracks not_allowed)
			(vias allowed)
			(pads allowed)
			(copperpour not_allowed)
			(footprints allowed)
		)
		(placement
			(enabled no)
			(sheetname "")
		)
		(fill yes
			(thermal_gap 0.5)
			(thermal_bridge_width 0.5)
			(island_removal_mode 0)
		)
		(polygon
			(pts
				(arc
					(start 218.399868 -103.6701)
					(mid 216.621868 -103.6701)
					(end 218.399868 -103.6701)
				)
			)
		)
	)
	(zone
		(layers "In1.Cu" "In3.Cu" "In6.Cu" "In8.Cu")
		(hatch none 0.5)
		(connect_pads
			(clearance 0)
		)
		(min_thickness 0.25)
		(keepout
			(tracks not_allowed)
			(vias allowed)
			(pads allowed)
			(copperpour not_allowed)
			(footprints allowed)
		)
		(placement
			(enabled no)
			(sheetname "")
		)
		(fill yes
			(thermal_gap 0.5)
			(thermal_bridge_width 0.5)
			(island_removal_mode 0)
		)
		(polygon
			(pts
				(arc
					(start 144.272 -112.268)
					(mid 142.494 -112.268)
					(end 144.272 -112.268)
				)
			)
		)
	)
	(zone
		(layers "In1.Cu" "In3.Cu" "In6.Cu" "In8.Cu")
		(hatch none 0.5)
		(connect_pads
			(clearance 0)
		)
		(min_thickness 0.25)
		(keepout
			(tracks not_allowed)
			(vias allowed)
			(pads allowed)
			(copperpour not_allowed)
			(footprints allowed)
		)
		(placement
			(enabled no)
			(sheetname "")
		)
		(fill yes
			(thermal_gap 0.5)
			(thermal_bridge_width 0.5)
			(island_removal_mode 0)
		)
		(polygon
			(pts
				(arc
					(start 89.154 -52.324)
					(mid 87.376 -52.324)
					(end 89.154 -52.324)
				)
			)
		)
	)
	(zone
		(layers "In1.Cu" "In3.Cu" "In6.Cu" "In8.Cu")
		(hatch none 0.5)
		(connect_pads
			(clearance 0)
		)
		(min_thickness 0.25)
		(keepout
			(tracks not_allowed)
			(vias allowed)
			(pads allowed)
			(copperpour not_allowed)
			(footprints allowed)
		)
		(placement
			(enabled no)
			(sheetname "")
		)
		(fill yes
			(thermal_gap 0.5)
			(thermal_bridge_width 0.5)
			(island_removal_mode 0)
		)
		(polygon
			(pts
				(arc
					(start 270.129 -88.9)
					(mid 268.351 -88.9)
					(end 270.129 -88.9)
				)
			)
		)
	)
	(zone
		(layers "In1.Cu" "In3.Cu" "In6.Cu" "In8.Cu")
		(hatch none 0.5)
		(connect_pads
			(clearance 0)
		)
		(min_thickness 0.25)
		(keepout
			(tracks not_allowed)
			(vias allowed)
			(pads allowed)
			(copperpour not_allowed)
			(footprints allowed)
		)
		(placement
			(enabled no)
			(sheetname "")
		)
		(fill yes
			(thermal_gap 0.5)
			(thermal_bridge_width 0.5)
			(island_removal_mode 0)
		)
		(polygon
			(pts
				(arc
					(start 206.965042 -105.896664)
					(mid 205.187042 -105.896664)
					(end 206.965042 -105.896664)
				)
			)
		)
	)
	(zone
		(layers "In1.Cu" "In3.Cu" "In6.Cu" "In8.Cu")
		(hatch none 0.5)
		(connect_pads
			(clearance 0)
		)
		(min_thickness 0.25)
		(keepout
			(tracks not_allowed)
			(vias allowed)
			(pads allowed)
			(copperpour not_allowed)
			(footprints allowed)
		)
		(placement
			(enabled no)
			(sheetname "")
		)
		(fill yes
			(thermal_gap 0.5)
			(thermal_bridge_width 0.5)
			(island_removal_mode 0)
		)
		(polygon
			(pts
				(arc
					(start 222.188278 -122.047762)
					(mid 220.410278 -122.047762)
					(end 222.188278 -122.047762)
				)
			)
		)
	)
	(zone
		(layers "In1.Cu" "In3.Cu" "In6.Cu" "In8.Cu")
		(hatch none 0.5)
		(connect_pads
			(clearance 0)
		)
		(min_thickness 0.25)
		(keepout
			(tracks not_allowed)
			(vias allowed)
			(pads allowed)
			(copperpour not_allowed)
			(footprints allowed)
		)
		(placement
			(enabled no)
			(sheetname "")
		)
		(fill yes
			(thermal_gap 0.5)
			(thermal_bridge_width 0.5)
			(island_removal_mode 0)
		)
		(polygon
			(pts
				(arc
					(start 234.720384 -131.829556)
					(mid 232.942384 -131.829556)
					(end 234.720384 -131.829556)
				)
			)
		)
	)
	(zone
		(layers "In1.Cu" "In3.Cu" "In6.Cu" "In8.Cu")
		(hatch none 0.5)
		(connect_pads
			(clearance 0)
		)
		(min_thickness 0.25)
		(keepout
			(tracks not_allowed)
			(vias allowed)
			(pads allowed)
			(copperpour not_allowed)
			(footprints allowed)
		)
		(placement
			(enabled no)
			(sheetname "")
		)
		(fill yes
			(thermal_gap 0.5)
			(thermal_bridge_width 0.5)
			(island_removal_mode 0)
		)
		(polygon
			(pts
				(arc
					(start 108.183426 -131.572)
					(mid 106.405426 -131.572)
					(end 108.183426 -131.572)
				)
			)
		)
	)
	(zone
		(layers "In1.Cu" "In3.Cu" "In6.Cu" "In8.Cu")
		(hatch none 0.5)
		(connect_pads
			(clearance 0)
		)
		(min_thickness 0.25)
		(keepout
			(tracks not_allowed)
			(vias allowed)
			(pads allowed)
			(copperpour not_allowed)
			(footprints allowed)
		)
		(placement
			(enabled no)
			(sheetname "")
		)
		(fill yes
			(thermal_gap 0.5)
			(thermal_bridge_width 0.5)
			(island_removal_mode 0)
		)
		(polygon
			(pts
				(arc
					(start 221.447868 -105.896664)
					(mid 219.669868 -105.896664)
					(end 221.447868 -105.896664)
				)
			)
		)
	)
	(zone
		(layers "In1.Cu" "In3.Cu" "In6.Cu" "In8.Cu")
		(hatch none 0.5)
		(connect_pads
			(clearance 0)
		)
		(min_thickness 0.25)
		(keepout
			(tracks not_allowed)
			(vias allowed)
			(pads allowed)
			(copperpour not_allowed)
			(footprints allowed)
		)
		(placement
			(enabled no)
			(sheetname "")
		)
		(fill yes
			(thermal_gap 0.5)
			(thermal_bridge_width 0.5)
			(island_removal_mode 0)
		)
		(polygon
			(pts
				(arc
					(start 295.5798 -44.699428)
					(mid 293.8018 -44.699428)
					(end 295.5798 -44.699428)
				)
			)
		)
	)
	(zone
		(layers "In1.Cu" "In3.Cu" "In6.Cu" "In8.Cu")
		(hatch none 0.5)
		(connect_pads
			(clearance 0)
		)
		(min_thickness 0.25)
		(keepout
			(tracks not_allowed)
			(vias allowed)
			(pads allowed)
			(copperpour not_allowed)
			(footprints allowed)
		)
		(placement
			(enabled no)
			(sheetname "")
		)
		(fill yes
			(thermal_gap 0.5)
			(thermal_bridge_width 0.5)
			(island_removal_mode 0)
		)
		(polygon
			(pts
				(arc
					(start 271.653 -77.597)
					(mid 269.875 -77.597)
					(end 271.653 -77.597)
				)
			)
		)
	)
	(zone
		(layers "In1.Cu" "In3.Cu" "In6.Cu" "In8.Cu")
		(hatch none 0.5)
		(connect_pads
			(clearance 0)
		)
		(min_thickness 0.25)
		(keepout
			(tracks not_allowed)
			(vias allowed)
			(pads allowed)
			(copperpour not_allowed)
			(footprints allowed)
		)
		(placement
			(enabled no)
			(sheetname "")
		)
		(fill yes
			(thermal_gap 0.5)
			(thermal_bridge_width 0.5)
			(island_removal_mode 0)
		)
		(polygon
			(pts
				(arc
					(start 214.867236 -131.435856)
					(mid 213.089236 -131.435856)
					(end 214.867236 -131.435856)
				)
			)
		)
	)
	(zone
		(layers "In1.Cu" "In3.Cu" "In6.Cu" "In8.Cu")
		(hatch none 0.5)
		(connect_pads
			(clearance 0)
		)
		(min_thickness 0.25)
		(keepout
			(tracks not_allowed)
			(vias allowed)
			(pads allowed)
			(copperpour not_allowed)
			(footprints allowed)
		)
		(placement
			(enabled no)
			(sheetname "")
		)
		(fill yes
			(thermal_gap 0.5)
			(thermal_bridge_width 0.5)
			(island_removal_mode 0)
		)
		(polygon
			(pts
				(arc
					(start 218.399868 -104.4321)
					(mid 216.621868 -104.4321)
					(end 218.399868 -104.4321)
				)
			)
		)
	)
	(zone
		(layers "In1.Cu" "In3.Cu" "In6.Cu" "In8.Cu")
		(hatch none 0.5)
		(connect_pads
			(clearance 0)
		)
		(min_thickness 0.25)
		(keepout
			(tracks not_allowed)
			(vias allowed)
			(pads allowed)
			(copperpour not_allowed)
			(footprints allowed)
		)
		(placement
			(enabled no)
			(sheetname "")
		)
		(fill yes
			(thermal_gap 0.5)
			(thermal_bridge_width 0.5)
			(island_removal_mode 0)
		)
		(polygon
			(pts
				(arc
					(start 222.188278 -121.331736)
					(mid 220.410278 -121.331736)
					(end 222.188278 -121.331736)
				)
			)
		)
	)
	(zone
		(layers "In1.Cu" "In3.Cu" "In6.Cu" "In8.Cu")
		(hatch none 0.5)
		(connect_pads
			(clearance 0)
		)
		(min_thickness 0.25)
		(keepout
			(tracks not_allowed)
			(vias allowed)
			(pads allowed)
			(copperpour not_allowed)
			(footprints allowed)
		)
		(placement
			(enabled no)
			(sheetname "")
		)
		(fill yes
			(thermal_gap 0.5)
			(thermal_bridge_width 0.5)
			(island_removal_mode 0)
		)
		(polygon
			(pts
				(arc
					(start 183.63946 -52.197)
					(mid 181.86146 -52.197)
					(end 183.63946 -52.197)
				)
			)
		)
	)
	(zone
		(layers "In1.Cu" "In3.Cu" "In6.Cu" "In8.Cu")
		(hatch none 0.5)
		(connect_pads
			(clearance 0)
		)
		(min_thickness 0.25)
		(keepout
			(tracks not_allowed)
			(vias allowed)
			(pads allowed)
			(copperpour not_allowed)
			(footprints allowed)
		)
		(placement
			(enabled no)
			(sheetname "")
		)
		(fill yes
			(thermal_gap 0.5)
			(thermal_bridge_width 0.5)
			(island_removal_mode 0)
		)
		(polygon
			(pts
				(arc
					(start 270.891 -124.333)
					(mid 269.113 -124.333)
					(end 270.891 -124.333)
				)
			)
		)
	)
	(zone
		(layers "In1.Cu" "In3.Cu" "In6.Cu" "In8.Cu")
		(hatch none 0.5)
		(connect_pads
			(clearance 0)
		)
		(min_thickness 0.25)
		(keepout
			(tracks not_allowed)
			(vias allowed)
			(pads allowed)
			(copperpour not_allowed)
			(footprints allowed)
		)
		(placement
			(enabled no)
			(sheetname "")
		)
		(fill yes
			(thermal_gap 0.5)
			(thermal_bridge_width 0.5)
			(island_removal_mode 0)
		)
		(polygon
			(pts
				(arc
					(start 204.777086 -123.528328)
					(mid 202.999086 -123.528328)
					(end 204.777086 -123.528328)
				)
			)
		)
	)
	(zone
		(layers "In1.Cu" "In3.Cu" "In6.Cu" "In8.Cu")
		(hatch none 0.5)
		(connect_pads
			(clearance 0)
		)
		(min_thickness 0.25)
		(keepout
			(tracks not_allowed)
			(vias allowed)
			(pads allowed)
			(copperpour not_allowed)
			(footprints allowed)
		)
		(placement
			(enabled no)
			(sheetname "")
		)
		(fill yes
			(thermal_gap 0.5)
			(thermal_bridge_width 0.5)
			(island_removal_mode 0)
		)
		(polygon
			(pts
				(arc
					(start 221.447868 -103.6701)
					(mid 219.669868 -103.6701)
					(end 221.447868 -103.6701)
				)
			)
		)
	)
	(zone
		(layers "In1.Cu" "In3.Cu" "In6.Cu" "In8.Cu")
		(hatch none 0.5)
		(connect_pads
			(clearance 0)
		)
		(min_thickness 0.25)
		(keepout
			(tracks not_allowed)
			(vias allowed)
			(pads allowed)
			(copperpour not_allowed)
			(footprints allowed)
		)
		(placement
			(enabled no)
			(sheetname "")
		)
		(fill yes
			(thermal_gap 0.5)
			(thermal_bridge_width 0.5)
			(island_removal_mode 0)
		)
		(polygon
			(pts
				(arc
					(start 216.347802 -131.42214)
					(mid 214.569802 -131.42214)
					(end 216.347802 -131.42214)
				)
			)
		)
	)
	(zone
		(layers "In1.Cu" "In3.Cu" "In6.Cu" "In8.Cu")
		(hatch none 0.5)
		(connect_pads
			(clearance 0)
		)
		(min_thickness 0.25)
		(keepout
			(tracks not_allowed)
			(vias allowed)
			(pads allowed)
			(copperpour not_allowed)
			(footprints allowed)
		)
		(placement
			(enabled no)
			(sheetname "")
		)
		(fill yes
			(thermal_gap 0.5)
			(thermal_bridge_width 0.5)
			(island_removal_mode 0)
		)
		(polygon
			(pts
				(arc
					(start 204.00137 -121.331736)
					(mid 202.22337 -121.331736)
					(end 204.00137 -121.331736)
				)
			)
		)
	)
	(zone
		(layers "In1.Cu" "In3.Cu" "In6.Cu" "In8.Cu")
		(hatch none 0.5)
		(connect_pads
			(clearance 0)
		)
		(min_thickness 0.25)
		(keepout
			(tracks not_allowed)
			(vias allowed)
			(pads allowed)
			(copperpour not_allowed)
			(footprints allowed)
		)
		(placement
			(enabled no)
			(sheetname "")
		)
		(fill yes
			(thermal_gap 0.5)
			(thermal_bridge_width 0.5)
			(island_removal_mode 0)
		)
		(polygon
			(pts
				(arc
					(start 272.415 -85.852)
					(mid 270.637 -85.852)
					(end 272.415 -85.852)
				)
			)
		)
	)
	(zone
		(layers "In1.Cu" "In3.Cu" "In6.Cu" "In8.Cu")
		(hatch none 0.5)
		(connect_pads
			(clearance 0)
		)
		(min_thickness 0.25)
		(keepout
			(tracks not_allowed)
			(vias allowed)
			(pads allowed)
			(copperpour not_allowed)
			(footprints allowed)
		)
		(placement
			(enabled no)
			(sheetname "")
		)
		(fill yes
			(thermal_gap 0.5)
			(thermal_bridge_width 0.5)
			(island_removal_mode 0)
		)
		(polygon
			(pts
				(arc
					(start 270.129 -113.03)
					(mid 268.351 -113.03)
					(end 270.129 -113.03)
				)
			)
		)
	)
	(zone
		(layers "In1.Cu" "In3.Cu" "In6.Cu" "In8.Cu")
		(hatch none 0.5)
		(connect_pads
			(clearance 0)
		)
		(min_thickness 0.25)
		(keepout
			(tracks not_allowed)
			(vias allowed)
			(pads allowed)
			(copperpour not_allowed)
			(footprints allowed)
		)
		(placement
			(enabled no)
			(sheetname "")
		)
		(fill yes
			(thermal_gap 0.5)
			(thermal_bridge_width 0.5)
			(island_removal_mode 0)
		)
		(polygon
			(pts
				(arc
					(start 273.177 -62.484)
					(mid 271.399 -62.484)
					(end 273.177 -62.484)
				)
			)
		)
	)
	(zone
		(layers "In1.Cu" "In3.Cu" "In6.Cu" "In8.Cu")
		(hatch none 0.5)
		(connect_pads
			(clearance 0)
		)
		(min_thickness 0.25)
		(keepout
			(tracks not_allowed)
			(vias allowed)
			(pads allowed)
			(copperpour not_allowed)
			(footprints allowed)
		)
		(placement
			(enabled no)
			(sheetname "")
		)
		(fill yes
			(thermal_gap 0.5)
			(thermal_bridge_width 0.5)
			(island_removal_mode 0)
		)
		(polygon
			(pts
				(arc
					(start 270.129 -76.835)
					(mid 268.351 -76.835)
					(end 270.129 -76.835)
				)
			)
		)
	)
	(zone
		(layers "In1.Cu" "In3.Cu" "In6.Cu" "In8.Cu")
		(hatch none 0.5)
		(connect_pads
			(clearance 0)
		)
		(min_thickness 0.25)
		(keepout
			(tracks not_allowed)
			(vias allowed)
			(pads allowed)
			(copperpour not_allowed)
			(footprints allowed)
		)
		(placement
			(enabled no)
			(sheetname "")
		)
		(fill yes
			(thermal_gap 0.5)
			(thermal_bridge_width 0.5)
			(island_removal_mode 0)
		)
		(polygon
			(pts
				(arc
					(start 271.653 -61.722)
					(mid 269.875 -61.722)
					(end 271.653 -61.722)
				)
			)
		)
	)
	(zone
		(layers "In1.Cu" "In3.Cu" "In6.Cu" "In8.Cu")
		(hatch none 0.5)
		(connect_pads
			(clearance 0)
		)
		(min_thickness 0.25)
		(keepout
			(tracks not_allowed)
			(vias allowed)
			(pads allowed)
			(copperpour not_allowed)
			(footprints allowed)
		)
		(placement
			(enabled no)
			(sheetname "")
		)
		(fill yes
			(thermal_gap 0.5)
			(thermal_bridge_width 0.5)
			(island_removal_mode 0)
		)
		(polygon
			(pts
				(arc
					(start 270.891 -122.809)
					(mid 269.113 -122.809)
					(end 270.891 -122.809)
				)
			)
		)
	)
	(zone
		(layers "In1.Cu" "In3.Cu" "In6.Cu" "In8.Cu")
		(hatch none 0.5)
		(connect_pads
			(clearance 0)
		)
		(min_thickness 0.25)
		(keepout
			(tracks not_allowed)
			(vias allowed)
			(pads allowed)
			(copperpour not_allowed)
			(footprints allowed)
		)
		(placement
			(enabled no)
			(sheetname "")
		)
		(fill yes
			(thermal_gap 0.5)
			(thermal_bridge_width 0.5)
			(island_removal_mode 0)
		)
		(polygon
			(pts
				(arc
					(start 270.891 -63.246)
					(mid 269.113 -63.246)
					(end 270.891 -63.246)
				)
			)
		)
	)
	(zone
		(layers "In1.Cu" "In3.Cu" "In6.Cu" "In8.Cu")
		(hatch none 0.5)
		(connect_pads
			(clearance 0)
		)
		(min_thickness 0.25)
		(keepout
			(tracks not_allowed)
			(vias allowed)
			(pads allowed)
			(copperpour not_allowed)
			(footprints allowed)
		)
		(placement
			(enabled no)
			(sheetname "")
		)
		(fill yes
			(thermal_gap 0.5)
			(thermal_bridge_width 0.5)
			(island_removal_mode 0)
		)
		(polygon
			(pts
				(arc
					(start 217.708226 -105.883202)
					(mid 215.930226 -105.883202)
					(end 217.708226 -105.883202)
				)
			)
		)
	)
	(zone
		(layers "In1.Cu" "In3.Cu" "In6.Cu" "In8.Cu")
		(hatch none 0.5)
		(connect_pads
			(clearance 0)
		)
		(min_thickness 0.25)
		(keepout
			(tracks not_allowed)
			(vias allowed)
			(pads allowed)
			(copperpour not_allowed)
			(footprints allowed)
		)
		(placement
			(enabled no)
			(sheetname "")
		)
		(fill yes
			(thermal_gap 0.5)
			(thermal_bridge_width 0.5)
			(island_removal_mode 0)
		)
		(polygon
			(pts
				(arc
					(start 41.656 -105.283)
					(mid 39.878 -105.283)
					(end 41.656 -105.283)
				)
			)
		)
	)
	(zone
		(layers "In1.Cu" "In3.Cu" "In6.Cu" "In8.Cu")
		(hatch none 0.5)
		(connect_pads
			(clearance 0)
		)
		(min_thickness 0.25)
		(keepout
			(tracks not_allowed)
			(vias allowed)
			(pads allowed)
			(copperpour not_allowed)
			(footprints allowed)
		)
		(placement
			(enabled no)
			(sheetname "")
		)
		(fill yes
			(thermal_gap 0.5)
			(thermal_bridge_width 0.5)
			(island_removal_mode 0)
		)
		(polygon
			(pts
				(arc
					(start 220.677994 -123.528328)
					(mid 218.899994 -123.528328)
					(end 220.677994 -123.528328)
				)
			)
		)
	)
	(zone
		(layers "In1.Cu" "In3.Cu" "In6.Cu" "In8.Cu")
		(hatch none 0.5)
		(connect_pads
			(clearance 0)
		)
		(min_thickness 0.25)
		(keepout
			(tracks not_allowed)
			(vias allowed)
			(pads allowed)
			(copperpour not_allowed)
			(footprints allowed)
		)
		(placement
			(enabled no)
			(sheetname "")
		)
		(fill yes
			(thermal_gap 0.5)
			(thermal_bridge_width 0.5)
			(island_removal_mode 0)
		)
		(polygon
			(pts
				(arc
					(start 47.94504 -52.9209)
					(mid 46.16704 -52.9209)
					(end 47.94504 -52.9209)
				)
			)
		)
	)
	(zone
		(layers "In1.Cu" "In3.Cu" "In6.Cu" "In8.Cu")
		(hatch none 0.5)
		(connect_pads
			(clearance 0)
		)
		(min_thickness 0.25)
		(keepout
			(tracks not_allowed)
			(vias allowed)
			(pads allowed)
			(copperpour not_allowed)
			(footprints allowed)
		)
		(placement
			(enabled no)
			(sheetname "")
		)
		(fill yes
			(thermal_gap 0.5)
			(thermal_bridge_width 0.5)
			(island_removal_mode 0)
		)
		(polygon
			(pts
				(arc
					(start 217.825828 -128.37414)
					(mid 216.047828 -128.37414)
					(end 217.825828 -128.37414)
				)
			)
		)
	)
	(zone
		(layers "In1.Cu" "In3.Cu" "In6.Cu" "In8.Cu")
		(hatch none 0.5)
		(connect_pads
			(clearance 0)
		)
		(min_thickness 0.25)
		(keepout
			(tracks not_allowed)
			(vias allowed)
			(pads allowed)
			(copperpour not_allowed)
			(footprints allowed)
		)
		(placement
			(enabled no)
			(sheetname "")
		)
		(fill yes
			(thermal_gap 0.5)
			(thermal_bridge_width 0.5)
			(island_removal_mode 0)
		)
		(polygon
			(pts
				(arc
					(start 217.063828 -131.42214)
					(mid 215.285828 -131.42214)
					(end 217.063828 -131.42214)
				)
			)
		)
	)
	(zone
		(layers "In1.Cu" "In3.Cu" "In6.Cu" "In8.Cu")
		(hatch none 0.5)
		(connect_pads
			(clearance 0)
		)
		(min_thickness 0.25)
		(keepout
			(tracks not_allowed)
			(vias allowed)
			(pads allowed)
			(copperpour not_allowed)
			(footprints allowed)
		)
		(placement
			(enabled no)
			(sheetname "")
		)
		(fill yes
			(thermal_gap 0.5)
			(thermal_bridge_width 0.5)
			(island_removal_mode 0)
		)
		(polygon
			(pts
				(arc
					(start 270.5354 -82.230468)
					(mid 268.7574 -82.230468)
					(end 270.5354 -82.230468)
				)
			)
		)
	)
	(zone
		(layers "In1.Cu" "In3.Cu" "In6.Cu" "In8.Cu")
		(hatch none 0.5)
		(connect_pads
			(clearance 0)
		)
		(min_thickness 0.25)
		(keepout
			(tracks not_allowed)
			(vias allowed)
			(pads allowed)
			(copperpour not_allowed)
			(footprints allowed)
		)
		(placement
			(enabled no)
			(sheetname "")
		)
		(fill yes
			(thermal_gap 0.5)
			(thermal_bridge_width 0.5)
			(island_removal_mode 0)
		)
		(polygon
			(pts
				(arc
					(start 234.706668 -127.300736)
					(mid 232.928668 -127.300736)
					(end 234.706668 -127.300736)
				)
			)
		)
	)
	(zone
		(layers "In1.Cu" "In3.Cu" "In6.Cu" "In8.Cu")
		(hatch none 0.5)
		(connect_pads
			(clearance 0)
		)
		(min_thickness 0.25)
		(keepout
			(tracks not_allowed)
			(vias allowed)
			(pads allowed)
			(copperpour not_allowed)
			(footprints allowed)
		)
		(placement
			(enabled no)
			(sheetname "")
		)
		(fill yes
			(thermal_gap 0.5)
			(thermal_bridge_width 0.5)
			(island_removal_mode 0)
		)
		(polygon
			(pts
				(arc
					(start 217.063828 -128.37414)
					(mid 215.285828 -128.37414)
					(end 217.063828 -128.37414)
				)
			)
		)
	)
	(zone
		(layers "In1.Cu" "In3.Cu" "In6.Cu" "In8.Cu")
		(hatch none 0.5)
		(connect_pads
			(clearance 0)
		)
		(min_thickness 0.25)
		(keepout
			(tracks not_allowed)
			(vias allowed)
			(pads allowed)
			(copperpour not_allowed)
			(footprints allowed)
		)
		(placement
			(enabled no)
			(sheetname "")
		)
		(fill yes
			(thermal_gap 0.5)
			(thermal_bridge_width 0.5)
			(island_removal_mode 0)
		)
		(polygon
			(pts
				(arc
					(start 205.52537 -121.331736)
					(mid 203.74737 -121.331736)
					(end 205.52537 -121.331736)
				)
			)
		)
	)
	(zone
		(layers "In1.Cu" "In3.Cu" "In6.Cu" "In8.Cu")
		(hatch none 0.5)
		(connect_pads
			(clearance 0)
		)
		(min_thickness 0.25)
		(keepout
			(tracks not_allowed)
			(vias allowed)
			(pads allowed)
			(copperpour not_allowed)
			(footprints allowed)
		)
		(placement
			(enabled no)
			(sheetname "")
		)
		(fill yes
			(thermal_gap 0.5)
			(thermal_bridge_width 0.5)
			(island_removal_mode 0)
		)
		(polygon
			(pts
				(arc
					(start 43.47464 -53.3019)
					(mid 41.69664 -53.3019)
					(end 43.47464 -53.3019)
				)
			)
		)
	)
	(zone
		(layers "In1.Cu" "In3.Cu" "In6.Cu" "In8.Cu")
		(hatch none 0.5)
		(connect_pads
			(clearance 0)
		)
		(min_thickness 0.25)
		(keepout
			(tracks not_allowed)
			(vias allowed)
			(pads allowed)
			(copperpour not_allowed)
			(footprints allowed)
		)
		(placement
			(enabled no)
			(sheetname "")
		)
		(fill yes
			(thermal_gap 0.5)
			(thermal_bridge_width 0.5)
			(island_removal_mode 0)
		)
		(polygon
			(pts
				(arc
					(start 205.441042 -102.9081)
					(mid 203.663042 -102.9081)
					(end 205.441042 -102.9081)
				)
			)
		)
	)
	(zone
		(layers "In1.Cu" "In3.Cu" "In6.Cu" "In8.Cu")
		(hatch none 0.5)
		(connect_pads
			(clearance 0)
		)
		(min_thickness 0.25)
		(keepout
			(tracks not_allowed)
			(vias allowed)
			(pads allowed)
			(copperpour not_allowed)
			(footprints allowed)
		)
		(placement
			(enabled no)
			(sheetname "")
		)
		(fill yes
			(thermal_gap 0.5)
			(thermal_bridge_width 0.5)
			(island_removal_mode 0)
		)
		(polygon
			(pts
				(arc
					(start 206.203042 -105.134664)
					(mid 204.425042 -105.134664)
					(end 206.203042 -105.134664)
				)
			)
		)
	)
	(zone
		(layers "In1.Cu" "In3.Cu" "In6.Cu" "In8.Cu")
		(hatch none 0.5)
		(connect_pads
			(clearance 0)
		)
		(min_thickness 0.25)
		(keepout
			(tracks not_allowed)
			(vias allowed)
			(pads allowed)
			(copperpour not_allowed)
			(footprints allowed)
		)
		(placement
			(enabled no)
			(sheetname "")
		)
		(fill yes
			(thermal_gap 0.5)
			(thermal_bridge_width 0.5)
			(island_removal_mode 0)
		)
		(polygon
			(pts
				(arc
					(start 100.076 -50.419)
					(mid 98.298 -50.419)
					(end 100.076 -50.419)
				)
			)
		)
	)
	(zone
		(layers "In1.Cu" "In3.Cu" "In6.Cu" "In8.Cu")
		(hatch none 0.5)
		(connect_pads
			(clearance 0)
		)
		(min_thickness 0.25)
		(keepout
			(tracks not_allowed)
			(vias allowed)
			(pads allowed)
			(copperpour not_allowed)
			(footprints allowed)
		)
		(placement
			(enabled no)
			(sheetname "")
		)
		(fill yes
			(thermal_gap 0.5)
			(thermal_bridge_width 0.5)
			(island_removal_mode 0)
		)
		(polygon
			(pts
				(arc
					(start 271.78 -139.7)
					(mid 270.002 -139.7)
					(end 271.78 -139.7)
				)
			)
		)
	)
	(zone
		(layers "In1.Cu" "In3.Cu" "In6.Cu" "In8.Cu")
		(hatch none 0.5)
		(connect_pads
			(clearance 0)
		)
		(min_thickness 0.25)
		(keepout
			(tracks not_allowed)
			(vias allowed)
			(pads allowed)
			(copperpour not_allowed)
			(footprints allowed)
		)
		(placement
			(enabled no)
			(sheetname "")
		)
		(fill yes
			(thermal_gap 0.5)
			(thermal_bridge_width 0.5)
			(island_removal_mode 0)
		)
		(polygon
			(pts
				(arc
					(start 270.5354 -130.490468)
					(mid 268.7574 -130.490468)
					(end 270.5354 -130.490468)
				)
			)
		)
	)
	(zone
		(layers "In1.Cu" "In3.Cu" "In6.Cu" "In8.Cu")
		(hatch none 0.5)
		(connect_pads
			(clearance 0)
		)
		(min_thickness 0.25)
		(keepout
			(tracks not_allowed)
			(vias allowed)
			(pads allowed)
			(copperpour not_allowed)
			(footprints allowed)
		)
		(placement
			(enabled no)
			(sheetname "")
		)
		(fill yes
			(thermal_gap 0.5)
			(thermal_bridge_width 0.5)
			(island_removal_mode 0)
		)
		(polygon
			(pts
				(arc
					(start 222.209868 -103.6701)
					(mid 220.431868 -103.6701)
					(end 222.209868 -103.6701)
				)
			)
		)
	)
	(zone
		(layers "In1.Cu" "In3.Cu" "In6.Cu" "In8.Cu")
		(hatch none 0.5)
		(connect_pads
			(clearance 0)
		)
		(min_thickness 0.25)
		(keepout
			(tracks not_allowed)
			(vias allowed)
			(pads allowed)
			(copperpour not_allowed)
			(footprints allowed)
		)
		(placement
			(enabled no)
			(sheetname "")
		)
		(fill yes
			(thermal_gap 0.5)
			(thermal_bridge_width 0.5)
			(island_removal_mode 0)
		)
		(polygon
			(pts
				(arc
					(start 43.469306 -136.906)
					(mid 40.624506 -136.906)
					(end 43.469306 -136.906)
				)
			)
		)
	)
	(zone
		(layers "In1.Cu" "In3.Cu" "In6.Cu" "In8.Cu")
		(hatch none 0.5)
		(connect_pads
			(clearance 0)
		)
		(min_thickness 0.25)
		(keepout
			(tracks not_allowed)
			(vias allowed)
			(pads allowed)
			(copperpour not_allowed)
			(footprints allowed)
		)
		(placement
			(enabled no)
			(sheetname "")
		)
		(fill yes
			(thermal_gap 0.5)
			(thermal_bridge_width 0.5)
			(island_removal_mode 0)
		)
		(polygon
			(pts
				(arc
					(start 208.57337 -121.331736)
					(mid 206.79537 -121.331736)
					(end 208.57337 -121.331736)
				)
			)
		)
	)
	(zone
		(layers "In1.Cu" "In3.Cu" "In6.Cu" "In8.Cu")
		(hatch none 0.5)
		(connect_pads
			(clearance 0)
		)
		(min_thickness 0.25)
		(keepout
			(tracks not_allowed)
			(vias allowed)
			(pads allowed)
			(copperpour not_allowed)
			(footprints allowed)
		)
		(placement
			(enabled no)
			(sheetname "")
		)
		(fill yes
			(thermal_gap 0.5)
			(thermal_bridge_width 0.5)
			(island_removal_mode 0)
		)
		(polygon
			(pts
				(arc
					(start 150.876 -49.657)
					(mid 149.098 -49.657)
					(end 150.876 -49.657)
				)
			)
		)
	)
	(zone
		(layers "In1.Cu" "In3.Cu" "In6.Cu" "In8.Cu")
		(hatch none 0.5)
		(connect_pads
			(clearance 0)
		)
		(min_thickness 0.25)
		(keepout
			(tracks not_allowed)
			(vias allowed)
			(pads allowed)
			(copperpour not_allowed)
			(footprints allowed)
		)
		(placement
			(enabled no)
			(sheetname "")
		)
		(fill yes
			(thermal_gap 0.5)
			(thermal_bridge_width 0.5)
			(island_removal_mode 0)
		)
		(polygon
			(pts
				(arc
					(start 123.7996 -126.492)
					(mid 122.0216 -126.492)
					(end 123.7996 -126.492)
				)
			)
		)
	)
	(zone
		(layers "In1.Cu" "In3.Cu" "In6.Cu" "In8.Cu")
		(hatch none 0.5)
		(connect_pads
			(clearance 0)
		)
		(min_thickness 0.25)
		(keepout
			(tracks not_allowed)
			(vias allowed)
			(pads allowed)
			(copperpour not_allowed)
			(footprints allowed)
		)
		(placement
			(enabled no)
			(sheetname "")
		)
		(fill yes
			(thermal_gap 0.5)
			(thermal_bridge_width 0.5)
			(island_removal_mode 0)
		)
		(polygon
			(pts
				(arc
					(start 45.25264 -52.2859)
					(mid 43.47464 -52.2859)
					(end 45.25264 -52.2859)
				)
			)
		)
	)
	(zone
		(layers "In1.Cu" "In3.Cu" "In6.Cu" "In8.Cu")
		(hatch none 0.5)
		(connect_pads
			(clearance 0)
		)
		(min_thickness 0.25)
		(keepout
			(tracks not_allowed)
			(vias allowed)
			(pads allowed)
			(copperpour not_allowed)
			(footprints allowed)
		)
		(placement
			(enabled no)
			(sheetname "")
		)
		(fill yes
			(thermal_gap 0.5)
			(thermal_bridge_width 0.5)
			(island_removal_mode 0)
		)
		(polygon
			(pts
				(arc
					(start 273.177 -65.532)
					(mid 271.399 -65.532)
					(end 273.177 -65.532)
				)
			)
		)
	)
	(zone
		(layers "In1.Cu" "In3.Cu" "In6.Cu" "In8.Cu")
		(hatch none 0.5)
		(connect_pads
			(clearance 0)
		)
		(min_thickness 0.25)
		(keepout
			(tracks not_allowed)
			(vias allowed)
			(pads allowed)
			(copperpour not_allowed)
			(footprints allowed)
		)
		(placement
			(enabled no)
			(sheetname "")
		)
		(fill yes
			(thermal_gap 0.5)
			(thermal_bridge_width 0.5)
			(island_removal_mode 0)
		)
		(polygon
			(pts
				(arc
					(start 271.653 -122.047)
					(mid 269.875 -122.047)
					(end 271.653 -122.047)
				)
			)
		)
	)
	(zone
		(layers "In1.Cu" "In3.Cu" "In6.Cu" "In8.Cu")
		(hatch none 0.5)
		(connect_pads
			(clearance 0)
		)
		(min_thickness 0.25)
		(keepout
			(tracks not_allowed)
			(vias allowed)
			(pads allowed)
			(copperpour not_allowed)
			(footprints allowed)
		)
		(placement
			(enabled no)
			(sheetname "")
		)
		(fill yes
			(thermal_gap 0.5)
			(thermal_bridge_width 0.5)
			(island_removal_mode 0)
		)
		(polygon
			(pts
				(arc
					(start 270.891 -122.047)
					(mid 269.113 -122.047)
					(end 270.891 -122.047)
				)
			)
		)
	)
	(zone
		(layers "In1.Cu" "In3.Cu" "In6.Cu" "In8.Cu")
		(hatch none 0.5)
		(connect_pads
			(clearance 0)
		)
		(min_thickness 0.25)
		(keepout
			(tracks not_allowed)
			(vias allowed)
			(pads allowed)
			(copperpour not_allowed)
			(footprints allowed)
		)
		(placement
			(enabled no)
			(sheetname "")
		)
		(fill yes
			(thermal_gap 0.5)
			(thermal_bridge_width 0.5)
			(island_removal_mode 0)
		)
		(polygon
			(pts
				(arc
					(start 210.688174 -60.96)
					(mid 207.894174 -60.96)
					(end 210.688174 -60.96)
				)
			)
		)
	)
	(zone
		(layers "In1.Cu" "In3.Cu" "In6.Cu" "In8.Cu")
		(hatch none 0.5)
		(connect_pads
			(clearance 0)
		)
		(min_thickness 0.25)
		(keepout
			(tracks not_allowed)
			(vias allowed)
			(pads allowed)
			(copperpour not_allowed)
			(footprints allowed)
		)
		(placement
			(enabled no)
			(sheetname "")
		)
		(fill yes
			(thermal_gap 0.5)
			(thermal_bridge_width 0.5)
			(island_removal_mode 0)
		)
		(polygon
			(pts
				(arc
					(start 205.441042 -103.6701)
					(mid 203.663042 -103.6701)
					(end 205.441042 -103.6701)
				)
			)
		)
	)
	(zone
		(layers "In1.Cu" "In3.Cu" "In6.Cu" "In8.Cu")
		(hatch none 0.5)
		(connect_pads
			(clearance 0)
		)
		(min_thickness 0.25)
		(keepout
			(tracks not_allowed)
			(vias allowed)
			(pads allowed)
			(copperpour not_allowed)
			(footprints allowed)
		)
		(placement
			(enabled no)
			(sheetname "")
		)
		(fill yes
			(thermal_gap 0.5)
			(thermal_bridge_width 0.5)
			(island_removal_mode 0)
		)
		(polygon
			(pts
				(arc
					(start 273.177 -122.047)
					(mid 271.399 -122.047)
					(end 273.177 -122.047)
				)
			)
		)
	)
	(zone
		(layers "In1.Cu" "In3.Cu" "In6.Cu" "In8.Cu")
		(hatch none 0.5)
		(connect_pads
			(clearance 0)
		)
		(min_thickness 0.25)
		(keepout
			(tracks not_allowed)
			(vias allowed)
			(pads allowed)
			(copperpour not_allowed)
			(footprints allowed)
		)
		(placement
			(enabled no)
			(sheetname "")
		)
		(fill yes
			(thermal_gap 0.5)
			(thermal_bridge_width 0.5)
			(island_removal_mode 0)
		)
		(polygon
			(pts
				(arc
					(start 272.542 -140.462)
					(mid 270.764 -140.462)
					(end 272.542 -140.462)
				)
			)
		)
	)
	(zone
		(layers "In1.Cu" "In3.Cu" "In6.Cu" "In8.Cu")
		(hatch none 0.5)
		(connect_pads
			(clearance 0)
		)
		(min_thickness 0.25)
		(keepout
			(tracks not_allowed)
			(vias allowed)
			(pads allowed)
			(copperpour not_allowed)
			(footprints allowed)
		)
		(placement
			(enabled no)
			(sheetname "")
		)
		(fill yes
			(thermal_gap 0.5)
			(thermal_bridge_width 0.5)
			(island_removal_mode 0)
		)
		(polygon
			(pts
				(arc
					(start 233.944668 -130.348736)
					(mid 232.166668 -130.348736)
					(end 233.944668 -130.348736)
				)
			)
		)
	)
	(zone
		(layers "In1.Cu" "In3.Cu" "In6.Cu" "In8.Cu")
		(hatch none 0.5)
		(connect_pads
			(clearance 0)
		)
		(min_thickness 0.25)
		(keepout
			(tracks not_allowed)
			(vias allowed)
			(pads allowed)
			(copperpour not_allowed)
			(footprints allowed)
		)
		(placement
			(enabled no)
			(sheetname "")
		)
		(fill yes
			(thermal_gap 0.5)
			(thermal_bridge_width 0.5)
			(island_removal_mode 0)
		)
		(polygon
			(pts
				(arc
					(start 105.537 -51.689)
					(mid 103.759 -51.689)
					(end 105.537 -51.689)
				)
			)
		)
	)
	(zone
		(layers "In1.Cu" "In3.Cu" "In6.Cu" "In8.Cu")
		(hatch none 0.5)
		(connect_pads
			(clearance 0)
		)
		(min_thickness 0.25)
		(keepout
			(tracks not_allowed)
			(vias allowed)
			(pads allowed)
			(copperpour not_allowed)
			(footprints allowed)
		)
		(placement
			(enabled no)
			(sheetname "")
		)
		(fill yes
			(thermal_gap 0.5)
			(thermal_bridge_width 0.5)
			(island_removal_mode 0)
		)
		(polygon
			(pts
				(arc
					(start 13.76172 -76.019914)
					(mid 11.01852 -76.019914)
					(end 13.76172 -76.019914)
				)
			)
		)
	)
	(zone
		(layers "In1.Cu" "In3.Cu" "In6.Cu" "In8.Cu")
		(hatch none 0.5)
		(connect_pads
			(clearance 0)
		)
		(min_thickness 0.25)
		(keepout
			(tracks not_allowed)
			(vias allowed)
			(pads allowed)
			(copperpour not_allowed)
			(footprints allowed)
		)
		(placement
			(enabled no)
			(sheetname "")
		)
		(fill yes
			(thermal_gap 0.5)
			(thermal_bridge_width 0.5)
			(island_removal_mode 0)
		)
		(polygon
			(pts
				(arc
					(start 71.302626 -69.869812)
					(mid 69.524626 -69.869812)
					(end 71.302626 -69.869812)
				)
			)
		)
	)
	(zone
		(layers "In1.Cu" "In3.Cu" "In6.Cu" "In8.Cu")
		(hatch none 0.5)
		(connect_pads
			(clearance 0)
		)
		(min_thickness 0.25)
		(keepout
			(tracks not_allowed)
			(vias allowed)
			(pads allowed)
			(copperpour not_allowed)
			(footprints allowed)
		)
		(placement
			(enabled no)
			(sheetname "")
		)
		(fill yes
			(thermal_gap 0.5)
			(thermal_bridge_width 0.5)
			(island_removal_mode 0)
		)
		(polygon
			(pts
				(arc
					(start 214.867236 -128.387856)
					(mid 213.089236 -128.387856)
					(end 214.867236 -128.387856)
				)
			)
		)
	)
	(zone
		(layers "In1.Cu" "In3.Cu" "In6.Cu" "In8.Cu")
		(hatch none 0.5)
		(connect_pads
			(clearance 0)
		)
		(min_thickness 0.25)
		(keepout
			(tracks not_allowed)
			(vias allowed)
			(pads allowed)
			(copperpour not_allowed)
			(footprints allowed)
		)
		(placement
			(enabled no)
			(sheetname "")
		)
		(fill yes
			(thermal_gap 0.5)
			(thermal_bridge_width 0.5)
			(island_removal_mode 0)
		)
		(polygon
			(pts
				(arc
					(start 221.426278 -122.047762)
					(mid 219.648278 -122.047762)
					(end 221.426278 -122.047762)
				)
			)
		)
	)
	(zone
		(layers "In1.Cu" "In3.Cu" "In6.Cu" "In8.Cu")
		(hatch none 0.5)
		(connect_pads
			(clearance 0)
		)
		(min_thickness 0.25)
		(keepout
			(tracks not_allowed)
			(vias allowed)
			(pads allowed)
			(copperpour not_allowed)
			(footprints allowed)
		)
		(placement
			(enabled no)
			(sheetname "")
		)
		(fill yes
			(thermal_gap 0.5)
			(thermal_bridge_width 0.5)
			(island_removal_mode 0)
		)
		(polygon
			(pts
				(arc
					(start 105.537 -50.419)
					(mid 103.759 -50.419)
					(end 105.537 -50.419)
				)
			)
		)
	)
	(zone
		(layers "In1.Cu" "In3.Cu" "In6.Cu" "In8.Cu")
		(hatch none 0.5)
		(connect_pads
			(clearance 0)
		)
		(min_thickness 0.25)
		(keepout
			(tracks not_allowed)
			(vias allowed)
			(pads allowed)
			(copperpour not_allowed)
			(footprints allowed)
		)
		(placement
			(enabled no)
			(sheetname "")
		)
		(fill yes
			(thermal_gap 0.5)
			(thermal_bridge_width 0.5)
			(island_removal_mode 0)
		)
		(polygon
			(pts
				(arc
					(start 272.542 -137.414)
					(mid 270.764 -137.414)
					(end 272.542 -137.414)
				)
			)
		)
	)
	(zone
		(layers "In1.Cu" "In3.Cu" "In6.Cu" "In8.Cu")
		(hatch none 0.5)
		(connect_pads
			(clearance 0)
		)
		(min_thickness 0.25)
		(keepout
			(tracks not_allowed)
			(vias allowed)
			(pads allowed)
			(copperpour not_allowed)
			(footprints allowed)
		)
		(placement
			(enabled no)
			(sheetname "")
		)
		(fill yes
			(thermal_gap 0.5)
			(thermal_bridge_width 0.5)
			(island_removal_mode 0)
		)
		(polygon
			(pts
				(arc
					(start 214.867236 -132.197856)
					(mid 213.089236 -132.197856)
					(end 214.867236 -132.197856)
				)
			)
		)
	)
	(zone
		(layers "In1.Cu" "In3.Cu" "In6.Cu" "In8.Cu")
		(hatch none 0.5)
		(connect_pads
			(clearance 0)
		)
		(min_thickness 0.25)
		(keepout
			(tracks not_allowed)
			(vias allowed)
			(pads allowed)
			(copperpour not_allowed)
			(footprints allowed)
		)
		(placement
			(enabled no)
			(sheetname "")
		)
		(fill yes
			(thermal_gap 0.5)
			(thermal_bridge_width 0.5)
			(island_removal_mode 0)
		)
		(polygon
			(pts
				(arc
					(start 216.347802 -129.89814)
					(mid 214.569802 -129.89814)
					(end 216.347802 -129.89814)
				)
			)
		)
	)
	(zone
		(layers "In1.Cu" "In3.Cu" "In6.Cu" "In8.Cu")
		(hatch none 0.5)
		(connect_pads
			(clearance 0)
		)
		(min_thickness 0.25)
		(keepout
			(tracks not_allowed)
			(vias allowed)
			(pads allowed)
			(copperpour not_allowed)
			(footprints allowed)
		)
		(placement
			(enabled no)
			(sheetname "")
		)
		(fill yes
			(thermal_gap 0.5)
			(thermal_bridge_width 0.5)
			(island_removal_mode 0)
		)
		(polygon
			(pts
				(arc
					(start 187.853574 -136.906)
					(mid 185.008774 -136.906)
					(end 187.853574 -136.906)
				)
			)
		)
	)
	(zone
		(layers "In1.Cu" "In3.Cu" "In6.Cu" "In8.Cu")
		(hatch none 0.5)
		(connect_pads
			(clearance 0)
		)
		(min_thickness 0.25)
		(keepout
			(tracks not_allowed)
			(vias allowed)
			(pads allowed)
			(copperpour not_allowed)
			(footprints allowed)
		)
		(placement
			(enabled no)
			(sheetname "")
		)
		(fill yes
			(thermal_gap 0.5)
			(thermal_bridge_width 0.5)
			(island_removal_mode 0)
		)
		(polygon
			(pts
				(arc
					(start 44.561506 -126.492)
					(mid 42.783506 -126.492)
					(end 44.561506 -126.492)
				)
			)
		)
	)
	(zone
		(layers "In1.Cu" "In3.Cu" "In6.Cu" "In8.Cu")
		(hatch none 0.5)
		(connect_pads
			(clearance 0)
		)
		(min_thickness 0.25)
		(keepout
			(tracks not_allowed)
			(vias allowed)
			(pads allowed)
			(copperpour not_allowed)
			(footprints allowed)
		)
		(placement
			(enabled no)
			(sheetname "")
		)
		(fill yes
			(thermal_gap 0.5)
			(thermal_bridge_width 0.5)
			(island_removal_mode 0)
		)
		(polygon
			(pts
				(arc
					(start 219.923868 -103.6701)
					(mid 218.145868 -103.6701)
					(end 219.923868 -103.6701)
				)
			)
		)
	)
	(zone
		(layers "In1.Cu" "In3.Cu" "In6.Cu" "In8.Cu")
		(hatch none 0.5)
		(connect_pads
			(clearance 0)
		)
		(min_thickness 0.25)
		(keepout
			(tracks not_allowed)
			(vias allowed)
			(pads allowed)
			(copperpour not_allowed)
			(footprints allowed)
		)
		(placement
			(enabled no)
			(sheetname "")
		)
		(fill yes
			(thermal_gap 0.5)
			(thermal_bridge_width 0.5)
			(island_removal_mode 0)
		)
		(polygon
			(pts
				(arc
					(start 222.950278 -122.809762)
					(mid 221.172278 -122.809762)
					(end 222.950278 -122.809762)
				)
			)
		)
	)
	(zone
		(layers "In1.Cu" "In3.Cu" "In6.Cu" "In8.Cu")
		(hatch none 0.5)
		(connect_pads
			(clearance 0)
		)
		(min_thickness 0.25)
		(keepout
			(tracks not_allowed)
			(vias allowed)
			(pads allowed)
			(copperpour not_allowed)
			(footprints allowed)
		)
		(placement
			(enabled no)
			(sheetname "")
		)
		(fill yes
			(thermal_gap 0.5)
			(thermal_bridge_width 0.5)
			(island_removal_mode 0)
		)
		(polygon
			(pts
				(arc
					(start 207.04937 -122.809762)
					(mid 205.27137 -122.809762)
					(end 207.04937 -122.809762)
				)
			)
		)
	)
	(zone
		(layers "In1.Cu" "In3.Cu" "In6.Cu" "In8.Cu")
		(hatch none 0.5)
		(connect_pads
			(clearance 0)
		)
		(min_thickness 0.25)
		(keepout
			(tracks not_allowed)
			(vias allowed)
			(pads allowed)
			(copperpour not_allowed)
			(footprints allowed)
		)
		(placement
			(enabled no)
			(sheetname "")
		)
		(fill yes
			(thermal_gap 0.5)
			(thermal_bridge_width 0.5)
			(island_removal_mode 0)
		)
		(polygon
			(pts
				(arc
					(start 43.799506 -131.572)
					(mid 42.021506 -131.572)
					(end 43.799506 -131.572)
				)
			)
		)
	)
	(zone
		(layers "In1.Cu" "In3.Cu" "In6.Cu" "In8.Cu")
		(hatch none 0.5)
		(connect_pads
			(clearance 0)
		)
		(min_thickness 0.25)
		(keepout
			(tracks not_allowed)
			(vias allowed)
			(pads allowed)
			(copperpour not_allowed)
			(footprints allowed)
		)
		(placement
			(enabled no)
			(sheetname "")
		)
		(fill yes
			(thermal_gap 0.5)
			(thermal_bridge_width 0.5)
			(island_removal_mode 0)
		)
		(polygon
			(pts
				(arc
					(start 148.336 -60.96)
					(mid 145.542 -60.96)
					(end 148.336 -60.96)
				)
			)
		)
	)
	(zone
		(layers "In1.Cu" "In3.Cu" "In6.Cu" "In8.Cu")
		(hatch none 0.5)
		(connect_pads
			(clearance 0)
		)
		(min_thickness 0.25)
		(keepout
			(tracks not_allowed)
			(vias allowed)
			(pads allowed)
			(copperpour not_allowed)
			(footprints allowed)
		)
		(placement
			(enabled no)
			(sheetname "")
		)
		(fill yes
			(thermal_gap 0.5)
			(thermal_bridge_width 0.5)
			(island_removal_mode 0)
		)
		(polygon
			(pts
				(arc
					(start 270.891 -62.484)
					(mid 269.113 -62.484)
					(end 270.891 -62.484)
				)
			)
		)
	)
	(zone
		(layers "In1.Cu" "In3.Cu" "In6.Cu" "In8.Cu")
		(hatch none 0.5)
		(connect_pads
			(clearance 0)
		)
		(min_thickness 0.25)
		(keepout
			(tracks not_allowed)
			(vias allowed)
			(pads allowed)
			(copperpour not_allowed)
			(footprints allowed)
		)
		(placement
			(enabled no)
			(sheetname "")
		)
		(fill yes
			(thermal_gap 0.5)
			(thermal_bridge_width 0.5)
			(island_removal_mode 0)
		)
		(polygon
			(pts
				(arc
					(start 218.399868 -102.9081)
					(mid 216.621868 -102.9081)
					(end 218.399868 -102.9081)
				)
			)
		)
	)
	(zone
		(layers "In1.Cu" "In3.Cu" "In6.Cu" "In8.Cu")
		(hatch none 0.5)
		(connect_pads
			(clearance 0)
		)
		(min_thickness 0.25)
		(keepout
			(tracks not_allowed)
			(vias allowed)
			(pads allowed)
			(copperpour not_allowed)
			(footprints allowed)
		)
		(placement
			(enabled no)
			(sheetname "")
		)
		(fill yes
			(thermal_gap 0.5)
			(thermal_bridge_width 0.5)
			(island_removal_mode 0)
		)
		(polygon
			(pts
				(arc
					(start 221.426278 -122.809762)
					(mid 219.648278 -122.809762)
					(end 221.426278 -122.809762)
				)
			)
		)
	)
	(zone
		(layers "In1.Cu" "In3.Cu" "In6.Cu" "In8.Cu")
		(hatch none 0.5)
		(connect_pads
			(clearance 0)
		)
		(min_thickness 0.25)
		(keepout
			(tracks not_allowed)
			(vias allowed)
			(pads allowed)
			(copperpour not_allowed)
			(footprints allowed)
		)
		(placement
			(enabled no)
			(sheetname "")
		)
		(fill yes
			(thermal_gap 0.5)
			(thermal_bridge_width 0.5)
			(island_removal_mode 0)
		)
		(polygon
			(pts
				(arc
					(start 71.302626 -68.853812)
					(mid 69.524626 -68.853812)
					(end 71.302626 -68.853812)
				)
			)
		)
	)
	(zone
		(layers "In1.Cu" "In3.Cu" "In6.Cu" "In8.Cu")
		(hatch none 0.5)
		(connect_pads
			(clearance 0)
		)
		(min_thickness 0.25)
		(keepout
			(tracks not_allowed)
			(vias allowed)
			(pads allowed)
			(copperpour not_allowed)
			(footprints allowed)
		)
		(placement
			(enabled no)
			(sheetname "")
		)
		(fill yes
			(thermal_gap 0.5)
			(thermal_bridge_width 0.5)
			(island_removal_mode 0)
		)
		(polygon
			(pts
				(arc
					(start 270.129 -73.787)
					(mid 268.351 -73.787)
					(end 270.129 -73.787)
				)
			)
		)
	)
	(zone
		(layers "In1.Cu" "In3.Cu" "In6.Cu" "In8.Cu")
		(hatch none 0.5)
		(connect_pads
			(clearance 0)
		)
		(min_thickness 0.25)
		(keepout
			(tracks not_allowed)
			(vias allowed)
			(pads allowed)
			(copperpour not_allowed)
			(footprints allowed)
		)
		(placement
			(enabled no)
			(sheetname "")
		)
		(fill yes
			(thermal_gap 0.5)
			(thermal_bridge_width 0.5)
			(island_removal_mode 0)
		)
		(polygon
			(pts
				(arc
					(start 217.616278 -122.809762)
					(mid 215.838278 -122.809762)
					(end 217.616278 -122.809762)
				)
			)
		)
	)
	(zone
		(layers "In1.Cu" "In3.Cu" "In6.Cu" "In8.Cu")
		(hatch none 0.5)
		(connect_pads
			(clearance 0)
		)
		(min_thickness 0.25)
		(keepout
			(tracks not_allowed)
			(vias allowed)
			(pads allowed)
			(copperpour not_allowed)
			(footprints allowed)
		)
		(placement
			(enabled no)
			(sheetname "")
		)
		(fill yes
			(thermal_gap 0.5)
			(thermal_bridge_width 0.5)
			(island_removal_mode 0)
		)
		(polygon
			(pts
				(arc
					(start 42.2529 -56.805068)
					(mid 40.4749 -56.805068)
					(end 42.2529 -56.805068)
				)
			)
		)
	)
	(zone
		(layers "In1.Cu" "In3.Cu" "In6.Cu" "In8.Cu")
		(hatch none 0.5)
		(connect_pads
			(clearance 0)
		)
		(min_thickness 0.25)
		(keepout
			(tracks not_allowed)
			(vias allowed)
			(pads allowed)
			(copperpour not_allowed)
			(footprints allowed)
		)
		(placement
			(enabled no)
			(sheetname "")
		)
		(fill yes
			(thermal_gap 0.5)
			(thermal_bridge_width 0.5)
			(island_removal_mode 0)
		)
		(polygon
			(pts
				(arc
					(start 214.867236 -129.149856)
					(mid 213.089236 -129.149856)
					(end 214.867236 -129.149856)
				)
			)
		)
	)
	(zone
		(layers "In1.Cu" "In3.Cu" "In6.Cu" "In8.Cu")
		(hatch none 0.5)
		(connect_pads
			(clearance 0)
		)
		(min_thickness 0.25)
		(keepout
			(tracks not_allowed)
			(vias allowed)
			(pads allowed)
			(copperpour not_allowed)
			(footprints allowed)
		)
		(placement
			(enabled no)
			(sheetname "")
		)
		(fill yes
			(thermal_gap 0.5)
			(thermal_bridge_width 0.5)
			(island_removal_mode 0)
		)
		(polygon
			(pts
				(arc
					(start 73.334626 -71.901812)
					(mid 71.556626 -71.901812)
					(end 73.334626 -71.901812)
				)
			)
		)
	)
	(zone
		(layers "In1.Cu" "In3.Cu" "In6.Cu" "In8.Cu")
		(hatch none 0.5)
		(connect_pads
			(clearance 0)
		)
		(min_thickness 0.25)
		(keepout
			(tracks not_allowed)
			(vias allowed)
			(pads allowed)
			(copperpour not_allowed)
			(footprints allowed)
		)
		(placement
			(enabled no)
			(sheetname "")
		)
		(fill yes
			(thermal_gap 0.5)
			(thermal_bridge_width 0.5)
			(island_removal_mode 0)
		)
		(polygon
			(pts
				(arc
					(start 47.18304 -50.0507)
					(mid 45.40504 -50.0507)
					(end 47.18304 -50.0507)
				)
			)
		)
	)
	(zone
		(layers "In1.Cu" "In3.Cu" "In6.Cu" "In8.Cu")
		(hatch none 0.5)
		(connect_pads
			(clearance 0)
		)
		(min_thickness 0.25)
		(keepout
			(tracks not_allowed)
			(vias allowed)
			(pads allowed)
			(copperpour not_allowed)
			(footprints allowed)
		)
		(placement
			(enabled no)
			(sheetname "")
		)
		(fill yes
			(thermal_gap 0.5)
			(thermal_bridge_width 0.5)
			(island_removal_mode 0)
		)
		(polygon
			(pts
				(arc
					(start 45.73524 -50.0507)
					(mid 43.95724 -50.0507)
					(end 45.73524 -50.0507)
				)
			)
		)
	)
	(zone
		(layers "In1.Cu" "In3.Cu" "In6.Cu" "In8.Cu")
		(hatch none 0.5)
		(connect_pads
			(clearance 0)
		)
		(min_thickness 0.25)
		(keepout
			(tracks not_allowed)
			(vias allowed)
			(pads allowed)
			(copperpour not_allowed)
			(footprints allowed)
		)
		(placement
			(enabled no)
			(sheetname "")
		)
		(fill yes
			(thermal_gap 0.5)
			(thermal_bridge_width 0.5)
			(island_removal_mode 0)
		)
		(polygon
			(pts
				(arc
					(start 204.76337 -120.569736)
					(mid 202.98537 -120.569736)
					(end 204.76337 -120.569736)
				)
			)
		)
	)
	(zone
		(layers "In1.Cu" "In3.Cu" "In6.Cu" "In8.Cu")
		(hatch none 0.5)
		(connect_pads
			(clearance 0)
		)
		(min_thickness 0.25)
		(keepout
			(tracks not_allowed)
			(vias allowed)
			(pads allowed)
			(copperpour not_allowed)
			(footprints allowed)
		)
		(placement
			(enabled no)
			(sheetname "")
		)
		(fill yes
			(thermal_gap 0.5)
			(thermal_bridge_width 0.5)
			(island_removal_mode 0)
		)
		(polygon
			(pts
				(arc
					(start 270.891 -98.679)
					(mid 269.113 -98.679)
					(end 270.891 -98.679)
				)
			)
		)
	)
	(zone
		(layers "In1.Cu" "In3.Cu" "In6.Cu" "In8.Cu")
		(hatch none 0.5)
		(connect_pads
			(clearance 0)
		)
		(min_thickness 0.25)
		(keepout
			(tracks not_allowed)
			(vias allowed)
			(pads allowed)
			(copperpour not_allowed)
			(footprints allowed)
		)
		(placement
			(enabled no)
			(sheetname "")
		)
		(fill yes
			(thermal_gap 0.5)
			(thermal_bridge_width 0.5)
			(island_removal_mode 0)
		)
		(polygon
			(pts
				(arc
					(start 232.480104 -129.586736)
					(mid 230.702104 -129.586736)
					(end 232.480104 -129.586736)
				)
			)
		)
	)
	(zone
		(layers "In1.Cu" "In3.Cu" "In6.Cu" "In8.Cu")
		(hatch none 0.5)
		(connect_pads
			(clearance 0)
		)
		(min_thickness 0.25)
		(keepout
			(tracks not_allowed)
			(vias allowed)
			(pads allowed)
			(copperpour not_allowed)
			(footprints allowed)
		)
		(placement
			(enabled no)
			(sheetname "")
		)
		(fill yes
			(thermal_gap 0.5)
			(thermal_bridge_width 0.5)
			(island_removal_mode 0)
		)
		(polygon
			(pts
				(arc
					(start 178.17846 -52.197)
					(mid 176.40046 -52.197)
					(end 178.17846 -52.197)
				)
			)
		)
	)
	(zone
		(layers "In1.Cu" "In3.Cu" "In6.Cu" "In8.Cu")
		(hatch none 0.5)
		(connect_pads
			(clearance 0)
		)
		(min_thickness 0.25)
		(keepout
			(tracks not_allowed)
			(vias allowed)
			(pads allowed)
			(copperpour not_allowed)
			(footprints allowed)
		)
		(placement
			(enabled no)
			(sheetname "")
		)
		(fill yes
			(thermal_gap 0.5)
			(thermal_bridge_width 0.5)
			(island_removal_mode 0)
		)
		(polygon
			(pts
				(arc
					(start 163.799774 -126.492)
					(mid 162.021774 -126.492)
					(end 163.799774 -126.492)
				)
			)
		)
	)
	(zone
		(layers "In1.Cu" "In3.Cu" "In6.Cu" "In8.Cu")
		(hatch none 0.5)
		(connect_pads
			(clearance 0)
		)
		(min_thickness 0.25)
		(keepout
			(tracks not_allowed)
			(vias allowed)
			(pads allowed)
			(copperpour not_allowed)
			(footprints allowed)
		)
		(placement
			(enabled no)
			(sheetname "")
		)
		(fill yes
			(thermal_gap 0.5)
			(thermal_bridge_width 0.5)
			(island_removal_mode 0)
		)
		(polygon
			(pts
				(arc
					(start 222.98787 -97.985834)
					(mid 221.20987 -97.985834)
					(end 222.98787 -97.985834)
				)
			)
		)
	)
	(zone
		(layers "In1.Cu" "In3.Cu" "In6.Cu" "In8.Cu")
		(hatch none 0.5)
		(connect_pads
			(clearance 0)
		)
		(min_thickness 0.25)
		(keepout
			(tracks not_allowed)
			(vias allowed)
			(pads allowed)
			(copperpour not_allowed)
			(footprints allowed)
		)
		(placement
			(enabled no)
			(sheetname "")
		)
		(fill yes
			(thermal_gap 0.5)
			(thermal_bridge_width 0.5)
			(island_removal_mode 0)
		)
		(polygon
			(pts
				(arc
					(start 72.771 -51.689)
					(mid 70.993 -51.689)
					(end 72.771 -51.689)
				)
			)
		)
	)
	(zone
		(layers "In1.Cu" "In3.Cu" "In6.Cu" "In8.Cu")
		(hatch none 0.5)
		(connect_pads
			(clearance 0)
		)
		(min_thickness 0.25)
		(keepout
			(tracks not_allowed)
			(vias allowed)
			(pads allowed)
			(copperpour not_allowed)
			(footprints allowed)
		)
		(placement
			(enabled no)
			(sheetname "")
		)
		(fill yes
			(thermal_gap 0.5)
			(thermal_bridge_width 0.5)
			(island_removal_mode 0)
		)
		(polygon
			(pts
				(arc
					(start 204.76337 -122.047762)
					(mid 202.98537 -122.047762)
					(end 204.76337 -122.047762)
				)
			)
		)
	)
	(zone
		(layers "In1.Cu" "In3.Cu" "In6.Cu" "In8.Cu")
		(hatch none 0.5)
		(connect_pads
			(clearance 0)
		)
		(min_thickness 0.25)
		(keepout
			(tracks not_allowed)
			(vias allowed)
			(pads allowed)
			(copperpour not_allowed)
			(footprints allowed)
		)
		(placement
			(enabled no)
			(sheetname "")
		)
		(fill yes
			(thermal_gap 0.5)
			(thermal_bridge_width 0.5)
			(island_removal_mode 0)
		)
		(polygon
			(pts
				(arc
					(start 272.126964 -128.937766)
					(mid 270.348964 -128.937766)
					(end 272.126964 -128.937766)
				)
			)
		)
	)
	(zone
		(layers "In1.Cu" "In3.Cu" "In6.Cu" "In8.Cu")
		(hatch none 0.5)
		(connect_pads
			(clearance 0)
		)
		(min_thickness 0.25)
		(keepout
			(tracks not_allowed)
			(vias allowed)
			(pads allowed)
			(copperpour not_allowed)
			(footprints allowed)
		)
		(placement
			(enabled no)
			(sheetname "")
		)
		(fill yes
			(thermal_gap 0.5)
			(thermal_bridge_width 0.5)
			(island_removal_mode 0)
		)
		(polygon
			(pts
				(arc
					(start 273.177 -122.809)
					(mid 271.399 -122.809)
					(end 273.177 -122.809)
				)
			)
		)
	)
	(zone
		(layers "In1.Cu" "In3.Cu" "In6.Cu" "In8.Cu")
		(hatch none 0.5)
		(connect_pads
			(clearance 0)
		)
		(min_thickness 0.25)
		(keepout
			(tracks not_allowed)
			(vias allowed)
			(pads allowed)
			(copperpour not_allowed)
			(footprints allowed)
		)
		(placement
			(enabled no)
			(sheetname "")
		)
		(fill yes
			(thermal_gap 0.5)
			(thermal_bridge_width 0.5)
			(island_removal_mode 0)
		)
		(polygon
			(pts
				(arc
					(start 272.542 -138.176)
					(mid 270.764 -138.176)
					(end 272.542 -138.176)
				)
			)
		)
	)
	(zone
		(layers "In1.Cu" "In3.Cu" "In6.Cu" "In8.Cu")
		(hatch none 0.5)
		(connect_pads
			(clearance 0)
		)
		(min_thickness 0.25)
		(keepout
			(tracks not_allowed)
			(vias allowed)
			(pads allowed)
			(copperpour not_allowed)
			(footprints allowed)
		)
		(placement
			(enabled no)
			(sheetname "")
		)
		(fill yes
			(thermal_gap 0.5)
			(thermal_bridge_width 0.5)
			(island_removal_mode 0)
		)
		(polygon
			(pts
				(arc
					(start 206.965042 -104.4321)
					(mid 205.187042 -104.4321)
					(end 206.965042 -104.4321)
				)
			)
		)
	)
	(zone
		(layers "In1.Cu" "In3.Cu" "In6.Cu" "In8.Cu")
		(hatch none 0.5)
		(connect_pads
			(clearance 0)
		)
		(min_thickness 0.25)
		(keepout
			(tracks not_allowed)
			(vias allowed)
			(pads allowed)
			(copperpour not_allowed)
			(footprints allowed)
		)
		(placement
			(enabled no)
			(sheetname "")
		)
		(fill yes
			(thermal_gap 0.5)
			(thermal_bridge_width 0.5)
			(island_removal_mode 0)
		)
		(polygon
			(pts
				(arc
					(start 220.685868 -105.134664)
					(mid 218.907868 -105.134664)
					(end 220.685868 -105.134664)
				)
			)
		)
	)
	(zone
		(layers "In1.Cu" "In3.Cu" "In6.Cu" "In8.Cu")
		(hatch none 0.5)
		(connect_pads
			(clearance 0)
		)
		(min_thickness 0.25)
		(keepout
			(tracks not_allowed)
			(vias allowed)
			(pads allowed)
			(copperpour not_allowed)
			(footprints allowed)
		)
		(placement
			(enabled no)
			(sheetname "")
		)
		(fill yes
			(thermal_gap 0.5)
			(thermal_bridge_width 0.5)
			(island_removal_mode 0)
		)
		(polygon
			(pts
				(arc
					(start 270.129 -100.203)
					(mid 268.351 -100.203)
					(end 270.129 -100.203)
				)
			)
		)
	)
	(zone
		(layers "In1.Cu" "In3.Cu" "In6.Cu" "In8.Cu")
		(hatch none 0.5)
		(connect_pads
			(clearance 0)
		)
		(min_thickness 0.25)
		(keepout
			(tracks not_allowed)
			(vias allowed)
			(pads allowed)
			(copperpour not_allowed)
			(footprints allowed)
		)
		(placement
			(enabled no)
			(sheetname "")
		)
		(fill yes
			(thermal_gap 0.5)
			(thermal_bridge_width 0.5)
			(island_removal_mode 0)
		)
		(polygon
			(pts
				(arc
					(start 273.177 -77.597)
					(mid 271.399 -77.597)
					(end 273.177 -77.597)
				)
			)
		)
	)
	(zone
		(layers "In1.Cu" "In3.Cu" "In6.Cu" "In8.Cu")
		(hatch none 0.5)
		(connect_pads
			(clearance 0)
		)
		(min_thickness 0.25)
		(keepout
			(tracks not_allowed)
			(vias allowed)
			(pads allowed)
			(copperpour not_allowed)
			(footprints allowed)
		)
		(placement
			(enabled no)
			(sheetname "")
		)
		(fill yes
			(thermal_gap 0.5)
			(thermal_bridge_width 0.5)
			(island_removal_mode 0)
		)
		(polygon
			(pts
				(arc
					(start 270.129 -113.792)
					(mid 268.351 -113.792)
					(end 270.129 -113.792)
				)
			)
		)
	)
	(zone
		(layers "In1.Cu" "In3.Cu" "In6.Cu" "In8.Cu")
		(hatch none 0.5)
		(connect_pads
			(clearance 0)
		)
		(min_thickness 0.25)
		(keepout
			(tracks not_allowed)
			(vias allowed)
			(pads allowed)
			(copperpour not_allowed)
			(footprints allowed)
		)
		(placement
			(enabled no)
			(sheetname "")
		)
		(fill yes
			(thermal_gap 0.5)
			(thermal_bridge_width 0.5)
			(island_removal_mode 0)
		)
		(polygon
			(pts
				(arc
					(start 286.131 -30.687264)
					(mid 284.353 -30.687264)
					(end 286.131 -30.687264)
				)
			)
		)
	)
	(zone
		(layers "In1.Cu" "In3.Cu" "In6.Cu" "In8.Cu")
		(hatch none 0.5)
		(connect_pads
			(clearance 0)
		)
		(min_thickness 0.25)
		(keepout
			(tracks not_allowed)
			(vias allowed)
			(pads allowed)
			(copperpour not_allowed)
			(footprints allowed)
		)
		(placement
			(enabled no)
			(sheetname "")
		)
		(fill yes
			(thermal_gap 0.5)
			(thermal_bridge_width 0.5)
			(island_removal_mode 0)
		)
		(polygon
			(pts
				(arc
					(start 31.242 -106.045)
					(mid 29.464 -106.045)
					(end 31.242 -106.045)
				)
			)
		)
	)
	(zone
		(layers "In1.Cu" "In3.Cu" "In6.Cu" "In8.Cu")
		(hatch none 0.5)
		(connect_pads
			(clearance 0)
		)
		(min_thickness 0.25)
		(keepout
			(tracks not_allowed)
			(vias allowed)
			(pads allowed)
			(copperpour not_allowed)
			(footprints allowed)
		)
		(placement
			(enabled no)
			(sheetname "")
		)
		(fill yes
			(thermal_gap 0.5)
			(thermal_bridge_width 0.5)
			(island_removal_mode 0)
		)
		(polygon
			(pts
				(arc
					(start 270.129 -125.857)
					(mid 268.351 -125.857)
					(end 270.129 -125.857)
				)
			)
		)
	)
	(zone
		(layers "In1.Cu" "In3.Cu" "In6.Cu" "In8.Cu")
		(hatch none 0.5)
		(connect_pads
			(clearance 0)
		)
		(min_thickness 0.25)
		(keepout
			(tracks not_allowed)
			(vias allowed)
			(pads allowed)
			(copperpour not_allowed)
			(footprints allowed)
		)
		(placement
			(enabled no)
			(sheetname "")
		)
		(fill yes
			(thermal_gap 0.5)
			(thermal_bridge_width 0.5)
			(island_removal_mode 0)
		)
		(polygon
			(pts
				(arc
					(start 272.415 -101.727)
					(mid 270.637 -101.727)
					(end 272.415 -101.727)
				)
			)
		)
	)
	(zone
		(layers "In1.Cu" "In3.Cu" "In6.Cu" "In8.Cu")
		(hatch none 0.5)
		(connect_pads
			(clearance 0)
		)
		(min_thickness 0.25)
		(keepout
			(tracks not_allowed)
			(vias allowed)
			(pads allowed)
			(copperpour not_allowed)
			(footprints allowed)
		)
		(placement
			(enabled no)
			(sheetname "")
		)
		(fill yes
			(thermal_gap 0.5)
			(thermal_bridge_width 0.5)
			(island_removal_mode 0)
		)
		(polygon
			(pts
				(arc
					(start 178.17846 -49.657)
					(mid 176.40046 -49.657)
					(end 178.17846 -49.657)
				)
			)
		)
	)
	(zone
		(layers "In1.Cu" "In3.Cu" "In6.Cu" "In8.Cu")
		(hatch none 0.5)
		(connect_pads
			(clearance 0)
		)
		(min_thickness 0.25)
		(keepout
			(tracks not_allowed)
			(vias allowed)
			(pads allowed)
			(copperpour not_allowed)
			(footprints allowed)
		)
		(placement
			(enabled no)
			(sheetname "")
		)
		(fill yes
			(thermal_gap 0.5)
			(thermal_bridge_width 0.5)
			(island_removal_mode 0)
		)
		(polygon
			(pts
				(arc
					(start 204.00137 -122.809762)
					(mid 202.22337 -122.809762)
					(end 204.00137 -122.809762)
				)
			)
		)
	)
	(zone
		(layers "In1.Cu" "In3.Cu" "In6.Cu" "In8.Cu")
		(hatch none 0.5)
		(connect_pads
			(clearance 0)
		)
		(min_thickness 0.25)
		(keepout
			(tracks not_allowed)
			(vias allowed)
			(pads allowed)
			(copperpour not_allowed)
			(footprints allowed)
		)
		(placement
			(enabled no)
			(sheetname "")
		)
		(fill yes
			(thermal_gap 0.5)
			(thermal_bridge_width 0.5)
			(island_removal_mode 0)
		)
		(polygon
			(pts
				(arc
					(start 72.318626 -70.885812)
					(mid 70.540626 -70.885812)
					(end 72.318626 -70.885812)
				)
			)
		)
	)
	(zone
		(layers "In1.Cu" "In3.Cu" "In6.Cu" "In8.Cu")
		(hatch none 0.5)
		(connect_pads
			(clearance 0)
		)
		(min_thickness 0.25)
		(keepout
			(tracks not_allowed)
			(vias allowed)
			(pads allowed)
			(copperpour not_allowed)
			(footprints allowed)
		)
		(placement
			(enabled no)
			(sheetname "")
		)
		(fill yes
			(thermal_gap 0.5)
			(thermal_bridge_width 0.5)
			(island_removal_mode 0)
		)
		(polygon
			(pts
				(arc
					(start 296.2148 -44.693586)
					(mid 294.4368 -44.693586)
					(end 296.2148 -44.693586)
				)
			)
		)
	)
	(zone
		(layers "In1.Cu" "In3.Cu" "In6.Cu" "In8.Cu")
		(hatch none 0.5)
		(connect_pads
			(clearance 0)
		)
		(min_thickness 0.25)
		(keepout
			(tracks not_allowed)
			(vias allowed)
			(pads allowed)
			(copperpour not_allowed)
			(footprints allowed)
		)
		(placement
			(enabled no)
			(sheetname "")
		)
		(fill yes
			(thermal_gap 0.5)
			(thermal_bridge_width 0.5)
			(island_removal_mode 0)
		)
		(polygon
			(pts
				(arc
					(start 199.512174 -60.96)
					(mid 196.718174 -60.96)
					(end 199.512174 -60.96)
				)
			)
		)
	)
	(zone
		(layers "In1.Cu" "In3.Cu" "In6.Cu" "In8.Cu")
		(hatch none 0.5)
		(connect_pads
			(clearance 0)
		)
		(min_thickness 0.25)
		(keepout
			(tracks not_allowed)
			(vias allowed)
			(pads allowed)
			(copperpour not_allowed)
			(footprints allowed)
		)
		(placement
			(enabled no)
			(sheetname "")
		)
		(fill yes
			(thermal_gap 0.5)
			(thermal_bridge_width 0.5)
			(island_removal_mode 0)
		)
		(polygon
			(pts
				(arc
					(start 83.799426 -126.492)
					(mid 82.021426 -126.492)
					(end 83.799426 -126.492)
				)
			)
		)
	)
	(zone
		(layers "In1.Cu" "In3.Cu" "In6.Cu" "In8.Cu")
		(hatch none 0.5)
		(connect_pads
			(clearance 0)
		)
		(min_thickness 0.25)
		(keepout
			(tracks not_allowed)
			(vias allowed)
			(pads allowed)
			(copperpour not_allowed)
			(footprints allowed)
		)
		(placement
			(enabled no)
			(sheetname "")
		)
		(fill yes
			(thermal_gap 0.5)
			(thermal_bridge_width 0.5)
			(island_removal_mode 0)
		)
		(polygon
			(pts
				(arc
					(start 217.825828 -129.89814)
					(mid 216.047828 -129.89814)
					(end 217.825828 -129.89814)
				)
			)
		)
	)
	(zone
		(layers "In1.Cu" "In3.Cu" "In6.Cu" "In8.Cu")
		(hatch none 0.5)
		(connect_pads
			(clearance 0)
		)
		(min_thickness 0.25)
		(keepout
			(tracks not_allowed)
			(vias allowed)
			(pads allowed)
			(copperpour not_allowed)
			(footprints allowed)
		)
		(placement
			(enabled no)
			(sheetname "")
		)
		(fill yes
			(thermal_gap 0.5)
			(thermal_bridge_width 0.5)
			(island_removal_mode 0)
		)
		(polygon
			(pts
				(arc
					(start 42.2529 -57.70499)
					(mid 40.4749 -57.70499)
					(end 42.2529 -57.70499)
				)
			)
		)
	)
	(zone
		(layers "In1.Cu" "In3.Cu" "In6.Cu" "In8.Cu")
		(hatch none 0.5)
		(connect_pads
			(clearance 0)
		)
		(min_thickness 0.25)
		(keepout
			(tracks not_allowed)
			(vias allowed)
			(pads allowed)
			(copperpour not_allowed)
			(footprints allowed)
		)
		(placement
			(enabled no)
			(sheetname "")
		)
		(fill yes
			(thermal_gap 0.5)
			(thermal_bridge_width 0.5)
			(island_removal_mode 0)
		)
		(polygon
			(pts
				(arc
					(start 46.47184 -50.0507)
					(mid 44.69384 -50.0507)
					(end 46.47184 -50.0507)
				)
			)
		)
	)
	(zone
		(layers "In1.Cu" "In3.Cu" "In6.Cu" "In8.Cu")
		(hatch none 0.5)
		(connect_pads
			(clearance 0)
		)
		(min_thickness 0.25)
		(keepout
			(tracks not_allowed)
			(vias allowed)
			(pads allowed)
			(copperpour not_allowed)
			(footprints allowed)
		)
		(placement
			(enabled no)
			(sheetname "")
		)
		(fill yes
			(thermal_gap 0.5)
			(thermal_bridge_width 0.5)
			(island_removal_mode 0)
		)
		(polygon
			(pts
				(arc
					(start 271.653 -101.727)
					(mid 269.875 -101.727)
					(end 271.653 -101.727)
				)
			)
		)
	)
	(zone
		(layers "In1.Cu" "In3.Cu" "In6.Cu" "In8.Cu")
		(hatch none 0.5)
		(connect_pads
			(clearance 0)
		)
		(min_thickness 0.25)
		(keepout
			(tracks not_allowed)
			(vias allowed)
			(pads allowed)
			(copperpour not_allowed)
			(footprints allowed)
		)
		(placement
			(enabled no)
			(sheetname "")
		)
		(fill yes
			(thermal_gap 0.5)
			(thermal_bridge_width 0.5)
			(island_removal_mode 0)
		)
		(polygon
			(pts
				(arc
					(start 214.867236 -127.625856)
					(mid 213.089236 -127.625856)
					(end 214.867236 -127.625856)
				)
			)
		)
	)
	(zone
		(layers "In1.Cu" "In3.Cu" "In6.Cu" "In8.Cu")
		(hatch none 0.5)
		(connect_pads
			(clearance 0)
		)
		(min_thickness 0.25)
		(keepout
			(tracks not_allowed)
			(vias allowed)
			(pads allowed)
			(copperpour not_allowed)
			(footprints allowed)
		)
		(placement
			(enabled no)
			(sheetname "")
		)
		(fill yes
			(thermal_gap 0.5)
			(thermal_bridge_width 0.5)
			(island_removal_mode 0)
		)
		(polygon
			(pts
				(arc
					(start 175.991774 -126.492)
					(mid 174.213774 -126.492)
					(end 175.991774 -126.492)
				)
			)
		)
	)
	(zone
		(layers "In1.Cu" "In3.Cu" "In6.Cu" "In8.Cu")
		(hatch none 0.5)
		(connect_pads
			(clearance 0)
		)
		(min_thickness 0.25)
		(keepout
			(tracks not_allowed)
			(vias allowed)
			(pads allowed)
			(copperpour not_allowed)
			(footprints allowed)
		)
		(placement
			(enabled no)
			(sheetname "")
		)
		(fill yes
			(thermal_gap 0.5)
			(thermal_bridge_width 0.5)
			(island_removal_mode 0)
		)
		(polygon
			(pts
				(arc
					(start 273.177 -86.614)
					(mid 271.399 -86.614)
					(end 273.177 -86.614)
				)
			)
		)
	)
	(zone
		(layers "In1.Cu" "In3.Cu" "In6.Cu" "In8.Cu")
		(hatch none 0.5)
		(connect_pads
			(clearance 0)
		)
		(min_thickness 0.25)
		(keepout
			(tracks not_allowed)
			(vias allowed)
			(pads allowed)
			(copperpour not_allowed)
			(footprints allowed)
		)
		(placement
			(enabled no)
			(sheetname "")
		)
		(fill yes
			(thermal_gap 0.5)
			(thermal_bridge_width 0.5)
			(island_removal_mode 0)
		)
		(polygon
			(pts
				(arc
					(start 228.496114 -97.985834)
					(mid 226.718114 -97.985834)
					(end 228.496114 -97.985834)
				)
			)
		)
	)
	(zone
		(layers "In1.Cu" "In3.Cu" "In6.Cu" "In8.Cu")
		(hatch none 0.5)
		(connect_pads
			(clearance 0)
		)
		(min_thickness 0.25)
		(keepout
			(tracks not_allowed)
			(vias allowed)
			(pads allowed)
			(copperpour not_allowed)
			(footprints allowed)
		)
		(placement
			(enabled no)
			(sheetname "")
		)
		(fill yes
			(thermal_gap 0.5)
			(thermal_bridge_width 0.5)
			(island_removal_mode 0)
		)
		(polygon
			(pts
				(arc
					(start 159.512 -60.96)
					(mid 156.718 -60.96)
					(end 159.512 -60.96)
				)
			)
		)
	)
	(zone
		(layers "In1.Cu" "In3.Cu" "In6.Cu" "In8.Cu")
		(hatch none 0.5)
		(connect_pads
			(clearance 0)
		)
		(min_thickness 0.25)
		(keepout
			(tracks not_allowed)
			(vias allowed)
			(pads allowed)
			(copperpour not_allowed)
			(footprints allowed)
		)
		(placement
			(enabled no)
			(sheetname "")
		)
		(fill yes
			(thermal_gap 0.5)
			(thermal_bridge_width 0.5)
			(island_removal_mode 0)
		)
		(polygon
			(pts
				(arc
					(start 217.063828 -129.89814)
					(mid 215.285828 -129.89814)
					(end 217.063828 -129.89814)
				)
			)
		)
	)
	(zone
		(layers "In1.Cu" "In3.Cu" "In6.Cu" "In8.Cu")
		(hatch none 0.5)
		(connect_pads
			(clearance 0)
		)
		(min_thickness 0.25)
		(keepout
			(tracks not_allowed)
			(vias allowed)
			(pads allowed)
			(copperpour not_allowed)
			(footprints allowed)
		)
		(placement
			(enabled no)
			(sheetname "")
		)
		(fill yes
			(thermal_gap 0.5)
			(thermal_bridge_width 0.5)
			(island_removal_mode 0)
		)
		(polygon
			(pts
				(arc
					(start 235.468668 -128.824736)
					(mid 233.690668 -128.824736)
					(end 235.468668 -128.824736)
				)
			)
		)
	)
	(zone
		(layers "In1.Cu" "In3.Cu" "In6.Cu" "In8.Cu")
		(hatch none 0.5)
		(connect_pads
			(clearance 0)
		)
		(min_thickness 0.25)
		(keepout
			(tracks not_allowed)
			(vias allowed)
			(pads allowed)
			(copperpour not_allowed)
			(footprints allowed)
		)
		(placement
			(enabled no)
			(sheetname "")
		)
		(fill yes
			(thermal_gap 0.5)
			(thermal_bridge_width 0.5)
			(island_removal_mode 0)
		)
		(polygon
			(pts
				(arc
					(start 272.415 -97.917)
					(mid 270.637 -97.917)
					(end 272.415 -97.917)
				)
			)
		)
	)
	(zone
		(layers "In1.Cu" "In3.Cu" "In6.Cu" "In8.Cu")
		(hatch none 0.5)
		(connect_pads
			(clearance 0)
		)
		(min_thickness 0.25)
		(keepout
			(tracks not_allowed)
			(vias allowed)
			(pads allowed)
			(copperpour not_allowed)
			(footprints allowed)
		)
		(placement
			(enabled no)
			(sheetname "")
		)
		(fill yes
			(thermal_gap 0.5)
			(thermal_bridge_width 0.5)
			(island_removal_mode 0)
		)
		(polygon
			(pts
				(arc
					(start 222.928688 -104.418384)
					(mid 221.150688 -104.418384)
					(end 222.928688 -104.418384)
				)
			)
		)
	)
	(zone
		(layers "In1.Cu" "In3.Cu" "In6.Cu" "In8.Cu")
		(hatch none 0.5)
		(connect_pads
			(clearance 0)
		)
		(min_thickness 0.25)
		(keepout
			(tracks not_allowed)
			(vias allowed)
			(pads allowed)
			(copperpour not_allowed)
			(footprints allowed)
		)
		(placement
			(enabled no)
			(sheetname "")
		)
		(fill yes
			(thermal_gap 0.5)
			(thermal_bridge_width 0.5)
			(island_removal_mode 0)
		)
		(polygon
			(pts
				(arc
					(start 206.28737 -122.047762)
					(mid 204.50937 -122.047762)
					(end 206.28737 -122.047762)
				)
			)
		)
	)
	(zone
		(layers "In1.Cu" "In3.Cu" "In6.Cu" "In8.Cu")
		(hatch none 0.5)
		(connect_pads
			(clearance 0)
		)
		(min_thickness 0.25)
		(keepout
			(tracks not_allowed)
			(vias allowed)
			(pads allowed)
			(copperpour not_allowed)
			(footprints allowed)
		)
		(placement
			(enabled no)
			(sheetname "")
		)
		(fill yes
			(thermal_gap 0.5)
			(thermal_bridge_width 0.5)
			(island_removal_mode 0)
		)
		(polygon
			(pts
				(arc
					(start 270.129 -76.073)
					(mid 268.351 -76.073)
					(end 270.129 -76.073)
				)
			)
		)
	)
	(zone
		(layers "In1.Cu" "In3.Cu" "In6.Cu" "In8.Cu")
		(hatch none 0.5)
		(connect_pads
			(clearance 0)
		)
		(min_thickness 0.25)
		(keepout
			(tracks not_allowed)
			(vias allowed)
			(pads allowed)
			(copperpour not_allowed)
			(footprints allowed)
		)
		(placement
			(enabled no)
			(sheetname "")
		)
		(fill yes
			(thermal_gap 0.5)
			(thermal_bridge_width 0.5)
			(island_removal_mode 0)
		)
		(polygon
			(pts
				(arc
					(start 271.653 -110.744)
					(mid 269.875 -110.744)
					(end 271.653 -110.744)
				)
			)
		)
	)
	(zone
		(layers "In1.Cu" "In3.Cu" "In6.Cu" "In8.Cu")
		(hatch none 0.5)
		(connect_pads
			(clearance 0)
		)
		(min_thickness 0.25)
		(keepout
			(tracks not_allowed)
			(vias allowed)
			(pads allowed)
			(copperpour not_allowed)
			(footprints allowed)
		)
		(placement
			(enabled no)
			(sheetname "")
		)
		(fill yes
			(thermal_gap 0.5)
			(thermal_bridge_width 0.5)
			(island_removal_mode 0)
		)
		(polygon
			(pts
				(arc
					(start 100.076 -51.689)
					(mid 98.298 -51.689)
					(end 100.076 -51.689)
				)
			)
		)
	)
	(zone
		(layers "In1.Cu" "In3.Cu" "In6.Cu" "In8.Cu")
		(hatch none 0.5)
		(connect_pads
			(clearance 0)
		)
		(min_thickness 0.25)
		(keepout
			(tracks not_allowed)
			(vias allowed)
			(pads allowed)
			(copperpour not_allowed)
			(footprints allowed)
		)
		(placement
			(enabled no)
			(sheetname "")
		)
		(fill yes
			(thermal_gap 0.5)
			(thermal_bridge_width 0.5)
			(island_removal_mode 0)
		)
		(polygon
			(pts
				(arc
					(start 232.480104 -131.110736)
					(mid 230.702104 -131.110736)
					(end 232.480104 -131.110736)
				)
			)
		)
	)
	(zone
		(layers "In1.Cu" "In3.Cu" "In6.Cu" "In8.Cu")
		(hatch none 0.5)
		(connect_pads
			(clearance 0)
		)
		(min_thickness 0.25)
		(keepout
			(tracks not_allowed)
			(vias allowed)
			(pads allowed)
			(copperpour not_allowed)
			(footprints allowed)
		)
		(placement
			(enabled no)
			(sheetname "")
		)
		(fill yes
			(thermal_gap 0.5)
			(thermal_bridge_width 0.5)
			(island_removal_mode 0)
		)
		(polygon
			(pts
				(arc
					(start 272.415 -89.662)
					(mid 270.637 -89.662)
					(end 272.415 -89.662)
				)
			)
		)
	)
	(zone
		(layers "In1.Cu" "In3.Cu" "In6.Cu" "In8.Cu")
		(hatch none 0.5)
		(connect_pads
			(clearance 0)
		)
		(min_thickness 0.25)
		(keepout
			(tracks not_allowed)
			(vias allowed)
			(pads allowed)
			(copperpour not_allowed)
			(footprints allowed)
		)
		(placement
			(enabled no)
			(sheetname "")
		)
		(fill yes
			(thermal_gap 0.5)
			(thermal_bridge_width 0.5)
			(island_removal_mode 0)
		)
		(polygon
			(pts
				(arc
					(start 150.876 -52.197)
					(mid 149.098 -52.197)
					(end 150.876 -52.197)
				)
			)
		)
	)
	(zone
		(layers "In1.Cu" "In3.Cu" "In6.Cu" "In8.Cu")
		(hatch none 0.5)
		(connect_pads
			(clearance 0)
		)
		(min_thickness 0.25)
		(keepout
			(tracks not_allowed)
			(vias allowed)
			(pads allowed)
			(copperpour not_allowed)
			(footprints allowed)
		)
		(placement
			(enabled no)
			(sheetname "")
		)
		(fill yes
			(thermal_gap 0.5)
			(thermal_bridge_width 0.5)
			(island_removal_mode 0)
		)
		(polygon
			(pts
				(arc
					(start 214.867236 -129.911856)
					(mid 213.089236 -129.911856)
					(end 214.867236 -129.911856)
				)
			)
		)
	)
	(zone
		(layers "In1.Cu" "In3.Cu" "In6.Cu" "In8.Cu")
		(hatch none 0.5)
		(connect_pads
			(clearance 0)
		)
		(min_thickness 0.25)
		(keepout
			(tracks not_allowed)
			(vias allowed)
			(pads allowed)
			(copperpour not_allowed)
			(footprints allowed)
		)
		(placement
			(enabled no)
			(sheetname "")
		)
		(fill yes
			(thermal_gap 0.5)
			(thermal_bridge_width 0.5)
			(island_removal_mode 0)
		)
		(polygon
			(pts
				(arc
					(start 43.799506 -126.492)
					(mid 42.021506 -126.492)
					(end 43.799506 -126.492)
				)
			)
		)
	)
	(zone
		(layers "In1.Cu" "In3.Cu" "In6.Cu" "In8.Cu")
		(hatch none 0.5)
		(connect_pads
			(clearance 0)
		)
		(min_thickness 0.25)
		(keepout
			(tracks not_allowed)
			(vias allowed)
			(pads allowed)
			(copperpour not_allowed)
			(footprints allowed)
		)
		(placement
			(enabled no)
			(sheetname "")
		)
		(fill yes
			(thermal_gap 0.5)
			(thermal_bridge_width 0.5)
			(island_removal_mode 0)
		)
		(polygon
			(pts
				(arc
					(start 242.21694 -98.012758)
					(mid 240.43894 -98.012758)
					(end 242.21694 -98.012758)
				)
			)
		)
	)
	(zone
		(layers "In1.Cu" "In3.Cu" "In6.Cu" "In8.Cu")
		(hatch none 0.5)
		(connect_pads
			(clearance 0)
		)
		(min_thickness 0.25)
		(keepout
			(tracks not_allowed)
			(vias allowed)
			(pads allowed)
			(copperpour not_allowed)
			(footprints allowed)
		)
		(placement
			(enabled no)
			(sheetname "")
		)
		(fill yes
			(thermal_gap 0.5)
			(thermal_bridge_width 0.5)
			(island_removal_mode 0)
		)
		(polygon
			(pts
				(arc
					(start 219.161868 -105.134664)
					(mid 217.383868 -105.134664)
					(end 219.161868 -105.134664)
				)
			)
		)
	)
	(zone
		(layers "In1.Cu" "In3.Cu" "In6.Cu" "In8.Cu")
		(hatch none 0.5)
		(connect_pads
			(clearance 0)
		)
		(min_thickness 0.25)
		(keepout
			(tracks not_allowed)
			(vias allowed)
			(pads allowed)
			(copperpour not_allowed)
			(footprints allowed)
		)
		(placement
			(enabled no)
			(sheetname "")
		)
		(fill yes
			(thermal_gap 0.5)
			(thermal_bridge_width 0.5)
			(island_removal_mode 0)
		)
		(polygon
			(pts
				(arc
					(start 136.7536 -131.572)
					(mid 134.9756 -131.572)
					(end 136.7536 -131.572)
				)
			)
		)
	)
	(zone
		(layers "In1.Cu" "In3.Cu" "In6.Cu" "In8.Cu")
		(hatch none 0.5)
		(connect_pads
			(clearance 0)
		)
		(min_thickness 0.25)
		(keepout
			(tracks not_allowed)
			(vias allowed)
			(pads allowed)
			(copperpour not_allowed)
			(footprints allowed)
		)
		(placement
			(enabled no)
			(sheetname "")
		)
		(fill yes
			(thermal_gap 0.5)
			(thermal_bridge_width 0.5)
			(island_removal_mode 0)
		)
		(polygon
			(pts
				(arc
					(start 72.771 -52.324)
					(mid 70.993 -52.324)
					(end 72.771 -52.324)
				)
			)
		)
	)
	(zone
		(layers "In1.Cu" "In3.Cu" "In6.Cu" "In8.Cu")
		(hatch none 0.5)
		(connect_pads
			(clearance 0)
		)
		(min_thickness 0.25)
		(keepout
			(tracks not_allowed)
			(vias allowed)
			(pads allowed)
			(copperpour not_allowed)
			(footprints allowed)
		)
		(placement
			(enabled no)
			(sheetname "")
		)
		(fill yes
			(thermal_gap 0.5)
			(thermal_bridge_width 0.5)
			(island_removal_mode 0)
		)
		(polygon
			(pts
				(arc
					(start 219.923868 -104.4321)
					(mid 218.145868 -104.4321)
					(end 219.923868 -104.4321)
				)
			)
		)
	)
	(zone
		(layers "In1.Cu" "In3.Cu" "In6.Cu" "In8.Cu")
		(hatch none 0.5)
		(connect_pads
			(clearance 0)
		)
		(min_thickness 0.25)
		(keepout
			(tracks not_allowed)
			(vias allowed)
			(pads allowed)
			(copperpour not_allowed)
			(footprints allowed)
		)
		(placement
			(enabled no)
			(sheetname "")
		)
		(fill yes
			(thermal_gap 0.5)
			(thermal_bridge_width 0.5)
			(island_removal_mode 0)
		)
		(polygon
			(pts
				(arc
					(start 271.653 -75.311)
					(mid 269.875 -75.311)
					(end 271.653 -75.311)
				)
			)
		)
	)
	(zone
		(layers "In1.Cu" "In3.Cu" "In6.Cu" "In8.Cu")
		(hatch none 0.5)
		(connect_pads
			(clearance 0)
		)
		(min_thickness 0.25)
		(keepout
			(tracks not_allowed)
			(vias allowed)
			(pads allowed)
			(copperpour not_allowed)
			(footprints allowed)
		)
		(placement
			(enabled no)
			(sheetname "")
		)
		(fill yes
			(thermal_gap 0.5)
			(thermal_bridge_width 0.5)
			(island_removal_mode 0)
		)
		(polygon
			(pts
				(arc
					(start 233.242104 -130.348736)
					(mid 231.464104 -130.348736)
					(end 233.242104 -130.348736)
				)
			)
		)
	)
	(zone
		(layers "In1.Cu" "In3.Cu" "In6.Cu" "In8.Cu")
		(hatch none 0.5)
		(connect_pads
			(clearance 0)
		)
		(min_thickness 0.25)
		(keepout
			(tracks not_allowed)
			(vias allowed)
			(pads allowed)
			(copperpour not_allowed)
			(footprints allowed)
		)
		(placement
			(enabled no)
			(sheetname "")
		)
		(fill yes
			(thermal_gap 0.5)
			(thermal_bridge_width 0.5)
			(island_removal_mode 0)
		)
		(polygon
			(pts
				(arc
					(start 208.445862 -103.656384)
					(mid 206.667862 -103.656384)
					(end 208.445862 -103.656384)
				)
			)
		)
	)
	(zone
		(layers "In1.Cu" "In3.Cu" "In6.Cu" "In8.Cu")
		(hatch none 0.5)
		(connect_pads
			(clearance 0)
		)
		(min_thickness 0.25)
		(keepout
			(tracks not_allowed)
			(vias allowed)
			(pads allowed)
			(copperpour not_allowed)
			(footprints allowed)
		)
		(placement
			(enabled no)
			(sheetname "")
		)
		(fill yes
			(thermal_gap 0.5)
			(thermal_bridge_width 0.5)
			(island_removal_mode 0)
		)
		(polygon
			(pts
				(arc
					(start 100.076 -49.784)
					(mid 98.298 -49.784)
					(end 100.076 -49.784)
				)
			)
		)
	)
	(zone
		(layers "In1.Cu" "In3.Cu" "In6.Cu" "In8.Cu")
		(hatch none 0.5)
		(connect_pads
			(clearance 0)
		)
		(min_thickness 0.25)
		(keepout
			(tracks not_allowed)
			(vias allowed)
			(pads allowed)
			(copperpour not_allowed)
			(footprints allowed)
		)
		(placement
			(enabled no)
			(sheetname "")
		)
		(fill yes
			(thermal_gap 0.5)
			(thermal_bridge_width 0.5)
			(island_removal_mode 0)
		)
		(polygon
			(pts
				(arc
					(start 270.5354 -118.425468)
					(mid 268.7574 -118.425468)
					(end 270.5354 -118.425468)
				)
			)
		)
	)
	(zone
		(layers "In1.Cu" "In3.Cu" "In6.Cu" "In8.Cu")
		(hatch none 0.5)
		(connect_pads
			(clearance 0)
		)
		(min_thickness 0.25)
		(keepout
			(tracks not_allowed)
			(vias allowed)
			(pads allowed)
			(copperpour not_allowed)
			(footprints allowed)
		)
		(placement
			(enabled no)
			(sheetname "")
		)
		(fill yes
			(thermal_gap 0.5)
			(thermal_bridge_width 0.5)
			(island_removal_mode 0)
		)
		(polygon
			(pts
				(arc
					(start 234.706668 -128.824736)
					(mid 232.928668 -128.824736)
					(end 234.706668 -128.824736)
				)
			)
		)
	)
	(zone
		(layers "In1.Cu" "In3.Cu" "In6.Cu" "In8.Cu")
		(hatch none 0.5)
		(connect_pads
			(clearance 0)
		)
		(min_thickness 0.25)
		(keepout
			(tracks not_allowed)
			(vias allowed)
			(pads allowed)
			(copperpour not_allowed)
			(footprints allowed)
		)
		(placement
			(enabled no)
			(sheetname "")
		)
		(fill yes
			(thermal_gap 0.5)
			(thermal_bridge_width 0.5)
			(island_removal_mode 0)
		)
		(polygon
			(pts
				(arc
					(start 234.706668 -130.348736)
					(mid 232.928668 -130.348736)
					(end 234.706668 -130.348736)
				)
			)
		)
	)
	(zone
		(layers "In1.Cu" "In3.Cu" "In6.Cu" "In8.Cu")
		(hatch none 0.5)
		(connect_pads
			(clearance 0)
		)
		(min_thickness 0.25)
		(keepout
			(tracks not_allowed)
			(vias allowed)
			(pads allowed)
			(copperpour not_allowed)
			(footprints allowed)
		)
		(placement
			(enabled no)
			(sheetname "")
		)
		(fill yes
			(thermal_gap 0.5)
			(thermal_bridge_width 0.5)
			(island_removal_mode 0)
		)
		(polygon
			(pts
				(arc
					(start 206.203042 -103.6701)
					(mid 204.425042 -103.6701)
					(end 206.203042 -103.6701)
				)
			)
		)
	)
	(zone
		(layers "In1.Cu" "In3.Cu" "In6.Cu" "In8.Cu")
		(hatch none 0.5)
		(connect_pads
			(clearance 0)
		)
		(min_thickness 0.25)
		(keepout
			(tracks not_allowed)
			(vias allowed)
			(pads allowed)
			(copperpour not_allowed)
			(footprints allowed)
		)
		(placement
			(enabled no)
			(sheetname "")
		)
		(fill yes
			(thermal_gap 0.5)
			(thermal_bridge_width 0.5)
			(island_removal_mode 0)
		)
		(polygon
			(pts
				(arc
					(start 94.615 -51.689)
					(mid 92.837 -51.689)
					(end 94.615 -51.689)
				)
			)
		)
	)
	(zone
		(layers "In1.Cu" "In3.Cu" "In6.Cu" "In8.Cu")
		(hatch none 0.5)
		(connect_pads
			(clearance 0)
		)
		(min_thickness 0.25)
		(keepout
			(tracks not_allowed)
			(vias allowed)
			(pads allowed)
			(copperpour not_allowed)
			(footprints allowed)
		)
		(placement
			(enabled no)
			(sheetname "")
		)
		(fill yes
			(thermal_gap 0.5)
			(thermal_bridge_width 0.5)
			(island_removal_mode 0)
		)
		(polygon
			(pts
				(arc
					(start 233.25582 -131.829556)
					(mid 231.47782 -131.829556)
					(end 233.25582 -131.829556)
				)
			)
		)
	)
	(zone
		(layers "In1.Cu" "In3.Cu" "In6.Cu" "In8.Cu")
		(hatch none 0.5)
		(connect_pads
			(clearance 0)
		)
		(min_thickness 0.25)
		(keepout
			(tracks not_allowed)
			(vias allowed)
			(pads allowed)
			(copperpour not_allowed)
			(footprints allowed)
		)
		(placement
			(enabled no)
			(sheetname "")
		)
		(fill yes
			(thermal_gap 0.5)
			(thermal_bridge_width 0.5)
			(island_removal_mode 0)
		)
		(polygon
			(pts
				(arc
					(start 105.537 -49.784)
					(mid 103.759 -49.784)
					(end 105.537 -49.784)
				)
			)
		)
	)
	(zone
		(layers "In1.Cu" "In3.Cu" "In6.Cu" "In8.Cu")
		(hatch none 0.5)
		(connect_pads
			(clearance 0)
		)
		(min_thickness 0.25)
		(keepout
			(tracks not_allowed)
			(vias allowed)
			(pads allowed)
			(copperpour not_allowed)
			(footprints allowed)
		)
		(placement
			(enabled no)
			(sheetname "")
		)
		(fill yes
			(thermal_gap 0.5)
			(thermal_bridge_width 0.5)
			(island_removal_mode 0)
		)
		(polygon
			(pts
				(arc
					(start 215.585802 -129.89814)
					(mid 213.807802 -129.89814)
					(end 215.585802 -129.89814)
				)
			)
		)
	)
	(zone
		(layers "In1.Cu" "In3.Cu" "In6.Cu" "In8.Cu")
		(hatch none 0.5)
		(connect_pads
			(clearance 0)
		)
		(min_thickness 0.25)
		(keepout
			(tracks not_allowed)
			(vias allowed)
			(pads allowed)
			(copperpour not_allowed)
			(footprints allowed)
		)
		(placement
			(enabled no)
			(sheetname "")
		)
		(fill yes
			(thermal_gap 0.5)
			(thermal_bridge_width 0.5)
			(island_removal_mode 0)
		)
		(polygon
			(pts
				(arc
					(start 83.693 -51.689)
					(mid 81.915 -51.689)
					(end 83.693 -51.689)
				)
			)
		)
	)
	(zone
		(layers "In1.Cu" "In3.Cu" "In6.Cu" "In8.Cu")
		(hatch none 0.5)
		(connect_pads
			(clearance 0)
		)
		(min_thickness 0.25)
		(keepout
			(tracks not_allowed)
			(vias allowed)
			(pads allowed)
			(copperpour not_allowed)
			(footprints allowed)
		)
		(placement
			(enabled no)
			(sheetname "")
		)
		(fill yes
			(thermal_gap 0.5)
			(thermal_bridge_width 0.5)
			(island_removal_mode 0)
		)
		(polygon
			(pts
				(arc
					(start 220.685868 -105.896664)
					(mid 218.907868 -105.896664)
					(end 220.685868 -105.896664)
				)
			)
		)
	)
	(zone
		(layers "In1.Cu" "In3.Cu" "In6.Cu" "In8.Cu")
		(hatch none 0.5)
		(connect_pads
			(clearance 0)
		)
		(min_thickness 0.25)
		(keepout
			(tracks not_allowed)
			(vias allowed)
			(pads allowed)
			(copperpour not_allowed)
			(footprints allowed)
		)
		(placement
			(enabled no)
			(sheetname "")
		)
		(fill yes
			(thermal_gap 0.5)
			(thermal_bridge_width 0.5)
			(island_removal_mode 0)
		)
		(polygon
			(pts
				(arc
					(start 206.203042 -102.9081)
					(mid 204.425042 -102.9081)
					(end 206.203042 -102.9081)
				)
			)
		)
	)
	(zone
		(layers "In1.Cu" "In3.Cu" "In6.Cu" "In8.Cu")
		(hatch none 0.5)
		(connect_pads
			(clearance 0)
		)
		(min_thickness 0.25)
		(keepout
			(tracks not_allowed)
			(vias allowed)
			(pads allowed)
			(copperpour not_allowed)
			(footprints allowed)
		)
		(placement
			(enabled no)
			(sheetname "")
		)
		(fill yes
			(thermal_gap 0.5)
			(thermal_bridge_width 0.5)
			(island_removal_mode 0)
		)
		(polygon
			(pts
				(arc
					(start 272.415 -113.03)
					(mid 270.637 -113.03)
					(end 272.415 -113.03)
				)
			)
		)
	)
	(zone
		(layers "In1.Cu" "In3.Cu" "In6.Cu" "In8.Cu")
		(hatch none 0.5)
		(connect_pads
			(clearance 0)
		)
		(min_thickness 0.25)
		(keepout
			(tracks not_allowed)
			(vias allowed)
			(pads allowed)
			(copperpour not_allowed)
			(footprints allowed)
		)
		(placement
			(enabled no)
			(sheetname "")
		)
		(fill yes
			(thermal_gap 0.5)
			(thermal_bridge_width 0.5)
			(island_removal_mode 0)
		)
		(polygon
			(pts
				(arc
					(start 208.57337 -120.569736)
					(mid 206.79537 -120.569736)
					(end 208.57337 -120.569736)
				)
			)
		)
	)
	(zone
		(layers "In1.Cu" "In3.Cu" "In6.Cu" "In8.Cu")
		(hatch none 0.5)
		(connect_pads
			(clearance 0)
		)
		(min_thickness 0.25)
		(keepout
			(tracks not_allowed)
			(vias allowed)
			(pads allowed)
			(copperpour not_allowed)
			(footprints allowed)
		)
		(placement
			(enabled no)
			(sheetname "")
		)
		(fill yes
			(thermal_gap 0.5)
			(thermal_bridge_width 0.5)
			(island_removal_mode 0)
		)
		(polygon
			(pts
				(arc
					(start 31.242 -106.807)
					(mid 29.464 -106.807)
					(end 31.242 -106.807)
				)
			)
		)
	)
	(zone
		(layers "In1.Cu" "In3.Cu" "In6.Cu" "In8.Cu")
		(hatch none 0.5)
		(connect_pads
			(clearance 0)
		)
		(min_thickness 0.25)
		(keepout
			(tracks not_allowed)
			(vias allowed)
			(pads allowed)
			(copperpour not_allowed)
			(footprints allowed)
		)
		(placement
			(enabled no)
			(sheetname "")
		)
		(fill yes
			(thermal_gap 0.5)
			(thermal_bridge_width 0.5)
			(island_removal_mode 0)
		)
		(polygon
			(pts
				(arc
					(start 217.825828 -127.61214)
					(mid 216.047828 -127.61214)
					(end 217.825828 -127.61214)
				)
			)
		)
	)
	(zone
		(layers "In1.Cu" "In3.Cu" "In6.Cu" "In8.Cu")
		(hatch none 0.5)
		(connect_pads
			(clearance 0)
		)
		(min_thickness 0.25)
		(keepout
			(tracks not_allowed)
			(vias allowed)
			(pads allowed)
			(copperpour not_allowed)
			(footprints allowed)
		)
		(placement
			(enabled no)
			(sheetname "")
		)
		(fill yes
			(thermal_gap 0.5)
			(thermal_bridge_width 0.5)
			(island_removal_mode 0)
		)
		(polygon
			(pts
				(arc
					(start 163.469574 -136.906)
					(mid 160.624774 -136.906)
					(end 163.469574 -136.906)
				)
			)
		)
	)
	(zone
		(layers "In1.Cu" "In3.Cu" "In6.Cu" "In8.Cu")
		(hatch none 0.5)
		(connect_pads
			(clearance 0)
		)
		(min_thickness 0.25)
		(keepout
			(tracks not_allowed)
			(vias allowed)
			(pads allowed)
			(copperpour not_allowed)
			(footprints allowed)
		)
		(placement
			(enabled no)
			(sheetname "")
		)
		(fill yes
			(thermal_gap 0.5)
			(thermal_bridge_width 0.5)
			(island_removal_mode 0)
		)
		(polygon
			(pts
				(arc
					(start 68.183506 -131.572)
					(mid 66.405506 -131.572)
					(end 68.183506 -131.572)
				)
			)
		)
	)
	(zone
		(layers "In1.Cu" "In3.Cu" "In6.Cu" "In8.Cu")
		(hatch none 0.5)
		(connect_pads
			(clearance 0)
		)
		(min_thickness 0.25)
		(keepout
			(tracks not_allowed)
			(vias allowed)
			(pads allowed)
			(copperpour not_allowed)
			(footprints allowed)
		)
		(placement
			(enabled no)
			(sheetname "")
		)
		(fill yes
			(thermal_gap 0.5)
			(thermal_bridge_width 0.5)
			(island_removal_mode 0)
		)
		(polygon
			(pts
				(arc
					(start 203.917042 -104.4321)
					(mid 202.139042 -104.4321)
					(end 203.917042 -104.4321)
				)
			)
		)
	)
	(zone
		(layers "In1.Cu" "In3.Cu" "In6.Cu" "In8.Cu")
		(hatch none 0.5)
		(connect_pads
			(clearance 0)
		)
		(min_thickness 0.25)
		(keepout
			(tracks not_allowed)
			(vias allowed)
			(pads allowed)
			(copperpour not_allowed)
			(footprints allowed)
		)
		(placement
			(enabled no)
			(sheetname "")
		)
		(fill yes
			(thermal_gap 0.5)
			(thermal_bridge_width 0.5)
			(island_removal_mode 0)
		)
		(polygon
			(pts
				(arc
					(start 233.944668 -127.300736)
					(mid 232.166668 -127.300736)
					(end 233.944668 -127.300736)
				)
			)
		)
	)
	(zone
		(layers "In1.Cu" "In3.Cu" "In6.Cu" "In8.Cu")
		(hatch none 0.5)
		(connect_pads
			(clearance 0)
		)
		(min_thickness 0.25)
		(keepout
			(tracks not_allowed)
			(vias allowed)
			(pads allowed)
			(copperpour not_allowed)
			(footprints allowed)
		)
		(placement
			(enabled no)
			(sheetname "")
		)
		(fill yes
			(thermal_gap 0.5)
			(thermal_bridge_width 0.5)
			(island_removal_mode 0)
		)
		(polygon
			(pts
				(arc
					(start 183.63946 -49.657)
					(mid 181.86146 -49.657)
					(end 183.63946 -49.657)
				)
			)
		)
	)
	(zone
		(layers "In1.Cu" "In3.Cu" "In6.Cu" "In8.Cu")
		(hatch none 0.5)
		(connect_pads
			(clearance 0)
		)
		(min_thickness 0.25)
		(keepout
			(tracks not_allowed)
			(vias allowed)
			(pads allowed)
			(copperpour not_allowed)
			(footprints allowed)
		)
		(placement
			(enabled no)
			(sheetname "")
		)
		(fill yes
			(thermal_gap 0.5)
			(thermal_bridge_width 0.5)
			(island_removal_mode 0)
		)
		(polygon
			(pts
				(arc
					(start 183.63946 -50.292)
					(mid 181.86146 -50.292)
					(end 183.63946 -50.292)
				)
			)
		)
	)
	(zone
		(layers "In1.Cu" "In3.Cu" "In6.Cu" "In8.Cu")
		(hatch none 0.5)
		(connect_pads
			(clearance 0)
		)
		(min_thickness 0.25)
		(keepout
			(tracks not_allowed)
			(vias allowed)
			(pads allowed)
			(copperpour not_allowed)
			(footprints allowed)
		)
		(placement
			(enabled no)
			(sheetname "")
		)
		(fill yes
			(thermal_gap 0.5)
			(thermal_bridge_width 0.5)
			(island_removal_mode 0)
		)
		(polygon
			(pts
				(arc
					(start 73.334626 -68.853812)
					(mid 71.556626 -68.853812)
					(end 73.334626 -68.853812)
				)
			)
		)
	)
	(zone
		(layers "In1.Cu" "In3.Cu" "In6.Cu" "In8.Cu")
		(hatch none 0.5)
		(connect_pads
			(clearance 0)
		)
		(min_thickness 0.25)
		(keepout
			(tracks not_allowed)
			(vias allowed)
			(pads allowed)
			(copperpour not_allowed)
			(footprints allowed)
		)
		(placement
			(enabled no)
			(sheetname "")
		)
		(fill yes
			(thermal_gap 0.5)
			(thermal_bridge_width 0.5)
			(island_removal_mode 0)
		)
		(polygon
			(pts
				(arc
					(start 270.891 -125.095)
					(mid 269.113 -125.095)
					(end 270.891 -125.095)
				)
			)
		)
	)
	(zone
		(layers "In1.Cu" "In3.Cu" "In6.Cu" "In8.Cu")
		(hatch none 0.5)
		(connect_pads
			(clearance 0)
		)
		(min_thickness 0.25)
		(keepout
			(tracks not_allowed)
			(vias allowed)
			(pads allowed)
			(copperpour not_allowed)
			(footprints allowed)
		)
		(placement
			(enabled no)
			(sheetname "")
		)
		(fill yes
			(thermal_gap 0.5)
			(thermal_bridge_width 0.5)
			(island_removal_mode 0)
		)
		(polygon
			(pts
				(arc
					(start 135.6614 -136.906)
					(mid 132.8166 -136.906)
					(end 135.6614 -136.906)
				)
			)
		)
	)
	(zone
		(layers "In1.Cu" "In3.Cu" "In6.Cu" "In8.Cu")
		(hatch none 0.5)
		(connect_pads
			(clearance 0)
		)
		(min_thickness 0.25)
		(keepout
			(tracks not_allowed)
			(vias allowed)
			(pads allowed)
			(copperpour not_allowed)
			(footprints allowed)
		)
		(placement
			(enabled no)
			(sheetname "")
		)
		(fill yes
			(thermal_gap 0.5)
			(thermal_bridge_width 0.5)
			(island_removal_mode 0)
		)
		(polygon
			(pts
				(arc
					(start 273.177 -89.662)
					(mid 271.399 -89.662)
					(end 273.177 -89.662)
				)
			)
		)
	)
	(zone
		(layers "In1.Cu" "In3.Cu" "In6.Cu" "In8.Cu")
		(hatch none 0.5)
		(connect_pads
			(clearance 0)
		)
		(min_thickness 0.25)
		(keepout
			(tracks not_allowed)
			(vias allowed)
			(pads allowed)
			(copperpour not_allowed)
			(footprints allowed)
		)
		(placement
			(enabled no)
			(sheetname "")
		)
		(fill yes
			(thermal_gap 0.5)
			(thermal_bridge_width 0.5)
			(island_removal_mode 0)
		)
		(polygon
			(pts
				(arc
					(start 123.7996 -131.572)
					(mid 122.0216 -131.572)
					(end 123.7996 -131.572)
				)
			)
		)
	)
	(zone
		(layers "In1.Cu" "In3.Cu" "In6.Cu" "In8.Cu")
		(hatch none 0.5)
		(connect_pads
			(clearance 0)
		)
		(min_thickness 0.25)
		(keepout
			(tracks not_allowed)
			(vias allowed)
			(pads allowed)
			(copperpour not_allowed)
			(footprints allowed)
		)
		(placement
			(enabled no)
			(sheetname "")
		)
		(fill yes
			(thermal_gap 0.5)
			(thermal_bridge_width 0.5)
			(island_removal_mode 0)
		)
		(polygon
			(pts
				(arc
					(start 204.76337 -122.809762)
					(mid 202.98537 -122.809762)
					(end 204.76337 -122.809762)
				)
			)
		)
	)
	(zone
		(layers "In1.Cu" "In3.Cu" "In6.Cu" "In8.Cu")
		(hatch none 0.5)
		(connect_pads
			(clearance 0)
		)
		(min_thickness 0.25)
		(keepout
			(tracks not_allowed)
			(vias allowed)
			(pads allowed)
			(copperpour not_allowed)
			(footprints allowed)
		)
		(placement
			(enabled no)
			(sheetname "")
		)
		(fill yes
			(thermal_gap 0.5)
			(thermal_bridge_width 0.5)
			(island_removal_mode 0)
		)
		(polygon
			(pts
				(arc
					(start 219.140278 -122.047762)
					(mid 217.362278 -122.047762)
					(end 219.140278 -122.047762)
				)
			)
		)
	)
	(zone
		(layers "In1.Cu" "In3.Cu" "In6.Cu" "In8.Cu")
		(hatch none 0.5)
		(connect_pads
			(clearance 0)
		)
		(min_thickness 0.25)
		(keepout
			(tracks not_allowed)
			(vias allowed)
			(pads allowed)
			(copperpour not_allowed)
			(footprints allowed)
		)
		(placement
			(enabled no)
			(sheetname "")
		)
		(fill yes
			(thermal_gap 0.5)
			(thermal_bridge_width 0.5)
			(island_removal_mode 0)
		)
		(polygon
			(pts
				(arc
					(start 233.944668 -129.586736)
					(mid 232.166668 -129.586736)
					(end 233.944668 -129.586736)
				)
			)
		)
	)
	(zone
		(layers "In1.Cu" "In3.Cu" "In6.Cu" "In8.Cu")
		(hatch none 0.5)
		(connect_pads
			(clearance 0)
		)
		(min_thickness 0.25)
		(keepout
			(tracks not_allowed)
			(vias allowed)
			(pads allowed)
			(copperpour not_allowed)
			(footprints allowed)
		)
		(placement
			(enabled no)
			(sheetname "")
		)
		(fill yes
			(thermal_gap 0.5)
			(thermal_bridge_width 0.5)
			(island_removal_mode 0)
		)
		(polygon
			(pts
				(arc
					(start 68.945506 -131.572)
					(mid 67.167506 -131.572)
					(end 68.945506 -131.572)
				)
			)
		)
	)
	(zone
		(layers "In1.Cu" "In3.Cu" "In6.Cu" "In8.Cu")
		(hatch none 0.5)
		(connect_pads
			(clearance 0)
		)
		(min_thickness 0.25)
		(keepout
			(tracks not_allowed)
			(vias allowed)
			(pads allowed)
			(copperpour not_allowed)
			(footprints allowed)
		)
		(placement
			(enabled no)
			(sheetname "")
		)
		(fill yes
			(thermal_gap 0.5)
			(thermal_bridge_width 0.5)
			(island_removal_mode 0)
		)
		(polygon
			(pts
				(arc
					(start 73.334626 -70.885812)
					(mid 71.556626 -70.885812)
					(end 73.334626 -70.885812)
				)
			)
		)
	)
	(zone
		(layers "In1.Cu" "In3.Cu" "In6.Cu" "In8.Cu")
		(hatch none 0.5)
		(connect_pads
			(clearance 0)
		)
		(min_thickness 0.25)
		(keepout
			(tracks not_allowed)
			(vias allowed)
			(pads allowed)
			(copperpour not_allowed)
			(footprints allowed)
		)
		(placement
			(enabled no)
			(sheetname "")
		)
		(fill yes
			(thermal_gap 0.5)
			(thermal_bridge_width 0.5)
			(island_removal_mode 0)
		)
		(polygon
			(pts
				(arc
					(start 272.415 -98.679)
					(mid 270.637 -98.679)
					(end 272.415 -98.679)
				)
			)
		)
	)
	(zone
		(layers "In1.Cu" "In3.Cu" "In6.Cu" "In8.Cu")
		(hatch none 0.5)
		(connect_pads
			(clearance 0)
		)
		(min_thickness 0.25)
		(keepout
			(tracks not_allowed)
			(vias allowed)
			(pads allowed)
			(copperpour not_allowed)
			(footprints allowed)
		)
		(placement
			(enabled no)
			(sheetname "")
		)
		(fill yes
			(thermal_gap 0.5)
			(thermal_bridge_width 0.5)
			(island_removal_mode 0)
		)
		(polygon
			(pts
				(arc
					(start 219.140278 -120.569736)
					(mid 217.362278 -120.569736)
					(end 219.140278 -120.569736)
				)
			)
		)
	)
	(zone
		(layers "In1.Cu" "In3.Cu" "In6.Cu" "In8.Cu")
		(hatch none 0.5)
		(connect_pads
			(clearance 0)
		)
		(min_thickness 0.25)
		(keepout
			(tracks not_allowed)
			(vias allowed)
			(pads allowed)
			(copperpour not_allowed)
			(footprints allowed)
		)
		(placement
			(enabled no)
			(sheetname "")
		)
		(fill yes
			(thermal_gap 0.5)
			(thermal_bridge_width 0.5)
			(island_removal_mode 0)
		)
		(polygon
			(pts
				(arc
					(start 270.891 -123.571)
					(mid 269.113 -123.571)
					(end 270.891 -123.571)
				)
			)
		)
	)
	(zone
		(layers "In1.Cu" "In3.Cu" "In6.Cu" "In8.Cu")
		(hatch none 0.5)
		(connect_pads
			(clearance 0)
		)
		(min_thickness 0.25)
		(keepout
			(tracks not_allowed)
			(vias allowed)
			(pads allowed)
			(copperpour not_allowed)
			(footprints allowed)
		)
		(placement
			(enabled no)
			(sheetname "")
		)
		(fill yes
			(thermal_gap 0.5)
			(thermal_bridge_width 0.5)
			(island_removal_mode 0)
		)
		(polygon
			(pts
				(arc
					(start 270.891 -65.532)
					(mid 269.113 -65.532)
					(end 270.891 -65.532)
				)
			)
		)
	)
	(zone
		(layers "In1.Cu" "In3.Cu" "In6.Cu" "In8.Cu")
		(hatch none 0.5)
		(connect_pads
			(clearance 0)
		)
		(min_thickness 0.25)
		(keepout
			(tracks not_allowed)
			(vias allowed)
			(pads allowed)
			(copperpour not_allowed)
			(footprints allowed)
		)
		(placement
			(enabled no)
			(sheetname "")
		)
		(fill yes
			(thermal_gap 0.5)
			(thermal_bridge_width 0.5)
			(island_removal_mode 0)
		)
		(polygon
			(pts
				(arc
					(start 32.131 -105.283)
					(mid 30.353 -105.283)
					(end 32.131 -105.283)
				)
			)
		)
	)
	(zone
		(layers "In1.Cu" "In3.Cu" "In6.Cu" "In8.Cu")
		(hatch none 0.5)
		(connect_pads
			(clearance 0)
		)
		(min_thickness 0.25)
		(keepout
			(tracks not_allowed)
			(vias allowed)
			(pads allowed)
			(copperpour not_allowed)
			(footprints allowed)
		)
		(placement
			(enabled no)
			(sheetname "")
		)
		(fill yes
			(thermal_gap 0.5)
			(thermal_bridge_width 0.5)
			(island_removal_mode 0)
		)
		(polygon
			(pts
				(arc
					(start 270.891 -113.03)
					(mid 269.113 -113.03)
					(end 270.891 -113.03)
				)
			)
		)
	)
	(zone
		(layers "In1.Cu" "In3.Cu" "In6.Cu" "In8.Cu")
		(hatch none 0.5)
		(connect_pads
			(clearance 0)
		)
		(min_thickness 0.25)
		(keepout
			(tracks not_allowed)
			(vias allowed)
			(pads allowed)
			(copperpour not_allowed)
			(footprints allowed)
		)
		(placement
			(enabled no)
			(sheetname "")
		)
		(fill yes
			(thermal_gap 0.5)
			(thermal_bridge_width 0.5)
			(island_removal_mode 0)
		)
		(polygon
			(pts
				(arc
					(start 273.177 -64.77)
					(mid 271.399 -64.77)
					(end 273.177 -64.77)
				)
			)
		)
	)
	(zone
		(layers "In1.Cu" "In3.Cu" "In6.Cu" "In8.Cu")
		(hatch none 0.5)
		(connect_pads
			(clearance 0)
		)
		(min_thickness 0.25)
		(keepout
			(tracks not_allowed)
			(vias allowed)
			(pads allowed)
			(copperpour not_allowed)
			(footprints allowed)
		)
		(placement
			(enabled no)
			(sheetname "")
		)
		(fill yes
			(thermal_gap 0.5)
			(thermal_bridge_width 0.5)
			(island_removal_mode 0)
		)
		(polygon
			(pts
				(arc
					(start 272.415 -77.597)
					(mid 270.637 -77.597)
					(end 272.415 -77.597)
				)
			)
		)
	)
	(zone
		(layers "In1.Cu" "In3.Cu" "In6.Cu" "In8.Cu")
		(hatch none 0.5)
		(connect_pads
			(clearance 0)
		)
		(min_thickness 0.25)
		(keepout
			(tracks not_allowed)
			(vias allowed)
			(pads allowed)
			(copperpour not_allowed)
			(footprints allowed)
		)
		(placement
			(enabled no)
			(sheetname "")
		)
		(fill yes
			(thermal_gap 0.5)
			(thermal_bridge_width 0.5)
			(island_removal_mode 0)
		)
		(polygon
			(pts
				(arc
					(start 270.891 -89.662)
					(mid 269.113 -89.662)
					(end 270.891 -89.662)
				)
			)
		)
	)
	(zone
		(layers "In1.Cu" "In3.Cu" "In6.Cu" "In8.Cu")
		(hatch none 0.5)
		(connect_pads
			(clearance 0)
		)
		(min_thickness 0.25)
		(keepout
			(tracks not_allowed)
			(vias allowed)
			(pads allowed)
			(copperpour not_allowed)
			(footprints allowed)
		)
		(placement
			(enabled no)
			(sheetname "")
		)
		(fill yes
			(thermal_gap 0.5)
			(thermal_bridge_width 0.5)
			(island_removal_mode 0)
		)
		(polygon
			(pts
				(arc
					(start 289.052 -30.687264)
					(mid 287.274 -30.687264)
					(end 289.052 -30.687264)
				)
			)
		)
	)
	(zone
		(layers "In1.Cu" "In3.Cu" "In6.Cu" "In8.Cu")
		(hatch none 0.5)
		(connect_pads
			(clearance 0)
		)
		(min_thickness 0.25)
		(keepout
			(tracks not_allowed)
			(vias allowed)
			(pads allowed)
			(copperpour not_allowed)
			(footprints allowed)
		)
		(placement
			(enabled no)
			(sheetname "")
		)
		(fill yes
			(thermal_gap 0.5)
			(thermal_bridge_width 0.5)
			(island_removal_mode 0)
		)
		(polygon
			(pts
				(arc
					(start 271.78 -138.938)
					(mid 270.002 -138.938)
					(end 271.78 -138.938)
				)
			)
		)
	)
	(zone
		(layers "In1.Cu" "In3.Cu" "In6.Cu" "In8.Cu")
		(hatch none 0.5)
		(connect_pads
			(clearance 0)
		)
		(min_thickness 0.25)
		(keepout
			(tracks not_allowed)
			(vias allowed)
			(pads allowed)
			(copperpour not_allowed)
			(footprints allowed)
		)
		(placement
			(enabled no)
			(sheetname "")
		)
		(fill yes
			(thermal_gap 0.5)
			(thermal_bridge_width 0.5)
			(island_removal_mode 0)
		)
		(polygon
			(pts
				(arc
					(start 272.415 -74.549)
					(mid 270.637 -74.549)
					(end 272.415 -74.549)
				)
			)
		)
	)
	(zone
		(layers "In1.Cu" "In3.Cu" "In6.Cu" "In8.Cu")
		(hatch none 0.5)
		(connect_pads
			(clearance 0)
		)
		(min_thickness 0.25)
		(keepout
			(tracks not_allowed)
			(vias allowed)
			(pads allowed)
			(copperpour not_allowed)
			(footprints allowed)
		)
		(placement
			(enabled no)
			(sheetname "")
		)
		(fill yes
			(thermal_gap 0.5)
			(thermal_bridge_width 0.5)
			(island_removal_mode 0)
		)
		(polygon
			(pts
				(arc
					(start 215.585802 -129.13614)
					(mid 213.807802 -129.13614)
					(end 215.585802 -129.13614)
				)
			)
		)
	)
	(zone
		(layers "In1.Cu" "In3.Cu" "In6.Cu" "In8.Cu")
		(hatch none 0.5)
		(connect_pads
			(clearance 0)
		)
		(min_thickness 0.25)
		(keepout
			(tracks not_allowed)
			(vias allowed)
			(pads allowed)
			(copperpour not_allowed)
			(footprints allowed)
		)
		(placement
			(enabled no)
			(sheetname "")
		)
		(fill yes
			(thermal_gap 0.5)
			(thermal_bridge_width 0.5)
			(island_removal_mode 0)
		)
		(polygon
			(pts
				(arc
					(start 217.825828 -129.13614)
					(mid 216.047828 -129.13614)
					(end 217.825828 -129.13614)
				)
			)
		)
	)
	(zone
		(layers "In1.Cu" "In3.Cu" "In6.Cu" "In8.Cu")
		(hatch none 0.5)
		(connect_pads
			(clearance 0)
		)
		(min_thickness 0.25)
		(keepout
			(tracks not_allowed)
			(vias allowed)
			(pads allowed)
			(copperpour not_allowed)
			(footprints allowed)
		)
		(placement
			(enabled no)
			(sheetname "")
		)
		(fill yes
			(thermal_gap 0.5)
			(thermal_bridge_width 0.5)
			(island_removal_mode 0)
		)
		(polygon
			(pts
				(arc
					(start 271.653 -97.917)
					(mid 269.875 -97.917)
					(end 271.653 -97.917)
				)
			)
		)
	)
	(zone
		(layers "In1.Cu" "In3.Cu" "In6.Cu" "In8.Cu")
		(hatch none 0.5)
		(connect_pads
			(clearance 0)
		)
		(min_thickness 0.25)
		(keepout
			(tracks not_allowed)
			(vias allowed)
			(pads allowed)
			(copperpour not_allowed)
			(footprints allowed)
		)
		(placement
			(enabled no)
			(sheetname "")
		)
		(fill yes
			(thermal_gap 0.5)
			(thermal_bridge_width 0.5)
			(island_removal_mode 0)
		)
		(polygon
			(pts
				(arc
					(start 95.991426 -126.492)
					(mid 94.213426 -126.492)
					(end 95.991426 -126.492)
				)
			)
		)
	)
	(zone
		(layers "In1.Cu" "In3.Cu" "In6.Cu" "In8.Cu")
		(hatch none 0.5)
		(connect_pads
			(clearance 0)
		)
		(min_thickness 0.25)
		(keepout
			(tracks not_allowed)
			(vias allowed)
			(pads allowed)
			(copperpour not_allowed)
			(footprints allowed)
		)
		(placement
			(enabled no)
			(sheetname "")
		)
		(fill yes
			(thermal_gap 0.5)
			(thermal_bridge_width 0.5)
			(island_removal_mode 0)
		)
		(polygon
			(pts
				(arc
					(start 219.140278 -121.331736)
					(mid 217.362278 -121.331736)
					(end 219.140278 -121.331736)
				)
			)
		)
	)
	(zone
		(layers "In1.Cu" "In3.Cu" "In6.Cu" "In8.Cu")
		(hatch none 0.5)
		(connect_pads
			(clearance 0)
		)
		(min_thickness 0.25)
		(keepout
			(tracks not_allowed)
			(vias allowed)
			(pads allowed)
			(copperpour not_allowed)
			(footprints allowed)
		)
		(placement
			(enabled no)
			(sheetname "")
		)
		(fill yes
			(thermal_gap 0.5)
			(thermal_bridge_width 0.5)
			(island_removal_mode 0)
		)
		(polygon
			(pts
				(arc
					(start 172.72 -52.197)
					(mid 170.942 -52.197)
					(end 172.72 -52.197)
				)
			)
		)
	)
	(zone
		(layers "In1.Cu" "In3.Cu" "In6.Cu" "In8.Cu")
		(hatch none 0.5)
		(connect_pads
			(clearance 0)
		)
		(min_thickness 0.25)
		(keepout
			(tracks not_allowed)
			(vias allowed)
			(pads allowed)
			(copperpour not_allowed)
			(footprints allowed)
		)
		(placement
			(enabled no)
			(sheetname "")
		)
		(fill yes
			(thermal_gap 0.5)
			(thermal_bridge_width 0.5)
			(island_removal_mode 0)
		)
		(polygon
			(pts
				(arc
					(start 208.57337 -122.809762)
					(mid 206.79537 -122.809762)
					(end 208.57337 -122.809762)
				)
			)
		)
	)
	(zone
		(layers "In1.Cu" "In3.Cu" "In6.Cu" "In8.Cu")
		(hatch none 0.5)
		(connect_pads
			(clearance 0)
		)
		(min_thickness 0.25)
		(keepout
			(tracks not_allowed)
			(vias allowed)
			(pads allowed)
			(copperpour not_allowed)
			(footprints allowed)
		)
		(placement
			(enabled no)
			(sheetname "")
		)
		(fill yes
			(thermal_gap 0.5)
			(thermal_bridge_width 0.5)
			(island_removal_mode 0)
		)
		(polygon
			(pts
				(arc
					(start 161.798 -49.657)
					(mid 160.02 -49.657)
					(end 161.798 -49.657)
				)
			)
		)
	)
	(zone
		(layers "In1.Cu" "In3.Cu" "In6.Cu" "In8.Cu")
		(hatch none 0.5)
		(connect_pads
			(clearance 0)
		)
		(min_thickness 0.25)
		(keepout
			(tracks not_allowed)
			(vias allowed)
			(pads allowed)
			(copperpour not_allowed)
			(footprints allowed)
		)
		(placement
			(enabled no)
			(sheetname "")
		)
		(fill yes
			(thermal_gap 0.5)
			(thermal_bridge_width 0.5)
			(island_removal_mode 0)
		)
		(polygon
			(pts
				(arc
					(start 89.154 -50.419)
					(mid 87.376 -50.419)
					(end 89.154 -50.419)
				)
			)
		)
	)
	(zone
		(layers "In1.Cu" "In3.Cu" "In6.Cu" "In8.Cu")
		(hatch none 0.5)
		(connect_pads
			(clearance 0)
		)
		(min_thickness 0.25)
		(keepout
			(tracks not_allowed)
			(vias allowed)
			(pads allowed)
			(copperpour not_allowed)
			(footprints allowed)
		)
		(placement
			(enabled no)
			(sheetname "")
		)
		(fill yes
			(thermal_gap 0.5)
			(thermal_bridge_width 0.5)
			(island_removal_mode 0)
		)
		(polygon
			(pts
				(arc
					(start 40.767 -106.045)
					(mid 38.989 -106.045)
					(end 40.767 -106.045)
				)
			)
		)
	)
	(zone
		(layers "In1.Cu" "In3.Cu" "In6.Cu" "In8.Cu")
		(hatch none 0.5)
		(connect_pads
			(clearance 0)
		)
		(min_thickness 0.25)
		(keepout
			(tracks not_allowed)
			(vias allowed)
			(pads allowed)
			(copperpour not_allowed)
			(footprints allowed)
		)
		(placement
			(enabled no)
			(sheetname "")
		)
		(fill yes
			(thermal_gap 0.5)
			(thermal_bridge_width 0.5)
			(island_removal_mode 0)
		)
		(polygon
			(pts
				(arc
					(start 270.891 -74.549)
					(mid 269.113 -74.549)
					(end 270.891 -74.549)
				)
			)
		)
	)
	(zone
		(layers "In1.Cu" "In3.Cu" "In6.Cu" "In8.Cu")
		(hatch none 0.5)
		(connect_pads
			(clearance 0)
		)
		(min_thickness 0.25)
		(keepout
			(tracks not_allowed)
			(vias allowed)
			(pads allowed)
			(copperpour not_allowed)
			(footprints allowed)
		)
		(placement
			(enabled no)
			(sheetname "")
		)
		(fill yes
			(thermal_gap 0.5)
			(thermal_bridge_width 0.5)
			(island_removal_mode 0)
		)
		(polygon
			(pts
				(arc
					(start 71.302626 -70.885812)
					(mid 69.524626 -70.885812)
					(end 71.302626 -70.885812)
				)
			)
		)
	)
	(zone
		(layers "In1.Cu" "In3.Cu" "In6.Cu" "In8.Cu")
		(hatch none 0.5)
		(connect_pads
			(clearance 0)
		)
		(min_thickness 0.25)
		(keepout
			(tracks not_allowed)
			(vias allowed)
			(pads allowed)
			(copperpour not_allowed)
			(footprints allowed)
		)
		(placement
			(enabled no)
			(sheetname "")
		)
		(fill yes
			(thermal_gap 0.5)
			(thermal_bridge_width 0.5)
			(island_removal_mode 0)
		)
		(polygon
			(pts
				(arc
					(start 273.177 -73.787)
					(mid 271.399 -73.787)
					(end 273.177 -73.787)
				)
			)
		)
	)
	(zone
		(layers "In1.Cu" "In3.Cu" "In6.Cu" "In8.Cu")
		(hatch none 0.5)
		(connect_pads
			(clearance 0)
		)
		(min_thickness 0.25)
		(keepout
			(tracks not_allowed)
			(vias allowed)
			(pads allowed)
			(copperpour not_allowed)
			(footprints allowed)
		)
		(placement
			(enabled no)
			(sheetname "")
		)
		(fill yes
			(thermal_gap 0.5)
			(thermal_bridge_width 0.5)
			(island_removal_mode 0)
		)
		(polygon
			(pts
				(arc
					(start 206.965042 -105.134664)
					(mid 205.187042 -105.134664)
					(end 206.965042 -105.134664)
				)
			)
		)
	)
	(zone
		(layers "In1.Cu" "In3.Cu" "In6.Cu" "In8.Cu")
		(hatch none 0.5)
		(connect_pads
			(clearance 0)
		)
		(min_thickness 0.25)
		(keepout
			(tracks not_allowed)
			(vias allowed)
			(pads allowed)
			(copperpour not_allowed)
			(footprints allowed)
		)
		(placement
			(enabled no)
			(sheetname "")
		)
		(fill yes
			(thermal_gap 0.5)
			(thermal_bridge_width 0.5)
			(island_removal_mode 0)
		)
		(polygon
			(pts
				(arc
					(start 40.767 -105.283)
					(mid 38.989 -105.283)
					(end 40.767 -105.283)
				)
			)
		)
	)
	(zone
		(layers "In1.Cu" "In3.Cu" "In6.Cu" "In8.Cu")
		(hatch none 0.5)
		(connect_pads
			(clearance 0)
		)
		(min_thickness 0.25)
		(keepout
			(tracks not_allowed)
			(vias allowed)
			(pads allowed)
			(copperpour not_allowed)
			(footprints allowed)
		)
		(placement
			(enabled no)
			(sheetname "")
		)
		(fill yes
			(thermal_gap 0.5)
			(thermal_bridge_width 0.5)
			(island_removal_mode 0)
		)
		(polygon
			(pts
				(arc
					(start 188.336174 -60.96)
					(mid 185.542174 -60.96)
					(end 188.336174 -60.96)
				)
			)
		)
	)
	(zone
		(layers "In1.Cu" "In3.Cu" "In6.Cu" "In8.Cu")
		(hatch none 0.5)
		(connect_pads
			(clearance 0)
		)
		(min_thickness 0.25)
		(keepout
			(tracks not_allowed)
			(vias allowed)
			(pads allowed)
			(copperpour not_allowed)
			(footprints allowed)
		)
		(placement
			(enabled no)
			(sheetname "")
		)
		(fill yes
			(thermal_gap 0.5)
			(thermal_bridge_width 0.5)
			(island_removal_mode 0)
		)
		(polygon
			(pts
				(arc
					(start 13.76172 -70.939914)
					(mid 11.01852 -70.939914)
					(end 13.76172 -70.939914)
				)
			)
		)
	)
	(zone
		(layers "In1.Cu" "In3.Cu" "In6.Cu" "In8.Cu")
		(hatch none 0.5)
		(connect_pads
			(clearance 0)
		)
		(min_thickness 0.25)
		(keepout
			(tracks not_allowed)
			(vias allowed)
			(pads allowed)
			(copperpour not_allowed)
			(footprints allowed)
		)
		(placement
			(enabled no)
			(sheetname "")
		)
		(fill yes
			(thermal_gap 0.5)
			(thermal_bridge_width 0.5)
			(island_removal_mode 0)
		)
		(polygon
			(pts
				(arc
					(start 207.063086 -123.528328)
					(mid 205.285086 -123.528328)
					(end 207.063086 -123.528328)
				)
			)
		)
	)
	(zone
		(layers "In1.Cu" "In3.Cu" "In6.Cu" "In8.Cu")
		(hatch none 0.5)
		(connect_pads
			(clearance 0)
		)
		(min_thickness 0.25)
		(keepout
			(tracks not_allowed)
			(vias allowed)
			(pads allowed)
			(copperpour not_allowed)
			(footprints allowed)
		)
		(placement
			(enabled no)
			(sheetname "")
		)
		(fill yes
			(thermal_gap 0.5)
			(thermal_bridge_width 0.5)
			(island_removal_mode 0)
		)
		(polygon
			(pts
				(arc
					(start 217.708226 -104.418638)
					(mid 215.930226 -104.418638)
					(end 217.708226 -104.418638)
				)
			)
		)
	)
	(zone
		(layers "In1.Cu" "In3.Cu" "In6.Cu" "In8.Cu")
		(hatch none 0.5)
		(connect_pads
			(clearance 0)
		)
		(min_thickness 0.25)
		(keepout
			(tracks not_allowed)
			(vias allowed)
			(pads allowed)
			(copperpour not_allowed)
			(footprints allowed)
		)
		(placement
			(enabled no)
			(sheetname "")
		)
		(fill yes
			(thermal_gap 0.5)
			(thermal_bridge_width 0.5)
			(island_removal_mode 0)
		)
		(polygon
			(pts
				(arc
					(start 78.232 -49.784)
					(mid 76.454 -49.784)
					(end 78.232 -49.784)
				)
			)
		)
	)
	(zone
		(layers "In1.Cu" "In3.Cu" "In6.Cu" "In8.Cu")
		(hatch none 0.5)
		(connect_pads
			(clearance 0)
		)
		(min_thickness 0.25)
		(keepout
			(tracks not_allowed)
			(vias allowed)
			(pads allowed)
			(copperpour not_allowed)
			(footprints allowed)
		)
		(placement
			(enabled no)
			(sheetname "")
		)
		(fill yes
			(thermal_gap 0.5)
			(thermal_bridge_width 0.5)
			(island_removal_mode 0)
		)
		(polygon
			(pts
				(arc
					(start 215.585802 -130.66014)
					(mid 213.807802 -130.66014)
					(end 215.585802 -130.66014)
				)
			)
		)
	)
	(zone
		(layers "In1.Cu" "In3.Cu" "In6.Cu" "In8.Cu")
		(hatch none 0.5)
		(connect_pads
			(clearance 0)
		)
		(min_thickness 0.25)
		(keepout
			(tracks not_allowed)
			(vias allowed)
			(pads allowed)
			(copperpour not_allowed)
			(footprints allowed)
		)
		(placement
			(enabled no)
			(sheetname "")
		)
		(fill yes
			(thermal_gap 0.5)
			(thermal_bridge_width 0.5)
			(island_removal_mode 0)
		)
		(polygon
			(pts
				(arc
					(start 234.72013 -126.609094)
					(mid 232.94213 -126.609094)
					(end 234.72013 -126.609094)
				)
			)
		)
	)
	(zone
		(layers "In1.Cu" "In3.Cu" "In6.Cu" "In8.Cu")
		(hatch none 0.5)
		(connect_pads
			(clearance 0)
		)
		(min_thickness 0.25)
		(keepout
			(tracks not_allowed)
			(vias allowed)
			(pads allowed)
			(copperpour not_allowed)
			(footprints allowed)
		)
		(placement
			(enabled no)
			(sheetname "")
		)
		(fill yes
			(thermal_gap 0.5)
			(thermal_bridge_width 0.5)
			(island_removal_mode 0)
		)
		(polygon
			(pts
				(arc
					(start 205.52537 -122.047762)
					(mid 203.74737 -122.047762)
					(end 205.52537 -122.047762)
				)
			)
		)
	)
	(zone
		(layers "In1.Cu" "In3.Cu" "In6.Cu" "In8.Cu")
		(hatch none 0.5)
		(connect_pads
			(clearance 0)
		)
		(min_thickness 0.25)
		(keepout
			(tracks not_allowed)
			(vias allowed)
			(pads allowed)
			(copperpour not_allowed)
			(footprints allowed)
		)
		(placement
			(enabled no)
			(sheetname "")
		)
		(fill yes
			(thermal_gap 0.5)
			(thermal_bridge_width 0.5)
			(island_removal_mode 0)
		)
		(polygon
			(pts
				(arc
					(start 270.129 -63.246)
					(mid 268.351 -63.246)
					(end 270.129 -63.246)
				)
			)
		)
	)
	(zone
		(layers "In1.Cu" "In3.Cu" "In6.Cu" "In8.Cu")
		(hatch none 0.5)
		(connect_pads
			(clearance 0)
		)
		(min_thickness 0.25)
		(keepout
			(tracks not_allowed)
			(vias allowed)
			(pads allowed)
			(copperpour not_allowed)
			(footprints allowed)
		)
		(placement
			(enabled no)
			(sheetname "")
		)
		(fill yes
			(thermal_gap 0.5)
			(thermal_bridge_width 0.5)
			(island_removal_mode 0)
		)
		(polygon
			(pts
				(arc
					(start 66.667126 -70.409816)
					(mid 62.272926 -70.409816)
					(end 66.667126 -70.409816)
				)
			)
		)
	)
	(zone
		(layers "In1.Cu" "In3.Cu" "In6.Cu" "In8.Cu")
		(hatch none 0.5)
		(connect_pads
			(clearance 0)
		)
		(min_thickness 0.25)
		(keepout
			(tracks not_allowed)
			(vias allowed)
			(pads allowed)
			(copperpour not_allowed)
			(footprints allowed)
		)
		(placement
			(enabled no)
			(sheetname "")
		)
		(fill yes
			(thermal_gap 0.5)
			(thermal_bridge_width 0.5)
			(island_removal_mode 0)
		)
		(polygon
			(pts
				(arc
					(start 271.653 -122.809)
					(mid 269.875 -122.809)
					(end 271.653 -122.809)
				)
			)
		)
	)
	(zone
		(layers "In1.Cu" "In3.Cu" "In6.Cu" "In8.Cu")
		(hatch none 0.5)
		(connect_pads
			(clearance 0)
		)
		(min_thickness 0.25)
		(keepout
			(tracks not_allowed)
			(vias allowed)
			(pads allowed)
			(copperpour not_allowed)
			(footprints allowed)
		)
		(placement
			(enabled no)
			(sheetname "")
		)
		(fill yes
			(thermal_gap 0.5)
			(thermal_bridge_width 0.5)
			(island_removal_mode 0)
		)
		(polygon
			(pts
				(arc
					(start 110.236 -60.96)
					(mid 107.442 -60.96)
					(end 110.236 -60.96)
				)
			)
		)
	)
	(zone
		(layers "In1.Cu" "In3.Cu" "In6.Cu" "In8.Cu")
		(hatch none 0.5)
		(connect_pads
			(clearance 0)
		)
		(min_thickness 0.25)
		(keepout
			(tracks not_allowed)
			(vias allowed)
			(pads allowed)
			(copperpour not_allowed)
			(footprints allowed)
		)
		(placement
			(enabled no)
			(sheetname "")
		)
		(fill yes
			(thermal_gap 0.5)
			(thermal_bridge_width 0.5)
			(island_removal_mode 0)
		)
		(polygon
			(pts
				(arc
					(start 107.853226 -136.906)
					(mid 105.008426 -136.906)
					(end 107.853226 -136.906)
				)
			)
		)
	)
	(zone
		(layers "In1.Cu" "In3.Cu" "In6.Cu" "In8.Cu")
		(hatch none 0.5)
		(connect_pads
			(clearance 0)
		)
		(min_thickness 0.25)
		(keepout
			(tracks not_allowed)
			(vias allowed)
			(pads allowed)
			(copperpour not_allowed)
			(footprints allowed)
		)
		(placement
			(enabled no)
			(sheetname "")
		)
		(fill yes
			(thermal_gap 0.5)
			(thermal_bridge_width 0.5)
			(island_removal_mode 0)
		)
		(polygon
			(pts
				(arc
					(start 271.653 -63.246)
					(mid 269.875 -63.246)
					(end 271.653 -63.246)
				)
			)
		)
	)
	(zone
		(layers "In1.Cu" "In3.Cu" "In6.Cu" "In8.Cu")
		(hatch none 0.5)
		(connect_pads
			(clearance 0)
		)
		(min_thickness 0.25)
		(keepout
			(tracks not_allowed)
			(vias allowed)
			(pads allowed)
			(copperpour not_allowed)
			(footprints allowed)
		)
		(placement
			(enabled no)
			(sheetname "")
		)
		(fill yes
			(thermal_gap 0.5)
			(thermal_bridge_width 0.5)
			(island_removal_mode 0)
		)
		(polygon
			(pts
				(arc
					(start 72.771 -49.784)
					(mid 70.993 -49.784)
					(end 72.771 -49.784)
				)
			)
		)
	)
	(zone
		(layers "In1.Cu" "In3.Cu" "In6.Cu" "In8.Cu")
		(hatch none 0.5)
		(connect_pads
			(clearance 0)
		)
		(min_thickness 0.25)
		(keepout
			(tracks not_allowed)
			(vias allowed)
			(pads allowed)
			(copperpour not_allowed)
			(footprints allowed)
		)
		(placement
			(enabled no)
			(sheetname "")
		)
		(fill yes
			(thermal_gap 0.5)
			(thermal_bridge_width 0.5)
			(island_removal_mode 0)
		)
		(polygon
			(pts
				(arc
					(start 270.891 -113.792)
					(mid 269.113 -113.792)
					(end 270.891 -113.792)
				)
			)
		)
	)
	(zone
		(layers "In1.Cu" "In3.Cu" "In6.Cu" "In8.Cu")
		(hatch none 0.5)
		(connect_pads
			(clearance 0)
		)
		(min_thickness 0.25)
		(keepout
			(tracks not_allowed)
			(vias allowed)
			(pads allowed)
			(copperpour not_allowed)
			(footprints allowed)
		)
		(placement
			(enabled no)
			(sheetname "")
		)
		(fill yes
			(thermal_gap 0.5)
			(thermal_bridge_width 0.5)
			(island_removal_mode 0)
		)
		(polygon
			(pts
				(arc
					(start 167.259 -49.657)
					(mid 165.481 -49.657)
					(end 167.259 -49.657)
				)
			)
		)
	)
	(zone
		(layers "In1.Cu" "In3.Cu" "In6.Cu" "In8.Cu")
		(hatch none 0.5)
		(connect_pads
			(clearance 0)
		)
		(min_thickness 0.25)
		(keepout
			(tracks not_allowed)
			(vias allowed)
			(pads allowed)
			(copperpour not_allowed)
			(footprints allowed)
		)
		(placement
			(enabled no)
			(sheetname "")
		)
		(fill yes
			(thermal_gap 0.5)
			(thermal_bridge_width 0.5)
			(island_removal_mode 0)
		)
		(polygon
			(pts
				(arc
					(start 183.63946 -51.562)
					(mid 181.86146 -51.562)
					(end 183.63946 -51.562)
				)
			)
		)
	)
	(zone
		(layers "In1.Cu" "In3.Cu" "In6.Cu" "In8.Cu")
		(hatch none 0.5)
		(connect_pads
			(clearance 0)
		)
		(min_thickness 0.25)
		(keepout
			(tracks not_allowed)
			(vias allowed)
			(pads allowed)
			(copperpour not_allowed)
			(footprints allowed)
		)
		(placement
			(enabled no)
			(sheetname "")
		)
		(fill yes
			(thermal_gap 0.5)
			(thermal_bridge_width 0.5)
			(island_removal_mode 0)
		)
		(polygon
			(pts
				(arc
					(start 147.8534 -136.906)
					(mid 145.0086 -136.906)
					(end 147.8534 -136.906)
				)
			)
		)
	)
	(zone
		(layers "In1.Cu" "In3.Cu" "In6.Cu" "In8.Cu")
		(hatch none 0.5)
		(connect_pads
			(clearance 0)
		)
		(min_thickness 0.25)
		(keepout
			(tracks not_allowed)
			(vias allowed)
			(pads allowed)
			(copperpour not_allowed)
			(footprints allowed)
		)
		(placement
			(enabled no)
			(sheetname "")
		)
		(fill yes
			(thermal_gap 0.5)
			(thermal_bridge_width 0.5)
			(island_removal_mode 0)
		)
		(polygon
			(pts
				(arc
					(start 221.426278 -120.569736)
					(mid 219.648278 -120.569736)
					(end 221.426278 -120.569736)
				)
			)
		)
	)
	(zone
		(layers "In1.Cu" "In3.Cu" "In6.Cu" "In8.Cu")
		(hatch none 0.5)
		(connect_pads
			(clearance 0)
		)
		(min_thickness 0.25)
		(keepout
			(tracks not_allowed)
			(vias allowed)
			(pads allowed)
			(copperpour not_allowed)
			(footprints allowed)
		)
		(placement
			(enabled no)
			(sheetname "")
		)
		(fill yes
			(thermal_gap 0.5)
			(thermal_bridge_width 0.5)
			(island_removal_mode 0)
		)
		(polygon
			(pts
				(arc
					(start 272.086578 -92.822268)
					(mid 270.308578 -92.822268)
					(end 272.086578 -92.822268)
				)
			)
		)
	)
	(zone
		(layers "In1.Cu" "In3.Cu" "In6.Cu" "In8.Cu")
		(hatch none 0.5)
		(connect_pads
			(clearance 0)
		)
		(min_thickness 0.25)
		(keepout
			(tracks not_allowed)
			(vias allowed)
			(pads allowed)
			(copperpour not_allowed)
			(footprints allowed)
		)
		(placement
			(enabled no)
			(sheetname "")
		)
		(fill yes
			(thermal_gap 0.5)
			(thermal_bridge_width 0.5)
			(island_removal_mode 0)
		)
		(polygon
			(pts
				(arc
					(start 271.78 -136.652)
					(mid 270.002 -136.652)
					(end 271.78 -136.652)
				)
			)
		)
	)
	(zone
		(layers "In1.Cu" "In3.Cu" "In6.Cu" "In8.Cu")
		(hatch none 0.5)
		(connect_pads
			(clearance 0)
		)
		(min_thickness 0.25)
		(keepout
			(tracks not_allowed)
			(vias allowed)
			(pads allowed)
			(copperpour not_allowed)
			(footprints allowed)
		)
		(placement
			(enabled no)
			(sheetname "")
		)
		(fill yes
			(thermal_gap 0.5)
			(thermal_bridge_width 0.5)
			(island_removal_mode 0)
		)
		(polygon
			(pts
				(arc
					(start 273.177 -109.982)
					(mid 271.399 -109.982)
					(end 273.177 -109.982)
				)
			)
		)
	)
	(zone
		(layers "In1.Cu" "In3.Cu" "In6.Cu" "In8.Cu")
		(hatch none 0.5)
		(connect_pads
			(clearance 0)
		)
		(min_thickness 0.25)
		(keepout
			(tracks not_allowed)
			(vias allowed)
			(pads allowed)
			(copperpour not_allowed)
			(footprints allowed)
		)
		(placement
			(enabled no)
			(sheetname "")
		)
		(fill yes
			(thermal_gap 0.5)
			(thermal_bridge_width 0.5)
			(island_removal_mode 0)
		)
		(polygon
			(pts
				(arc
					(start 55.991506 -131.572)
					(mid 54.213506 -131.572)
					(end 55.991506 -131.572)
				)
			)
		)
	)
	(zone
		(layers "In1.Cu" "In3.Cu" "In6.Cu" "In8.Cu")
		(hatch none 0.5)
		(connect_pads
			(clearance 0)
		)
		(min_thickness 0.25)
		(keepout
			(tracks not_allowed)
			(vias allowed)
			(pads allowed)
			(copperpour not_allowed)
			(footprints allowed)
		)
		(placement
			(enabled no)
			(sheetname "")
		)
		(fill yes
			(thermal_gap 0.5)
			(thermal_bridge_width 0.5)
			(island_removal_mode 0)
		)
		(polygon
			(pts
				(arc
					(start 232.480104 -128.062736)
					(mid 230.702104 -128.062736)
					(end 232.480104 -128.062736)
				)
			)
		)
	)
	(zone
		(layers "In1.Cu" "In3.Cu" "In6.Cu" "In8.Cu")
		(hatch none 0.5)
		(connect_pads
			(clearance 0)
		)
		(min_thickness 0.25)
		(keepout
			(tracks not_allowed)
			(vias allowed)
			(pads allowed)
			(copperpour not_allowed)
			(footprints allowed)
		)
		(placement
			(enabled no)
			(sheetname "")
		)
		(fill yes
			(thermal_gap 0.5)
			(thermal_bridge_width 0.5)
			(island_removal_mode 0)
		)
		(polygon
			(pts
				(arc
					(start 50.20564 -52.8828)
					(mid 48.42764 -52.8828)
					(end 50.20564 -52.8828)
				)
			)
		)
	)
	(zone
		(layers "In1.Cu" "In3.Cu" "In6.Cu" "In8.Cu")
		(hatch none 0.5)
		(connect_pads
			(clearance 0)
		)
		(min_thickness 0.25)
		(keepout
			(tracks not_allowed)
			(vias allowed)
			(pads allowed)
			(copperpour not_allowed)
			(footprints allowed)
		)
		(placement
			(enabled no)
			(sheetname "")
		)
		(fill yes
			(thermal_gap 0.5)
			(thermal_bridge_width 0.5)
			(island_removal_mode 0)
		)
		(polygon
			(pts
				(arc
					(start 235.468668 -127.300736)
					(mid 233.690668 -127.300736)
					(end 235.468668 -127.300736)
				)
			)
		)
	)
	(zone
		(layers "In1.Cu" "In3.Cu" "In6.Cu" "In8.Cu")
		(hatch none 0.5)
		(connect_pads
			(clearance 0)
		)
		(min_thickness 0.25)
		(keepout
			(tracks not_allowed)
			(vias allowed)
			(pads allowed)
			(copperpour not_allowed)
			(footprints allowed)
		)
		(placement
			(enabled no)
			(sheetname "")
		)
		(fill yes
			(thermal_gap 0.5)
			(thermal_bridge_width 0.5)
			(island_removal_mode 0)
		)
		(polygon
			(pts
				(arc
					(start 272.09242 -116.929408)
					(mid 270.31442 -116.929408)
					(end 272.09242 -116.929408)
				)
			)
		)
	)
	(zone
		(layers "In1.Cu" "In3.Cu" "In6.Cu" "In8.Cu")
		(hatch none 0.5)
		(connect_pads
			(clearance 0)
		)
		(min_thickness 0.25)
		(keepout
			(tracks not_allowed)
			(vias allowed)
			(pads allowed)
			(copperpour not_allowed)
			(footprints allowed)
		)
		(placement
			(enabled no)
			(sheetname "")
		)
		(fill yes
			(thermal_gap 0.5)
			(thermal_bridge_width 0.5)
			(island_removal_mode 0)
		)
		(polygon
			(pts
				(arc
					(start 273.177 -76.835)
					(mid 271.399 -76.835)
					(end 273.177 -76.835)
				)
			)
		)
	)
	(zone
		(layers "In1.Cu" "In3.Cu" "In6.Cu" "In8.Cu")
		(hatch none 0.5)
		(connect_pads
			(clearance 0)
		)
		(min_thickness 0.25)
		(keepout
			(tracks not_allowed)
			(vias allowed)
			(pads allowed)
			(copperpour not_allowed)
			(footprints allowed)
		)
		(placement
			(enabled no)
			(sheetname "")
		)
		(fill yes
			(thermal_gap 0.5)
			(thermal_bridge_width 0.5)
			(island_removal_mode 0)
		)
		(polygon
			(pts
				(arc
					(start 221.439994 -123.528328)
					(mid 219.661994 -123.528328)
					(end 221.439994 -123.528328)
				)
			)
		)
	)
	(zone
		(layers "In1.Cu" "In3.Cu" "In6.Cu" "In8.Cu")
		(hatch none 0.5)
		(connect_pads
			(clearance 0)
		)
		(min_thickness 0.25)
		(keepout
			(tracks not_allowed)
			(vias allowed)
			(pads allowed)
			(copperpour not_allowed)
			(footprints allowed)
		)
		(placement
			(enabled no)
			(sheetname "")
		)
		(fill yes
			(thermal_gap 0.5)
			(thermal_bridge_width 0.5)
			(island_removal_mode 0)
		)
		(polygon
			(pts
				(arc
					(start 270.129 -61.722)
					(mid 268.351 -61.722)
					(end 270.129 -61.722)
				)
			)
		)
	)
	(zone
		(layers "In1.Cu" "In3.Cu" "In6.Cu" "In8.Cu")
		(hatch none 0.5)
		(connect_pads
			(clearance 0)
		)
		(min_thickness 0.25)
		(keepout
			(tracks not_allowed)
			(vias allowed)
			(pads allowed)
			(copperpour not_allowed)
			(footprints allowed)
		)
		(placement
			(enabled no)
			(sheetname "")
		)
		(fill yes
			(thermal_gap 0.5)
			(thermal_bridge_width 0.5)
			(island_removal_mode 0)
		)
		(polygon
			(pts
				(arc
					(start 217.616278 -122.047762)
					(mid 215.838278 -122.047762)
					(end 217.616278 -122.047762)
				)
			)
		)
	)
	(zone
		(layers "In1.Cu" "In3.Cu" "In6.Cu" "In8.Cu")
		(hatch none 0.5)
		(connect_pads
			(clearance 0)
		)
		(min_thickness 0.25)
		(keepout
			(tracks not_allowed)
			(vias allowed)
			(pads allowed)
			(copperpour not_allowed)
			(footprints allowed)
		)
		(placement
			(enabled no)
			(sheetname "")
		)
		(fill yes
			(thermal_gap 0.5)
			(thermal_bridge_width 0.5)
			(island_removal_mode 0)
		)
		(polygon
			(pts
				(arc
					(start 164.561774 -126.492)
					(mid 162.783774 -126.492)
					(end 164.561774 -126.492)
				)
			)
		)
	)
	(zone
		(layers "In1.Cu" "In3.Cu" "In6.Cu" "In8.Cu")
		(hatch none 0.5)
		(connect_pads
			(clearance 0)
		)
		(min_thickness 0.25)
		(keepout
			(tracks not_allowed)
			(vias allowed)
			(pads allowed)
			(copperpour not_allowed)
			(footprints allowed)
		)
		(placement
			(enabled no)
			(sheetname "")
		)
		(fill yes
			(thermal_gap 0.5)
			(thermal_bridge_width 0.5)
			(island_removal_mode 0)
		)
		(polygon
			(pts
				(arc
					(start 273.177 -110.744)
					(mid 271.399 -110.744)
					(end 273.177 -110.744)
				)
			)
		)
	)
	(zone
		(layers "In1.Cu" "In3.Cu" "In6.Cu" "In8.Cu")
		(hatch none 0.5)
		(connect_pads
			(clearance 0)
		)
		(min_thickness 0.25)
		(keepout
			(tracks not_allowed)
			(vias allowed)
			(pads allowed)
			(copperpour not_allowed)
			(footprints allowed)
		)
		(placement
			(enabled no)
			(sheetname "")
		)
		(fill yes
			(thermal_gap 0.5)
			(thermal_bridge_width 0.5)
			(island_removal_mode 0)
		)
		(polygon
			(pts
				(arc
					(start 231.181148 -98.012758)
					(mid 229.403148 -98.012758)
					(end 231.181148 -98.012758)
				)
			)
		)
	)
	(zone
		(layers "In1.Cu" "In3.Cu" "In6.Cu" "In8.Cu")
		(hatch none 0.5)
		(connect_pads
			(clearance 0)
		)
		(min_thickness 0.25)
		(keepout
			(tracks not_allowed)
			(vias allowed)
			(pads allowed)
			(copperpour not_allowed)
			(footprints allowed)
		)
		(placement
			(enabled no)
			(sheetname "")
		)
		(fill yes
			(thermal_gap 0.5)
			(thermal_bridge_width 0.5)
			(island_removal_mode 0)
		)
		(polygon
			(pts
				(arc
					(start 270.129 -125.095)
					(mid 268.351 -125.095)
					(end 270.129 -125.095)
				)
			)
		)
	)
	(zone
		(layers "In1.Cu" "In3.Cu" "In6.Cu" "In8.Cu")
		(hatch none 0.5)
		(connect_pads
			(clearance 0)
		)
		(min_thickness 0.25)
		(keepout
			(tracks not_allowed)
			(vias allowed)
			(pads allowed)
			(copperpour not_allowed)
			(footprints allowed)
		)
		(placement
			(enabled no)
			(sheetname "")
		)
		(fill yes
			(thermal_gap 0.5)
			(thermal_bridge_width 0.5)
			(island_removal_mode 0)
		)
		(polygon
			(pts
				(arc
					(start 95.661226 -136.906)
					(mid 92.816426 -136.906)
					(end 95.661226 -136.906)
				)
			)
		)
	)
	(zone
		(layers "In1.Cu" "In3.Cu" "In6.Cu" "In8.Cu")
		(hatch none 0.5)
		(connect_pads
			(clearance 0)
		)
		(min_thickness 0.25)
		(keepout
			(tracks not_allowed)
			(vias allowed)
			(pads allowed)
			(copperpour not_allowed)
			(footprints allowed)
		)
		(placement
			(enabled no)
			(sheetname "")
		)
		(fill yes
			(thermal_gap 0.5)
			(thermal_bridge_width 0.5)
			(island_removal_mode 0)
		)
		(polygon
			(pts
				(arc
					(start 207.81137 -122.809762)
					(mid 206.03337 -122.809762)
					(end 207.81137 -122.809762)
				)
			)
		)
	)
	(zone
		(layers "In1.Cu" "In3.Cu" "In6.Cu" "In8.Cu")
		(hatch none 0.5)
		(connect_pads
			(clearance 0)
		)
		(min_thickness 0.25)
		(keepout
			(tracks not_allowed)
			(vias allowed)
			(pads allowed)
			(copperpour not_allowed)
			(footprints allowed)
		)
		(placement
			(enabled no)
			(sheetname "")
		)
		(fill yes
			(thermal_gap 0.5)
			(thermal_bridge_width 0.5)
			(island_removal_mode 0)
		)
		(polygon
			(pts
				(arc
					(start 204.679042 -103.6701)
					(mid 202.901042 -103.6701)
					(end 204.679042 -103.6701)
				)
			)
		)
	)
	(zone
		(layers "In1.Cu" "In3.Cu" "In6.Cu" "In8.Cu")
		(hatch none 0.5)
		(connect_pads
			(clearance 0)
		)
		(min_thickness 0.25)
		(keepout
			(tracks not_allowed)
			(vias allowed)
			(pads allowed)
			(copperpour not_allowed)
			(footprints allowed)
		)
		(placement
			(enabled no)
			(sheetname "")
		)
		(fill yes
			(thermal_gap 0.5)
			(thermal_bridge_width 0.5)
			(island_removal_mode 0)
		)
		(polygon
			(pts
				(arc
					(start 219.153994 -123.528328)
					(mid 217.375994 -123.528328)
					(end 219.153994 -123.528328)
				)
			)
		)
	)
	(zone
		(layers "In1.Cu" "In3.Cu" "In6.Cu" "In8.Cu")
		(hatch none 0.5)
		(connect_pads
			(clearance 0)
		)
		(min_thickness 0.25)
		(keepout
			(tracks not_allowed)
			(vias allowed)
			(pads allowed)
			(copperpour not_allowed)
			(footprints allowed)
		)
		(placement
			(enabled no)
			(sheetname "")
		)
		(fill yes
			(thermal_gap 0.5)
			(thermal_bridge_width 0.5)
			(island_removal_mode 0)
		)
		(polygon
			(pts
				(arc
					(start 235.468668 -131.110736)
					(mid 233.690668 -131.110736)
					(end 235.468668 -131.110736)
				)
			)
		)
	)
	(zone
		(layers "In1.Cu" "In3.Cu" "In6.Cu" "In8.Cu")
		(hatch none 0.5)
		(connect_pads
			(clearance 0)
		)
		(min_thickness 0.25)
		(keepout
			(tracks not_allowed)
			(vias allowed)
			(pads allowed)
			(copperpour not_allowed)
			(footprints allowed)
		)
		(placement
			(enabled no)
			(sheetname "")
		)
		(fill yes
			(thermal_gap 0.5)
			(thermal_bridge_width 0.5)
			(island_removal_mode 0)
		)
		(polygon
			(pts
				(arc
					(start 204.76337 -121.331736)
					(mid 202.98537 -121.331736)
					(end 204.76337 -121.331736)
				)
			)
		)
	)
	(zone
		(layers "In1.Cu" "In3.Cu" "In6.Cu" "In8.Cu")
		(hatch none 0.5)
		(connect_pads
			(clearance 0)
		)
		(min_thickness 0.25)
		(keepout
			(tracks not_allowed)
			(vias allowed)
			(pads allowed)
			(copperpour not_allowed)
			(footprints allowed)
		)
		(placement
			(enabled no)
			(sheetname "")
		)
		(fill yes
			(thermal_gap 0.5)
			(thermal_bridge_width 0.5)
			(island_removal_mode 0)
		)
		(polygon
			(pts
				(arc
					(start 235.192316 -97.985834)
					(mid 233.414316 -97.985834)
					(end 235.192316 -97.985834)
				)
			)
		)
	)
	(zone
		(layers "In1.Cu" "In3.Cu" "In6.Cu" "In8.Cu")
		(hatch none 0.5)
		(connect_pads
			(clearance 0)
		)
		(min_thickness 0.25)
		(keepout
			(tracks not_allowed)
			(vias allowed)
			(pads allowed)
			(copperpour not_allowed)
			(footprints allowed)
		)
		(placement
			(enabled no)
			(sheetname "")
		)
		(fill yes
			(thermal_gap 0.5)
			(thermal_bridge_width 0.5)
			(island_removal_mode 0)
		)
		(polygon
			(pts
				(arc
					(start 45.25264 -51.4731)
					(mid 43.47464 -51.4731)
					(end 45.25264 -51.4731)
				)
			)
		)
	)
	(zone
		(layers "In1.Cu" "In3.Cu" "In6.Cu" "In8.Cu")
		(hatch none 0.5)
		(connect_pads
			(clearance 0)
		)
		(min_thickness 0.25)
		(keepout
			(tracks not_allowed)
			(vias allowed)
			(pads allowed)
			(copperpour not_allowed)
			(footprints allowed)
		)
		(placement
			(enabled no)
			(sheetname "")
		)
		(fill yes
			(thermal_gap 0.5)
			(thermal_bridge_width 0.5)
			(island_removal_mode 0)
		)
		(polygon
			(pts
				(arc
					(start 51.72964 -52.8828)
					(mid 49.95164 -52.8828)
					(end 51.72964 -52.8828)
				)
			)
		)
	)
	(zone
		(layers "In1.Cu" "In3.Cu" "In6.Cu" "In8.Cu")
		(hatch none 0.5)
		(connect_pads
			(clearance 0)
		)
		(min_thickness 0.25)
		(keepout
			(tracks not_allowed)
			(vias allowed)
			(pads allowed)
			(copperpour not_allowed)
			(footprints allowed)
		)
		(placement
			(enabled no)
			(sheetname "")
		)
		(fill yes
			(thermal_gap 0.5)
			(thermal_bridge_width 0.5)
			(island_removal_mode 0)
		)
		(polygon
			(pts
				(arc
					(start 206.965042 -103.6701)
					(mid 205.187042 -103.6701)
					(end 206.965042 -103.6701)
				)
			)
		)
	)
	(zone
		(layers "In1.Cu" "In3.Cu" "In6.Cu" "In8.Cu")
		(hatch none 0.5)
		(connect_pads
			(clearance 0)
		)
		(min_thickness 0.25)
		(keepout
			(tracks not_allowed)
			(vias allowed)
			(pads allowed)
			(copperpour not_allowed)
			(footprints allowed)
		)
		(placement
			(enabled no)
			(sheetname "")
		)
		(fill yes
			(thermal_gap 0.5)
			(thermal_bridge_width 0.5)
			(island_removal_mode 0)
		)
		(polygon
			(pts
				(arc
					(start 203.917042 -105.896664)
					(mid 202.139042 -105.896664)
					(end 203.917042 -105.896664)
				)
			)
		)
	)
	(zone
		(layers "In1.Cu" "In3.Cu" "In6.Cu" "In8.Cu")
		(hatch none 0.5)
		(connect_pads
			(clearance 0)
		)
		(min_thickness 0.25)
		(keepout
			(tracks not_allowed)
			(vias allowed)
			(pads allowed)
			(copperpour not_allowed)
			(footprints allowed)
		)
		(placement
			(enabled no)
			(sheetname "")
		)
		(fill yes
			(thermal_gap 0.5)
			(thermal_bridge_width 0.5)
			(island_removal_mode 0)
		)
		(polygon
			(pts
				(arc
					(start 272.415 -125.095)
					(mid 270.637 -125.095)
					(end 272.415 -125.095)
				)
			)
		)
	)
	(zone
		(layers "In1.Cu" "In3.Cu" "In6.Cu" "In8.Cu")
		(hatch none 0.5)
		(connect_pads
			(clearance 0)
		)
		(min_thickness 0.25)
		(keepout
			(tracks not_allowed)
			(vias allowed)
			(pads allowed)
			(copperpour not_allowed)
			(footprints allowed)
		)
		(placement
			(enabled no)
			(sheetname "")
		)
		(fill yes
			(thermal_gap 0.5)
			(thermal_bridge_width 0.5)
			(island_removal_mode 0)
		)
		(polygon
			(pts
				(arc
					(start 270.129 -99.441)
					(mid 268.351 -99.441)
					(end 270.129 -99.441)
				)
			)
		)
	)
	(zone
		(layers "In1.Cu" "In3.Cu" "In6.Cu" "In8.Cu")
		(hatch none 0.5)
		(connect_pads
			(clearance 0)
		)
		(min_thickness 0.25)
		(keepout
			(tracks not_allowed)
			(vias allowed)
			(pads allowed)
			(copperpour not_allowed)
			(footprints allowed)
		)
		(placement
			(enabled no)
			(sheetname "")
		)
		(fill yes
			(thermal_gap 0.5)
			(thermal_bridge_width 0.5)
			(island_removal_mode 0)
		)
		(polygon
			(pts
				(arc
					(start 218.399868 -105.896664)
					(mid 216.621868 -105.896664)
					(end 218.399868 -105.896664)
				)
			)
		)
	)
	(zone
		(layers "In1.Cu" "In3.Cu" "In6.Cu" "In8.Cu")
		(hatch none 0.5)
		(connect_pads
			(clearance 0)
		)
		(min_thickness 0.25)
		(keepout
			(tracks not_allowed)
			(vias allowed)
			(pads allowed)
			(copperpour not_allowed)
			(footprints allowed)
		)
		(placement
			(enabled no)
			(sheetname "")
		)
		(fill yes
			(thermal_gap 0.5)
			(thermal_bridge_width 0.5)
			(island_removal_mode 0)
		)
		(polygon
			(pts
				(arc
					(start 31.242 -105.283)
					(mid 29.464 -105.283)
					(end 31.242 -105.283)
				)
			)
		)
	)
	(zone
		(layers "In1.Cu" "In3.Cu" "In6.Cu" "In8.Cu")
		(hatch none 0.5)
		(connect_pads
			(clearance 0)
		)
		(min_thickness 0.25)
		(keepout
			(tracks not_allowed)
			(vias allowed)
			(pads allowed)
			(copperpour not_allowed)
			(footprints allowed)
		)
		(placement
			(enabled no)
			(sheetname "")
		)
		(fill yes
			(thermal_gap 0.5)
			(thermal_bridge_width 0.5)
			(island_removal_mode 0)
		)
		(polygon
			(pts
				(arc
					(start 217.708226 -102.894638)
					(mid 215.930226 -102.894638)
					(end 217.708226 -102.894638)
				)
			)
		)
	)
	(zone
		(layers "In1.Cu" "In3.Cu" "In6.Cu" "In8.Cu")
		(hatch none 0.5)
		(connect_pads
			(clearance 0)
		)
		(min_thickness 0.25)
		(keepout
			(tracks not_allowed)
			(vias allowed)
			(pads allowed)
			(copperpour not_allowed)
			(footprints allowed)
		)
		(placement
			(enabled no)
			(sheetname "")
		)
		(fill yes
			(thermal_gap 0.5)
			(thermal_bridge_width 0.5)
			(island_removal_mode 0)
		)
		(polygon
			(pts
				(arc
					(start 270.129 -89.662)
					(mid 268.351 -89.662)
					(end 270.129 -89.662)
				)
			)
		)
	)
	(zone
		(layers "In1.Cu" "In3.Cu" "In6.Cu" "In8.Cu")
		(hatch none 0.5)
		(connect_pads
			(clearance 0)
		)
		(min_thickness 0.25)
		(keepout
			(tracks not_allowed)
			(vias allowed)
			(pads allowed)
			(copperpour not_allowed)
			(footprints allowed)
		)
		(placement
			(enabled no)
			(sheetname "")
		)
		(fill yes
			(thermal_gap 0.5)
			(thermal_bridge_width 0.5)
			(island_removal_mode 0)
		)
		(polygon
			(pts
				(arc
					(start 271.653 -109.982)
					(mid 269.875 -109.982)
					(end 271.653 -109.982)
				)
			)
		)
	)
	(zone
		(layers "In1.Cu" "In3.Cu" "In6.Cu" "In8.Cu")
		(hatch none 0.5)
		(connect_pads
			(clearance 0)
		)
		(min_thickness 0.25)
		(keepout
			(tracks not_allowed)
			(vias allowed)
			(pads allowed)
			(copperpour not_allowed)
			(footprints allowed)
		)
		(placement
			(enabled no)
			(sheetname "")
		)
		(fill yes
			(thermal_gap 0.5)
			(thermal_bridge_width 0.5)
			(island_removal_mode 0)
		)
		(polygon
			(pts
				(arc
					(start 270.891 -110.744)
					(mid 269.113 -110.744)
					(end 270.891 -110.744)
				)
			)
		)
	)
	(zone
		(layers "In1.Cu" "In3.Cu" "In6.Cu" "In8.Cu")
		(hatch none 0.5)
		(connect_pads
			(clearance 0)
		)
		(min_thickness 0.25)
		(keepout
			(tracks not_allowed)
			(vias allowed)
			(pads allowed)
			(copperpour not_allowed)
			(footprints allowed)
		)
		(placement
			(enabled no)
			(sheetname "")
		)
		(fill yes
			(thermal_gap 0.5)
			(thermal_bridge_width 0.5)
			(island_removal_mode 0)
		)
		(polygon
			(pts
				(arc
					(start 40.767 -106.807)
					(mid 38.989 -106.807)
					(end 40.767 -106.807)
				)
			)
		)
	)
	(zone
		(layers "In1.Cu" "In3.Cu" "In6.Cu" "In8.Cu")
		(hatch none 0.5)
		(connect_pads
			(clearance 0)
		)
		(min_thickness 0.25)
		(keepout
			(tracks not_allowed)
			(vias allowed)
			(pads allowed)
			(copperpour not_allowed)
			(footprints allowed)
		)
		(placement
			(enabled no)
			(sheetname "")
		)
		(fill yes
			(thermal_gap 0.5)
			(thermal_bridge_width 0.5)
			(island_removal_mode 0)
		)
		(polygon
			(pts
				(arc
					(start 71.302626 -71.901812)
					(mid 69.524626 -71.901812)
					(end 71.302626 -71.901812)
				)
			)
		)
	)
	(zone
		(layers "In1.Cu" "In3.Cu" "In6.Cu" "In8.Cu")
		(hatch none 0.5)
		(connect_pads
			(clearance 0)
		)
		(min_thickness 0.25)
		(keepout
			(tracks not_allowed)
			(vias allowed)
			(pads allowed)
			(copperpour not_allowed)
			(footprints allowed)
		)
		(placement
			(enabled no)
			(sheetname "")
		)
		(fill yes
			(thermal_gap 0.5)
			(thermal_bridge_width 0.5)
			(island_removal_mode 0)
		)
		(polygon
			(pts
				(arc
					(start 270.129 -111.506)
					(mid 268.351 -111.506)
					(end 270.129 -111.506)
				)
			)
		)
	)
	(zone
		(layers "In1.Cu" "In3.Cu" "In6.Cu" "In8.Cu")
		(hatch none 0.5)
		(connect_pads
			(clearance 0)
		)
		(min_thickness 0.25)
		(keepout
			(tracks not_allowed)
			(vias allowed)
			(pads allowed)
			(copperpour not_allowed)
			(footprints allowed)
		)
		(placement
			(enabled no)
			(sheetname "")
		)
		(fill yes
			(thermal_gap 0.5)
			(thermal_bridge_width 0.5)
			(island_removal_mode 0)
		)
		(polygon
			(pts
				(arc
					(start 41.656 -106.807)
					(mid 39.878 -106.807)
					(end 41.656 -106.807)
				)
			)
		)
	)
	(zone
		(layers "In1.Cu" "In3.Cu" "In6.Cu" "In8.Cu")
		(hatch none 0.5)
		(connect_pads
			(clearance 0)
		)
		(min_thickness 0.25)
		(keepout
			(tracks not_allowed)
			(vias allowed)
			(pads allowed)
			(copperpour not_allowed)
			(footprints allowed)
		)
		(placement
			(enabled no)
			(sheetname "")
		)
		(fill yes
			(thermal_gap 0.5)
			(thermal_bridge_width 0.5)
			(island_removal_mode 0)
		)
		(polygon
			(pts
				(arc
					(start 270.891 -100.203)
					(mid 269.113 -100.203)
					(end 270.891 -100.203)
				)
			)
		)
	)
	(zone
		(layers "In1.Cu" "In3.Cu" "In6.Cu" "In8.Cu")
		(hatch none 0.5)
		(connect_pads
			(clearance 0)
		)
		(min_thickness 0.25)
		(keepout
			(tracks not_allowed)
			(vias allowed)
			(pads allowed)
			(copperpour not_allowed)
			(footprints allowed)
		)
		(placement
			(enabled no)
			(sheetname "")
		)
		(fill yes
			(thermal_gap 0.5)
			(thermal_bridge_width 0.5)
			(island_removal_mode 0)
		)
		(polygon
			(pts
				(arc
					(start 41.656 -104.521)
					(mid 39.878 -104.521)
					(end 41.656 -104.521)
				)
			)
		)
	)
	(zone
		(layers "In1.Cu" "In3.Cu" "In6.Cu" "In8.Cu")
		(hatch none 0.5)
		(connect_pads
			(clearance 0)
		)
		(min_thickness 0.25)
		(keepout
			(tracks not_allowed)
			(vias allowed)
			(pads allowed)
			(copperpour not_allowed)
			(footprints allowed)
		)
		(placement
			(enabled no)
			(sheetname "")
		)
		(fill yes
			(thermal_gap 0.5)
			(thermal_bridge_width 0.5)
			(island_removal_mode 0)
		)
		(polygon
			(pts
				(arc
					(start 219.902278 -122.047762)
					(mid 218.124278 -122.047762)
					(end 219.902278 -122.047762)
				)
			)
		)
	)
	(zone
		(layers "In1.Cu" "In3.Cu" "In6.Cu" "In8.Cu")
		(hatch none 0.5)
		(connect_pads
			(clearance 0)
		)
		(min_thickness 0.25)
		(keepout
			(tracks not_allowed)
			(vias allowed)
			(pads allowed)
			(copperpour not_allowed)
			(footprints allowed)
		)
		(placement
			(enabled no)
			(sheetname "")
		)
		(fill yes
			(thermal_gap 0.5)
			(thermal_bridge_width 0.5)
			(island_removal_mode 0)
		)
		(polygon
			(pts
				(arc
					(start 203.2254 -105.883202)
					(mid 201.4474 -105.883202)
					(end 203.2254 -105.883202)
				)
			)
		)
	)
	(zone
		(layers "In1.Cu" "In3.Cu" "In6.Cu" "In8.Cu")
		(hatch none 0.5)
		(connect_pads
			(clearance 0)
		)
		(min_thickness 0.25)
		(keepout
			(tracks not_allowed)
			(vias allowed)
			(pads allowed)
			(copperpour not_allowed)
			(footprints allowed)
		)
		(placement
			(enabled no)
			(sheetname "")
		)
		(fill yes
			(thermal_gap 0.5)
			(thermal_bridge_width 0.5)
			(island_removal_mode 0)
		)
		(polygon
			(pts
				(arc
					(start 207.727042 -105.134664)
					(mid 205.949042 -105.134664)
					(end 207.727042 -105.134664)
				)
			)
		)
	)
	(zone
		(layers "In1.Cu" "In3.Cu" "In6.Cu" "In8.Cu")
		(hatch none 0.5)
		(connect_pads
			(clearance 0)
		)
		(min_thickness 0.25)
		(keepout
			(tracks not_allowed)
			(vias allowed)
			(pads allowed)
			(copperpour not_allowed)
			(footprints allowed)
		)
		(placement
			(enabled no)
			(sheetname "")
		)
		(fill yes
			(thermal_gap 0.5)
			(thermal_bridge_width 0.5)
			(island_removal_mode 0)
		)
		(polygon
			(pts
				(arc
					(start 273.177 -100.965)
					(mid 271.399 -100.965)
					(end 273.177 -100.965)
				)
			)
		)
	)
	(zone
		(layers "In1.Cu" "In3.Cu" "In6.Cu" "In8.Cu")
		(hatch none 0.5)
		(connect_pads
			(clearance 0)
		)
		(min_thickness 0.25)
		(keepout
			(tracks not_allowed)
			(vias allowed)
			(pads allowed)
			(copperpour not_allowed)
			(footprints allowed)
		)
		(placement
			(enabled no)
			(sheetname "")
		)
		(fill yes
			(thermal_gap 0.5)
			(thermal_bridge_width 0.5)
			(island_removal_mode 0)
		)
		(polygon
			(pts
				(arc
					(start 68.183506 -126.492)
					(mid 66.405506 -126.492)
					(end 68.183506 -126.492)
				)
			)
		)
	)
	(zone
		(layers "In1.Cu" "In3.Cu" "In6.Cu" "In8.Cu")
		(hatch none 0.5)
		(connect_pads
			(clearance 0)
		)
		(min_thickness 0.25)
		(keepout
			(tracks not_allowed)
			(vias allowed)
			(pads allowed)
			(copperpour not_allowed)
			(footprints allowed)
		)
		(placement
			(enabled no)
			(sheetname "")
		)
		(fill yes
			(thermal_gap 0.5)
			(thermal_bridge_width 0.5)
			(island_removal_mode 0)
		)
		(polygon
			(pts
				(arc
					(start 270.891 -97.917)
					(mid 269.113 -97.917)
					(end 270.891 -97.917)
				)
			)
		)
	)
	(zone
		(layers "In1.Cu" "In3.Cu" "In6.Cu" "In8.Cu")
		(hatch none 0.5)
		(connect_pads
			(clearance 0)
		)
		(min_thickness 0.25)
		(keepout
			(tracks not_allowed)
			(vias allowed)
			(pads allowed)
			(copperpour not_allowed)
			(footprints allowed)
		)
		(placement
			(enabled no)
			(sheetname "")
		)
		(fill yes
			(thermal_gap 0.5)
			(thermal_bridge_width 0.5)
			(island_removal_mode 0)
		)
		(polygon
			(pts
				(arc
					(start 11.22172 -76.019914)
					(mid 8.47852 -76.019914)
					(end 11.22172 -76.019914)
				)
			)
		)
	)
	(zone
		(layers "In1.Cu" "In3.Cu" "In6.Cu" "In8.Cu")
		(hatch none 0.5)
		(connect_pads
			(clearance 0)
		)
		(min_thickness 0.25)
		(keepout
			(tracks not_allowed)
			(vias allowed)
			(pads allowed)
			(copperpour not_allowed)
			(footprints allowed)
		)
		(placement
			(enabled no)
			(sheetname "")
		)
		(fill yes
			(thermal_gap 0.5)
			(thermal_bridge_width 0.5)
			(island_removal_mode 0)
		)
		(polygon
			(pts
				(arc
					(start 219.923868 -102.9081)
					(mid 218.145868 -102.9081)
					(end 219.923868 -102.9081)
				)
			)
		)
	)
	(zone
		(layers "In1.Cu" "In3.Cu" "In6.Cu" "In8.Cu")
		(hatch none 0.5)
		(connect_pads
			(clearance 0)
		)
		(min_thickness 0.25)
		(keepout
			(tracks not_allowed)
			(vias allowed)
			(pads allowed)
			(copperpour not_allowed)
			(footprints allowed)
		)
		(placement
			(enabled no)
			(sheetname "")
		)
		(fill yes
			(thermal_gap 0.5)
			(thermal_bridge_width 0.5)
			(island_removal_mode 0)
		)
		(polygon
			(pts
				(arc
					(start 203.2254 -104.418638)
					(mid 201.4474 -104.418638)
					(end 203.2254 -104.418638)
				)
			)
		)
	)
	(zone
		(layers "In1.Cu" "In3.Cu" "In6.Cu" "In8.Cu")
		(hatch none 0.5)
		(connect_pads
			(clearance 0)
		)
		(min_thickness 0.25)
		(keepout
			(tracks not_allowed)
			(vias allowed)
			(pads allowed)
			(copperpour not_allowed)
			(footprints allowed)
		)
		(placement
			(enabled no)
			(sheetname "")
		)
		(fill yes
			(thermal_gap 0.5)
			(thermal_bridge_width 0.5)
			(island_removal_mode 0)
		)
		(polygon
			(pts
				(arc
					(start 270.891 -87.376)
					(mid 269.113 -87.376)
					(end 270.891 -87.376)
				)
			)
		)
	)
	(zone
		(layers "In1.Cu" "In3.Cu" "In6.Cu" "In8.Cu")
		(hatch none 0.5)
		(connect_pads
			(clearance 0)
		)
		(min_thickness 0.25)
		(keepout
			(tracks not_allowed)
			(vias allowed)
			(pads allowed)
			(copperpour not_allowed)
			(footprints allowed)
		)
		(placement
			(enabled no)
			(sheetname "")
		)
		(fill yes
			(thermal_gap 0.5)
			(thermal_bridge_width 0.5)
			(island_removal_mode 0)
		)
		(polygon
			(pts
				(arc
					(start 156.337 -50.292)
					(mid 154.559 -50.292)
					(end 156.337 -50.292)
				)
			)
		)
	)
	(zone
		(layers "In1.Cu" "In3.Cu" "In6.Cu" "In8.Cu")
		(hatch none 0.5)
		(connect_pads
			(clearance 0)
		)
		(min_thickness 0.25)
		(keepout
			(tracks not_allowed)
			(vias allowed)
			(pads allowed)
			(copperpour not_allowed)
			(footprints allowed)
		)
		(placement
			(enabled no)
			(sheetname "")
		)
		(fill yes
			(thermal_gap 0.5)
			(thermal_bridge_width 0.5)
			(island_removal_mode 0)
		)
		(polygon
			(pts
				(arc
					(start 206.203042 -105.896664)
					(mid 204.425042 -105.896664)
					(end 206.203042 -105.896664)
				)
			)
		)
	)
	(zone
		(layers "In1.Cu" "In3.Cu" "In6.Cu" "In8.Cu")
		(hatch none 0.5)
		(connect_pads
			(clearance 0)
		)
		(min_thickness 0.25)
		(keepout
			(tracks not_allowed)
			(vias allowed)
			(pads allowed)
			(copperpour not_allowed)
			(footprints allowed)
		)
		(placement
			(enabled no)
			(sheetname "")
		)
		(fill yes
			(thermal_gap 0.5)
			(thermal_bridge_width 0.5)
			(island_removal_mode 0)
		)
		(polygon
			(pts
				(arc
					(start 68.945506 -126.492)
					(mid 67.167506 -126.492)
					(end 68.945506 -126.492)
				)
			)
		)
	)
	(zone
		(layers "In1.Cu" "In3.Cu" "In6.Cu" "In8.Cu")
		(hatch none 0.5)
		(connect_pads
			(clearance 0)
		)
		(min_thickness 0.25)
		(keepout
			(tracks not_allowed)
			(vias allowed)
			(pads allowed)
			(copperpour not_allowed)
			(footprints allowed)
		)
		(placement
			(enabled no)
			(sheetname "")
		)
		(fill yes
			(thermal_gap 0.5)
			(thermal_bridge_width 0.5)
			(island_removal_mode 0)
		)
		(polygon
			(pts
				(arc
					(start 94.615 -52.324)
					(mid 92.837 -52.324)
					(end 94.615 -52.324)
				)
			)
		)
	)
	(zone
		(layers "In1.Cu" "In3.Cu" "In6.Cu" "In8.Cu")
		(hatch none 0.5)
		(connect_pads
			(clearance 0)
		)
		(min_thickness 0.25)
		(keepout
			(tracks not_allowed)
			(vias allowed)
			(pads allowed)
			(copperpour not_allowed)
			(footprints allowed)
		)
		(placement
			(enabled no)
			(sheetname "")
		)
		(fill yes
			(thermal_gap 0.5)
			(thermal_bridge_width 0.5)
			(island_removal_mode 0)
		)
		(polygon
			(pts
				(arc
					(start 270.129 -123.571)
					(mid 268.351 -123.571)
					(end 270.129 -123.571)
				)
			)
		)
	)
	(zone
		(layers "In1.Cu" "In3.Cu" "In6.Cu" "In8.Cu")
		(hatch none 0.5)
		(connect_pads
			(clearance 0)
		)
		(min_thickness 0.25)
		(keepout
			(tracks not_allowed)
			(vias allowed)
			(pads allowed)
			(copperpour not_allowed)
			(footprints allowed)
		)
		(placement
			(enabled no)
			(sheetname "")
		)
		(fill yes
			(thermal_gap 0.5)
			(thermal_bridge_width 0.5)
			(island_removal_mode 0)
		)
		(polygon
			(pts
				(arc
					(start 222.209868 -102.9081)
					(mid 220.431868 -102.9081)
					(end 222.209868 -102.9081)
				)
			)
		)
	)
	(zone
		(layers "In1.Cu" "In3.Cu" "In6.Cu" "In8.Cu")
		(hatch none 0.5)
		(connect_pads
			(clearance 0)
		)
		(min_thickness 0.25)
		(keepout
			(tracks not_allowed)
			(vias allowed)
			(pads allowed)
			(copperpour not_allowed)
			(footprints allowed)
		)
		(placement
			(enabled no)
			(sheetname "")
		)
		(fill yes
			(thermal_gap 0.5)
			(thermal_bridge_width 0.5)
			(island_removal_mode 0)
		)
		(polygon
			(pts
				(arc
					(start 233.944668 -131.110736)
					(mid 232.166668 -131.110736)
					(end 233.944668 -131.110736)
				)
			)
		)
	)
	(zone
		(layers "In1.Cu" "In3.Cu" "In6.Cu" "In8.Cu")
		(hatch none 0.5)
		(connect_pads
			(clearance 0)
		)
		(min_thickness 0.25)
		(keepout
			(tracks not_allowed)
			(vias allowed)
			(pads allowed)
			(copperpour not_allowed)
			(footprints allowed)
		)
		(placement
			(enabled no)
			(sheetname "")
		)
		(fill yes
			(thermal_gap 0.5)
			(thermal_bridge_width 0.5)
			(island_removal_mode 0)
		)
		(polygon
			(pts
				(arc
					(start 272.415 -125.857)
					(mid 270.637 -125.857)
					(end 272.415 -125.857)
				)
			)
		)
	)
	(zone
		(layers "In1.Cu" "In3.Cu" "In6.Cu" "In8.Cu")
		(hatch none 0.5)
		(connect_pads
			(clearance 0)
		)
		(min_thickness 0.25)
		(keepout
			(tracks not_allowed)
			(vias allowed)
			(pads allowed)
			(copperpour not_allowed)
			(footprints allowed)
		)
		(placement
			(enabled no)
			(sheetname "")
		)
		(fill yes
			(thermal_gap 0.5)
			(thermal_bridge_width 0.5)
			(island_removal_mode 0)
		)
		(polygon
			(pts
				(arc
					(start 271.653 -113.792)
					(mid 269.875 -113.792)
					(end 271.653 -113.792)
				)
			)
		)
	)
	(zone
		(layers "In1.Cu" "In3.Cu" "In6.Cu" "In8.Cu")
		(hatch none 0.5)
		(connect_pads
			(clearance 0)
		)
		(min_thickness 0.25)
		(keepout
			(tracks not_allowed)
			(vias allowed)
			(pads allowed)
			(copperpour not_allowed)
			(footprints allowed)
		)
		(placement
			(enabled no)
			(sheetname "")
		)
		(fill yes
			(thermal_gap 0.5)
			(thermal_bridge_width 0.5)
			(island_removal_mode 0)
		)
		(polygon
			(pts
				(arc
					(start 150.876 -50.292)
					(mid 149.098 -50.292)
					(end 150.876 -50.292)
				)
			)
		)
	)
	(zone
		(layers "In1.Cu" "In3.Cu" "In6.Cu" "In8.Cu")
		(hatch none 0.5)
		(connect_pads
			(clearance 0)
		)
		(min_thickness 0.25)
		(keepout
			(tracks not_allowed)
			(vias allowed)
			(pads allowed)
			(copperpour not_allowed)
			(footprints allowed)
		)
		(placement
			(enabled no)
			(sheetname "")
		)
		(fill yes
			(thermal_gap 0.5)
			(thermal_bridge_width 0.5)
			(island_removal_mode 0)
		)
		(polygon
			(pts
				(arc
					(start 271.653 -98.679)
					(mid 269.875 -98.679)
					(end 271.653 -98.679)
				)
			)
		)
	)
	(zone
		(layers "In1.Cu" "In3.Cu" "In6.Cu" "In8.Cu")
		(hatch none 0.5)
		(connect_pads
			(clearance 0)
		)
		(min_thickness 0.25)
		(keepout
			(tracks not_allowed)
			(vias allowed)
			(pads allowed)
			(copperpour not_allowed)
			(footprints allowed)
		)
		(placement
			(enabled no)
			(sheetname "")
		)
		(fill yes
			(thermal_gap 0.5)
			(thermal_bridge_width 0.5)
			(island_removal_mode 0)
		)
		(polygon
			(pts
				(arc
					(start 217.063828 -132.18414)
					(mid 215.285828 -132.18414)
					(end 217.063828 -132.18414)
				)
			)
		)
	)
	(zone
		(layers "In1.Cu" "In3.Cu" "In6.Cu" "In8.Cu")
		(hatch none 0.5)
		(connect_pads
			(clearance 0)
		)
		(min_thickness 0.25)
		(keepout
			(tracks not_allowed)
			(vias allowed)
			(pads allowed)
			(copperpour not_allowed)
			(footprints allowed)
		)
		(placement
			(enabled no)
			(sheetname "")
		)
		(fill yes
			(thermal_gap 0.5)
			(thermal_bridge_width 0.5)
			(island_removal_mode 0)
		)
		(polygon
			(pts
				(arc
					(start 50.20564 -52.1208)
					(mid 48.42764 -52.1208)
					(end 50.20564 -52.1208)
				)
			)
		)
	)
	(zone
		(layers "In1.Cu" "In3.Cu" "In6.Cu" "In8.Cu")
		(hatch none 0.5)
		(connect_pads
			(clearance 0)
		)
		(min_thickness 0.25)
		(keepout
			(tracks not_allowed)
			(vias allowed)
			(pads allowed)
			(copperpour not_allowed)
			(footprints allowed)
		)
		(placement
			(enabled no)
			(sheetname "")
		)
		(fill yes
			(thermal_gap 0.5)
			(thermal_bridge_width 0.5)
			(island_removal_mode 0)
		)
		(polygon
			(pts
				(arc
					(start 272.415 -113.792)
					(mid 270.637 -113.792)
					(end 272.415 -113.792)
				)
			)
		)
	)
	(zone
		(layers "In1.Cu" "In3.Cu" "In6.Cu" "In8.Cu")
		(hatch none 0.5)
		(connect_pads
			(clearance 0)
		)
		(min_thickness 0.25)
		(keepout
			(tracks not_allowed)
			(vias allowed)
			(pads allowed)
			(copperpour not_allowed)
			(footprints allowed)
		)
		(placement
			(enabled no)
			(sheetname "")
		)
		(fill yes
			(thermal_gap 0.5)
			(thermal_bridge_width 0.5)
			(island_removal_mode 0)
		)
		(polygon
			(pts
				(arc
					(start 42.8879 -58.604912)
					(mid 41.1099 -58.604912)
					(end 42.8879 -58.604912)
				)
			)
		)
	)
	(zone
		(layers "In1.Cu" "In3.Cu" "In6.Cu" "In8.Cu")
		(hatch none 0.5)
		(connect_pads
			(clearance 0)
		)
		(min_thickness 0.25)
		(keepout
			(tracks not_allowed)
			(vias allowed)
			(pads allowed)
			(copperpour not_allowed)
			(footprints allowed)
		)
		(placement
			(enabled no)
			(sheetname "")
		)
		(fill yes
			(thermal_gap 0.5)
			(thermal_bridge_width 0.5)
			(island_removal_mode 0)
		)
		(polygon
			(pts
				(arc
					(start 217.825828 -132.18414)
					(mid 216.047828 -132.18414)
					(end 217.825828 -132.18414)
				)
			)
		)
	)
	(zone
		(layers "In1.Cu" "In3.Cu" "In6.Cu" "In8.Cu")
		(hatch none 0.5)
		(connect_pads
			(clearance 0)
		)
		(min_thickness 0.25)
		(keepout
			(tracks not_allowed)
			(vias allowed)
			(pads allowed)
			(copperpour not_allowed)
			(footprints allowed)
		)
		(placement
			(enabled no)
			(sheetname "")
		)
		(fill yes
			(thermal_gap 0.5)
			(thermal_bridge_width 0.5)
			(island_removal_mode 0)
		)
		(polygon
			(pts
				(arc
					(start 270.129 -122.809)
					(mid 268.351 -122.809)
					(end 270.129 -122.809)
				)
			)
		)
	)
	(zone
		(layers "In1.Cu" "In3.Cu" "In6.Cu" "In8.Cu")
		(hatch none 0.5)
		(connect_pads
			(clearance 0)
		)
		(min_thickness 0.25)
		(keepout
			(tracks not_allowed)
			(vias allowed)
			(pads allowed)
			(copperpour not_allowed)
			(footprints allowed)
		)
		(placement
			(enabled no)
			(sheetname "")
		)
		(fill yes
			(thermal_gap 0.5)
			(thermal_bridge_width 0.5)
			(island_removal_mode 0)
		)
		(polygon
			(pts
				(arc
					(start 271.653 -123.571)
					(mid 269.875 -123.571)
					(end 271.653 -123.571)
				)
			)
		)
	)
	(zone
		(layers "In1.Cu" "In3.Cu" "In6.Cu" "In8.Cu")
		(hatch none 0.5)
		(connect_pads
			(clearance 0)
		)
		(min_thickness 0.25)
		(keepout
			(tracks not_allowed)
			(vias allowed)
			(pads allowed)
			(copperpour not_allowed)
			(footprints allowed)
		)
		(placement
			(enabled no)
			(sheetname "")
		)
		(fill yes
			(thermal_gap 0.5)
			(thermal_bridge_width 0.5)
			(island_removal_mode 0)
		)
		(polygon
			(pts
				(arc
					(start 207.04937 -121.331736)
					(mid 205.27137 -121.331736)
					(end 207.04937 -121.331736)
				)
			)
		)
	)
	(zone
		(layers "In1.Cu" "In3.Cu" "In6.Cu" "In8.Cu")
		(hatch none 0.5)
		(connect_pads
			(clearance 0)
		)
		(min_thickness 0.25)
		(keepout
			(tracks not_allowed)
			(vias allowed)
			(pads allowed)
			(copperpour not_allowed)
			(footprints allowed)
		)
		(placement
			(enabled no)
			(sheetname "")
		)
		(fill yes
			(thermal_gap 0.5)
			(thermal_bridge_width 0.5)
			(island_removal_mode 0)
		)
		(polygon
			(pts
				(arc
					(start 222.963994 -123.528328)
					(mid 221.185994 -123.528328)
					(end 222.963994 -123.528328)
				)
			)
		)
	)
	(zone
		(layers "In1.Cu" "In3.Cu" "In6.Cu" "In8.Cu")
		(hatch none 0.5)
		(connect_pads
			(clearance 0)
		)
		(min_thickness 0.25)
		(keepout
			(tracks not_allowed)
			(vias allowed)
			(pads allowed)
			(copperpour not_allowed)
			(footprints allowed)
		)
		(placement
			(enabled no)
			(sheetname "")
		)
		(fill yes
			(thermal_gap 0.5)
			(thermal_bridge_width 0.5)
			(island_removal_mode 0)
		)
		(polygon
			(pts
				(arc
					(start 167.259 -50.292)
					(mid 165.481 -50.292)
					(end 167.259 -50.292)
				)
			)
		)
	)
	(zone
		(layers "In1.Cu" "In3.Cu" "In6.Cu" "In8.Cu")
		(hatch none 0.5)
		(connect_pads
			(clearance 0)
		)
		(min_thickness 0.25)
		(keepout
			(tracks not_allowed)
			(vias allowed)
			(pads allowed)
			(copperpour not_allowed)
			(footprints allowed)
		)
		(placement
			(enabled no)
			(sheetname "")
		)
		(fill yes
			(thermal_gap 0.5)
			(thermal_bridge_width 0.5)
			(island_removal_mode 0)
		)
		(polygon
			(pts
				(arc
					(start 273.765264 -103.35895)
					(mid 271.987264 -103.35895)
					(end 273.765264 -103.35895)
				)
			)
		)
	)
	(zone
		(layers "In1.Cu" "In3.Cu" "In6.Cu" "In8.Cu")
		(hatch none 0.5)
		(connect_pads
			(clearance 0)
		)
		(min_thickness 0.25)
		(keepout
			(tracks not_allowed)
			(vias allowed)
			(pads allowed)
			(copperpour not_allowed)
			(footprints allowed)
		)
		(placement
			(enabled no)
			(sheetname "")
		)
		(fill yes
			(thermal_gap 0.5)
			(thermal_bridge_width 0.5)
			(island_removal_mode 0)
		)
		(polygon
			(pts
				(arc
					(start 270.891 -73.787)
					(mid 269.113 -73.787)
					(end 270.891 -73.787)
				)
			)
		)
	)
	(zone
		(layers "In1.Cu" "In3.Cu" "In6.Cu" "In8.Cu")
		(hatch none 0.5)
		(connect_pads
			(clearance 0)
		)
		(min_thickness 0.25)
		(keepout
			(tracks not_allowed)
			(vias allowed)
			(pads allowed)
			(copperpour not_allowed)
			(footprints allowed)
		)
		(placement
			(enabled no)
			(sheetname "")
		)
		(fill yes
			(thermal_gap 0.5)
			(thermal_bridge_width 0.5)
			(island_removal_mode 0)
		)
		(polygon
			(pts
				(arc
					(start 284.302454 -32.1564)
					(mid 282.524454 -32.1564)
					(end 284.302454 -32.1564)
				)
			)
		)
	)
	(zone
		(layers "In1.Cu" "In3.Cu" "In6.Cu" "In8.Cu")
		(hatch none 0.5)
		(connect_pads
			(clearance 0)
		)
		(min_thickness 0.25)
		(keepout
			(tracks not_allowed)
			(vias allowed)
			(pads allowed)
			(copperpour not_allowed)
			(footprints allowed)
		)
		(placement
			(enabled no)
			(sheetname "")
		)
		(fill yes
			(thermal_gap 0.5)
			(thermal_bridge_width 0.5)
			(island_removal_mode 0)
		)
		(polygon
			(pts
				(arc
					(start 215.585802 -132.94614)
					(mid 213.807802 -132.94614)
					(end 215.585802 -132.94614)
				)
			)
		)
	)
	(zone
		(layers "In1.Cu" "In3.Cu" "In6.Cu" "In8.Cu")
		(hatch none 0.5)
		(connect_pads
			(clearance 0)
		)
		(min_thickness 0.25)
		(keepout
			(tracks not_allowed)
			(vias allowed)
			(pads allowed)
			(copperpour not_allowed)
			(footprints allowed)
		)
		(placement
			(enabled no)
			(sheetname "")
		)
		(fill yes
			(thermal_gap 0.5)
			(thermal_bridge_width 0.5)
			(island_removal_mode 0)
		)
		(polygon
			(pts
				(arc
					(start 219.902278 -122.809762)
					(mid 218.124278 -122.809762)
					(end 219.902278 -122.809762)
				)
			)
		)
	)
	(zone
		(layers "In1.Cu" "In3.Cu" "In6.Cu" "In8.Cu")
		(hatch none 0.5)
		(connect_pads
			(clearance 0)
		)
		(min_thickness 0.25)
		(keepout
			(tracks not_allowed)
			(vias allowed)
			(pads allowed)
			(copperpour not_allowed)
			(footprints allowed)
		)
		(placement
			(enabled no)
			(sheetname "")
		)
		(fill yes
			(thermal_gap 0.5)
			(thermal_bridge_width 0.5)
			(island_removal_mode 0)
		)
		(polygon
			(pts
				(arc
					(start 205.441042 -105.134664)
					(mid 203.663042 -105.134664)
					(end 205.441042 -105.134664)
				)
			)
		)
	)
	(zone
		(layers "In1.Cu" "In3.Cu" "In6.Cu" "In8.Cu")
		(hatch none 0.5)
		(connect_pads
			(clearance 0)
		)
		(min_thickness 0.25)
		(keepout
			(tracks not_allowed)
			(vias allowed)
			(pads allowed)
			(copperpour not_allowed)
			(footprints allowed)
		)
		(placement
			(enabled no)
			(sheetname "")
		)
		(fill yes
			(thermal_gap 0.5)
			(thermal_bridge_width 0.5)
			(island_removal_mode 0)
		)
		(polygon
			(pts
				(arc
					(start 80.772 -60.96)
					(mid 77.978 -60.96)
					(end 80.772 -60.96)
				)
			)
		)
	)
	(zone
		(layers "In1.Cu" "In3.Cu" "In6.Cu" "In8.Cu")
		(hatch none 0.5)
		(connect_pads
			(clearance 0)
		)
		(min_thickness 0.25)
		(keepout
			(tracks not_allowed)
			(vias allowed)
			(pads allowed)
			(copperpour not_allowed)
			(footprints allowed)
		)
		(placement
			(enabled no)
			(sheetname "")
		)
		(fill yes
			(thermal_gap 0.5)
			(thermal_bridge_width 0.5)
			(island_removal_mode 0)
		)
		(polygon
			(pts
				(arc
					(start 11.22172 -70.939914)
					(mid 8.47852 -70.939914)
					(end 11.22172 -70.939914)
				)
			)
		)
	)
	(zone
		(layers "In1.Cu" "In3.Cu" "In6.Cu" "In8.Cu")
		(hatch none 0.5)
		(connect_pads
			(clearance 0)
		)
		(min_thickness 0.25)
		(keepout
			(tracks not_allowed)
			(vias allowed)
			(pads allowed)
			(copperpour not_allowed)
			(footprints allowed)
		)
		(placement
			(enabled no)
			(sheetname "")
		)
		(fill yes
			(thermal_gap 0.5)
			(thermal_bridge_width 0.5)
			(island_removal_mode 0)
		)
		(polygon
			(pts
				(arc
					(start 186.286394 -121.209816)
					(mid 182.654194 -121.209816)
					(end 186.286394 -121.209816)
				)
			)
		)
	)
	(zone
		(layers "In1.Cu" "In3.Cu" "In6.Cu" "In8.Cu")
		(hatch none 0.5)
		(connect_pads
			(clearance 0)
		)
		(min_thickness 0.25)
		(keepout
			(tracks not_allowed)
			(vias allowed)
			(pads allowed)
			(copperpour not_allowed)
			(footprints allowed)
		)
		(placement
			(enabled no)
			(sheetname "")
		)
		(fill yes
			(thermal_gap 0.5)
			(thermal_bridge_width 0.5)
			(island_removal_mode 0)
		)
		(polygon
			(pts
				(arc
					(start 270.891 -88.9)
					(mid 269.113 -88.9)
					(end 270.891 -88.9)
				)
			)
		)
	)
	(zone
		(layers "In1.Cu" "In3.Cu" "In6.Cu" "In8.Cu")
		(hatch none 0.5)
		(connect_pads
			(clearance 0)
		)
		(min_thickness 0.25)
		(keepout
			(tracks not_allowed)
			(vias allowed)
			(pads allowed)
			(copperpour not_allowed)
			(footprints allowed)
		)
		(placement
			(enabled no)
			(sheetname "")
		)
		(fill yes
			(thermal_gap 0.5)
			(thermal_bridge_width 0.5)
			(island_removal_mode 0)
		)
		(polygon
			(pts
				(arc
					(start 270.891 -77.597)
					(mid 269.113 -77.597)
					(end 270.891 -77.597)
				)
			)
		)
	)
	(zone
		(layers "In1.Cu" "In3.Cu" "In6.Cu" "In8.Cu")
		(hatch none 0.5)
		(connect_pads
			(clearance 0)
		)
		(min_thickness 0.25)
		(keepout
			(tracks not_allowed)
			(vias allowed)
			(pads allowed)
			(copperpour not_allowed)
			(footprints allowed)
		)
		(placement
			(enabled no)
			(sheetname "")
		)
		(fill yes
			(thermal_gap 0.5)
			(thermal_bridge_width 0.5)
			(island_removal_mode 0)
		)
		(polygon
			(pts
				(arc
					(start 286.893 -30.687264)
					(mid 285.115 -30.687264)
					(end 286.893 -30.687264)
				)
			)
		)
	)
	(zone
		(layers "In1.Cu" "In3.Cu" "In6.Cu" "In8.Cu")
		(hatch none 0.5)
		(connect_pads
			(clearance 0)
		)
		(min_thickness 0.25)
		(keepout
			(tracks not_allowed)
			(vias allowed)
			(pads allowed)
			(copperpour not_allowed)
			(footprints allowed)
		)
		(placement
			(enabled no)
			(sheetname "")
		)
		(fill yes
			(thermal_gap 0.5)
			(thermal_bridge_width 0.5)
			(island_removal_mode 0)
		)
		(polygon
			(pts
				(arc
					(start 108.945426 -126.492)
					(mid 107.167426 -126.492)
					(end 108.945426 -126.492)
				)
			)
		)
	)
	(zone
		(layers "In1.Cu" "In3.Cu" "In6.Cu" "In8.Cu")
		(hatch none 0.5)
		(connect_pads
			(clearance 0)
		)
		(min_thickness 0.25)
		(keepout
			(tracks not_allowed)
			(vias allowed)
			(pads allowed)
			(copperpour not_allowed)
			(footprints allowed)
		)
		(placement
			(enabled no)
			(sheetname "")
		)
		(fill yes
			(thermal_gap 0.5)
			(thermal_bridge_width 0.5)
			(island_removal_mode 0)
		)
		(polygon
			(pts
				(arc
					(start 270.129 -85.852)
					(mid 268.351 -85.852)
					(end 270.129 -85.852)
				)
			)
		)
	)
	(zone
		(layers "In1.Cu" "In3.Cu" "In6.Cu" "In8.Cu")
		(hatch none 0.5)
		(connect_pads
			(clearance 0)
		)
		(min_thickness 0.25)
		(keepout
			(tracks not_allowed)
			(vias allowed)
			(pads allowed)
			(copperpour not_allowed)
			(footprints allowed)
		)
		(placement
			(enabled no)
			(sheetname "")
		)
		(fill yes
			(thermal_gap 0.5)
			(thermal_bridge_width 0.5)
			(island_removal_mode 0)
		)
		(polygon
			(pts
				(arc
					(start 272.415 -110.744)
					(mid 270.637 -110.744)
					(end 272.415 -110.744)
				)
			)
		)
	)
	(zone
		(layers "In1.Cu" "In3.Cu" "In6.Cu" "In8.Cu")
		(hatch none 0.5)
		(connect_pads
			(clearance 0)
		)
		(min_thickness 0.25)
		(keepout
			(tracks not_allowed)
			(vias allowed)
			(pads allowed)
			(copperpour not_allowed)
			(footprints allowed)
		)
		(placement
			(enabled no)
			(sheetname "")
		)
		(fill yes
			(thermal_gap 0.5)
			(thermal_bridge_width 0.5)
			(island_removal_mode 0)
		)
		(polygon
			(pts
				(arc
					(start 207.727042 -104.4321)
					(mid 205.949042 -104.4321)
					(end 207.727042 -104.4321)
				)
			)
		)
	)
	(zone
		(layers "In1.Cu" "In3.Cu" "In6.Cu" "In8.Cu")
		(hatch none 0.5)
		(connect_pads
			(clearance 0)
		)
		(min_thickness 0.25)
		(keepout
			(tracks not_allowed)
			(vias allowed)
			(pads allowed)
			(copperpour not_allowed)
			(footprints allowed)
		)
		(placement
			(enabled no)
			(sheetname "")
		)
		(fill yes
			(thermal_gap 0.5)
			(thermal_bridge_width 0.5)
			(island_removal_mode 0)
		)
		(polygon
			(pts
				(arc
					(start 270.129 -62.484)
					(mid 268.351 -62.484)
					(end 270.129 -62.484)
				)
			)
		)
	)
	(zone
		(layers "In1.Cu" "In3.Cu" "In6.Cu" "In8.Cu")
		(hatch none 0.5)
		(connect_pads
			(clearance 0)
		)
		(min_thickness 0.25)
		(keepout
			(tracks not_allowed)
			(vias allowed)
			(pads allowed)
			(copperpour not_allowed)
			(footprints allowed)
		)
		(placement
			(enabled no)
			(sheetname "")
		)
		(fill yes
			(thermal_gap 0.5)
			(thermal_bridge_width 0.5)
			(island_removal_mode 0)
		)
		(polygon
			(pts
				(arc
					(start 225.482912 -97.985834)
					(mid 223.704912 -97.985834)
					(end 225.482912 -97.985834)
				)
			)
		)
	)
	(zone
		(layers "In1.Cu" "In3.Cu" "In6.Cu" "In8.Cu")
		(hatch none 0.5)
		(connect_pads
			(clearance 0)
		)
		(min_thickness 0.25)
		(keepout
			(tracks not_allowed)
			(vias allowed)
			(pads allowed)
			(copperpour not_allowed)
			(footprints allowed)
		)
		(placement
			(enabled no)
			(sheetname "")
		)
		(fill yes
			(thermal_gap 0.5)
			(thermal_bridge_width 0.5)
			(island_removal_mode 0)
		)
		(polygon
			(pts
				(arc
					(start 56.753506 -126.492)
					(mid 54.975506 -126.492)
					(end 56.753506 -126.492)
				)
			)
		)
	)
	(zone
		(layers "In1.Cu" "In3.Cu" "In6.Cu" "In8.Cu")
		(hatch none 0.5)
		(connect_pads
			(clearance 0)
		)
		(min_thickness 0.25)
		(keepout
			(tracks not_allowed)
			(vias allowed)
			(pads allowed)
			(copperpour not_allowed)
			(footprints allowed)
		)
		(placement
			(enabled no)
			(sheetname "")
		)
		(fill yes
			(thermal_gap 0.5)
			(thermal_bridge_width 0.5)
			(island_removal_mode 0)
		)
		(polygon
			(pts
				(arc
					(start 42.8879 -56.805068)
					(mid 41.1099 -56.805068)
					(end 42.8879 -56.805068)
				)
			)
		)
	)
	(zone
		(layers "In1.Cu" "In3.Cu" "In6.Cu" "In8.Cu")
		(hatch none 0.5)
		(connect_pads
			(clearance 0)
		)
		(min_thickness 0.25)
		(keepout
			(tracks not_allowed)
			(vias allowed)
			(pads allowed)
			(copperpour not_allowed)
			(footprints allowed)
		)
		(placement
			(enabled no)
			(sheetname "")
		)
		(fill yes
			(thermal_gap 0.5)
			(thermal_bridge_width 0.5)
			(island_removal_mode 0)
		)
		(polygon
			(pts
				(arc
					(start 219.161868 -103.6701)
					(mid 217.383868 -103.6701)
					(end 219.161868 -103.6701)
				)
			)
		)
	)
	(zone
		(layers "In1.Cu" "In3.Cu" "In6.Cu" "In8.Cu")
		(hatch none 0.5)
		(connect_pads
			(clearance 0)
		)
		(min_thickness 0.25)
		(keepout
			(tracks not_allowed)
			(vias allowed)
			(pads allowed)
			(copperpour not_allowed)
			(footprints allowed)
		)
		(placement
			(enabled no)
			(sheetname "")
		)
		(fill yes
			(thermal_gap 0.5)
			(thermal_bridge_width 0.5)
			(island_removal_mode 0)
		)
		(polygon
			(pts
				(arc
					(start 217.825828 -131.42214)
					(mid 216.047828 -131.42214)
					(end 217.825828 -131.42214)
				)
			)
		)
	)
	(zone
		(layers "In1.Cu" "In3.Cu" "In6.Cu" "In8.Cu")
		(hatch none 0.5)
		(connect_pads
			(clearance 0)
		)
		(min_thickness 0.25)
		(keepout
			(tracks not_allowed)
			(vias allowed)
			(pads allowed)
			(copperpour not_allowed)
			(footprints allowed)
		)
		(placement
			(enabled no)
			(sheetname "")
		)
		(fill yes
			(thermal_gap 0.5)
			(thermal_bridge_width 0.5)
			(island_removal_mode 0)
		)
		(polygon
			(pts
				(arc
					(start 206.203042 -104.4321)
					(mid 204.425042 -104.4321)
					(end 206.203042 -104.4321)
				)
			)
		)
	)
	(zone
		(layers "In1.Cu" "In3.Cu" "In6.Cu" "In8.Cu")
		(hatch none 0.5)
		(connect_pads
			(clearance 0)
		)
		(min_thickness 0.25)
		(keepout
			(tracks not_allowed)
			(vias allowed)
			(pads allowed)
			(copperpour not_allowed)
			(footprints allowed)
		)
		(placement
			(enabled no)
			(sheetname "")
		)
		(fill yes
			(thermal_gap 0.5)
			(thermal_bridge_width 0.5)
			(island_removal_mode 0)
		)
		(polygon
			(pts
				(arc
					(start 270.129 -112.268)
					(mid 268.351 -112.268)
					(end 270.129 -112.268)
				)
			)
		)
	)
	(zone
		(layers "In1.Cu" "In3.Cu" "In6.Cu" "In8.Cu")
		(hatch none 0.5)
		(connect_pads
			(clearance 0)
		)
		(min_thickness 0.25)
		(keepout
			(tracks not_allowed)
			(vias allowed)
			(pads allowed)
			(copperpour not_allowed)
			(footprints allowed)
		)
		(placement
			(enabled no)
			(sheetname "")
		)
		(fill yes
			(thermal_gap 0.5)
			(thermal_bridge_width 0.5)
			(island_removal_mode 0)
		)
		(polygon
			(pts
				(arc
					(start 205.441042 -104.4321)
					(mid 203.663042 -104.4321)
					(end 205.441042 -104.4321)
				)
			)
		)
	)
	(zone
		(layers "In1.Cu" "In3.Cu" "In6.Cu" "In8.Cu")
		(hatch none 0.5)
		(connect_pads
			(clearance 0)
		)
		(min_thickness 0.25)
		(keepout
			(tracks not_allowed)
			(vias allowed)
			(pads allowed)
			(copperpour not_allowed)
			(footprints allowed)
		)
		(placement
			(enabled no)
			(sheetname "")
		)
		(fill yes
			(thermal_gap 0.5)
			(thermal_bridge_width 0.5)
			(island_removal_mode 0)
		)
		(polygon
			(pts
				(arc
					(start 11.22172 -74.319892)
					(mid 8.47852 -74.319892)
					(end 11.22172 -74.319892)
				)
			)
		)
	)
	(zone
		(layers "In1.Cu" "In3.Cu" "In6.Cu" "In8.Cu")
		(hatch none 0.5)
		(connect_pads
			(clearance 0)
		)
		(min_thickness 0.25)
		(keepout
			(tracks not_allowed)
			(vias allowed)
			(pads allowed)
			(copperpour not_allowed)
			(footprints allowed)
		)
		(placement
			(enabled no)
			(sheetname "")
		)
		(fill yes
			(thermal_gap 0.5)
			(thermal_bridge_width 0.5)
			(island_removal_mode 0)
		)
		(polygon
			(pts
				(arc
					(start 271.653 -111.506)
					(mid 269.875 -111.506)
					(end 271.653 -111.506)
				)
			)
		)
	)
	(zone
		(layers "In1.Cu" "In3.Cu" "In6.Cu" "In8.Cu")
		(hatch none 0.5)
		(connect_pads
			(clearance 0)
		)
		(min_thickness 0.25)
		(keepout
			(tracks not_allowed)
			(vias allowed)
			(pads allowed)
			(copperpour not_allowed)
			(footprints allowed)
		)
		(placement
			(enabled no)
			(sheetname "")
		)
		(fill yes
			(thermal_gap 0.5)
			(thermal_bridge_width 0.5)
			(island_removal_mode 0)
		)
		(polygon
			(pts
				(arc
					(start 270.129 -75.311)
					(mid 268.351 -75.311)
					(end 270.129 -75.311)
				)
			)
		)
	)
	(zone
		(layers "In1.Cu" "In3.Cu" "In6.Cu" "In8.Cu")
		(hatch none 0.5)
		(connect_pads
			(clearance 0)
		)
		(min_thickness 0.25)
		(keepout
			(tracks not_allowed)
			(vias allowed)
			(pads allowed)
			(copperpour not_allowed)
			(footprints allowed)
		)
		(placement
			(enabled no)
			(sheetname "")
		)
		(fill yes
			(thermal_gap 0.5)
			(thermal_bridge_width 0.5)
			(island_removal_mode 0)
		)
		(polygon
			(pts
				(arc
					(start 270.129 -64.77)
					(mid 268.351 -64.77)
					(end 270.129 -64.77)
				)
			)
		)
	)
	(zone
		(layers "In1.Cu" "In3.Cu" "In6.Cu" "In8.Cu")
		(hatch none 0.5)
		(connect_pads
			(clearance 0)
		)
		(min_thickness 0.25)
		(keepout
			(tracks not_allowed)
			(vias allowed)
			(pads allowed)
			(copperpour not_allowed)
			(footprints allowed)
		)
		(placement
			(enabled no)
			(sheetname "")
		)
		(fill yes
			(thermal_gap 0.5)
			(thermal_bridge_width 0.5)
			(island_removal_mode 0)
		)
		(polygon
			(pts
				(arc
					(start 208.445862 -105.882948)
					(mid 206.667862 -105.882948)
					(end 208.445862 -105.882948)
				)
			)
		)
	)
	(zone
		(layers "In1.Cu" "In3.Cu" "In6.Cu" "In8.Cu")
		(hatch none 0.5)
		(connect_pads
			(clearance 0)
		)
		(min_thickness 0.25)
		(keepout
			(tracks not_allowed)
			(vias allowed)
			(pads allowed)
			(copperpour not_allowed)
			(footprints allowed)
		)
		(placement
			(enabled no)
			(sheetname "")
		)
		(fill yes
			(thermal_gap 0.5)
			(thermal_bridge_width 0.5)
			(island_removal_mode 0)
		)
		(polygon
			(pts
				(arc
					(start 270.129 -65.532)
					(mid 268.351 -65.532)
					(end 270.129 -65.532)
				)
			)
		)
	)
	(zone
		(layers "In1.Cu" "In3.Cu" "In6.Cu" "In8.Cu")
		(hatch none 0.5)
		(connect_pads
			(clearance 0)
		)
		(min_thickness 0.25)
		(keepout
			(tracks not_allowed)
			(vias allowed)
			(pads allowed)
			(copperpour not_allowed)
			(footprints allowed)
		)
		(placement
			(enabled no)
			(sheetname "")
		)
		(fill yes
			(thermal_gap 0.5)
			(thermal_bridge_width 0.5)
			(island_removal_mode 0)
		)
		(polygon
			(pts
				(arc
					(start 238.205518 -97.985834)
					(mid 236.427518 -97.985834)
					(end 238.205518 -97.985834)
				)
			)
		)
	)
	(zone
		(layers "In1.Cu" "In3.Cu" "In6.Cu" "In8.Cu")
		(hatch none 0.5)
		(connect_pads
			(clearance 0)
		)
		(min_thickness 0.25)
		(keepout
			(tracks not_allowed)
			(vias allowed)
			(pads allowed)
			(copperpour not_allowed)
			(footprints allowed)
		)
		(placement
			(enabled no)
			(sheetname "")
		)
		(fill yes
			(thermal_gap 0.5)
			(thermal_bridge_width 0.5)
			(island_removal_mode 0)
		)
		(polygon
			(pts
				(arc
					(start 203.23937 -122.809762)
					(mid 201.46137 -122.809762)
					(end 203.23937 -122.809762)
				)
			)
		)
	)
	(zone
		(layers "In1.Cu" "In3.Cu" "In6.Cu" "In8.Cu")
		(hatch none 0.5)
		(connect_pads
			(clearance 0)
		)
		(min_thickness 0.25)
		(keepout
			(tracks not_allowed)
			(vias allowed)
			(pads allowed)
			(copperpour not_allowed)
			(footprints allowed)
		)
		(placement
			(enabled no)
			(sheetname "")
		)
		(fill yes
			(thermal_gap 0.5)
			(thermal_bridge_width 0.5)
			(island_removal_mode 0)
		)
		(polygon
			(pts
				(arc
					(start 232.480104 -128.824736)
					(mid 230.702104 -128.824736)
					(end 232.480104 -128.824736)
				)
			)
		)
	)
	(zone
		(layers "In1.Cu" "In3.Cu" "In6.Cu" "In8.Cu")
		(hatch none 0.5)
		(connect_pads
			(clearance 0)
		)
		(min_thickness 0.25)
		(keepout
			(tracks not_allowed)
			(vias allowed)
			(pads allowed)
			(copperpour not_allowed)
			(footprints allowed)
		)
		(placement
			(enabled no)
			(sheetname "")
		)
		(fill yes
			(thermal_gap 0.5)
			(thermal_bridge_width 0.5)
			(island_removal_mode 0)
		)
		(polygon
			(pts
				(arc
					(start 42.73804 -53.3019)
					(mid 40.96004 -53.3019)
					(end 42.73804 -53.3019)
				)
			)
		)
	)
	(zone
		(layers "In1.Cu" "In3.Cu" "In6.Cu" "In8.Cu")
		(hatch none 0.5)
		(connect_pads
			(clearance 0)
		)
		(min_thickness 0.25)
		(keepout
			(tracks not_allowed)
			(vias allowed)
			(pads allowed)
			(copperpour not_allowed)
			(footprints allowed)
		)
		(placement
			(enabled no)
			(sheetname "")
		)
		(fill yes
			(thermal_gap 0.5)
			(thermal_bridge_width 0.5)
			(island_removal_mode 0)
		)
		(polygon
			(pts
				(arc
					(start 222.928688 -103.656384)
					(mid 221.150688 -103.656384)
					(end 222.928688 -103.656384)
				)
			)
		)
	)
	(zone
		(layers "In1.Cu" "In3.Cu" "In6.Cu" "In8.Cu")
		(hatch none 0.5)
		(connect_pads
			(clearance 0)
		)
		(min_thickness 0.25)
		(keepout
			(tracks not_allowed)
			(vias allowed)
			(pads allowed)
			(copperpour not_allowed)
			(footprints allowed)
		)
		(placement
			(enabled no)
			(sheetname "")
		)
		(fill yes
			(thermal_gap 0.5)
			(thermal_bridge_width 0.5)
			(island_removal_mode 0)
		)
		(polygon
			(pts
				(arc
					(start 270.129 -77.597)
					(mid 268.351 -77.597)
					(end 270.129 -77.597)
				)
			)
		)
	)
	(zone
		(layers "In1.Cu" "In3.Cu" "In6.Cu" "In8.Cu")
		(hatch none 0.5)
		(connect_pads
			(clearance 0)
		)
		(min_thickness 0.25)
		(keepout
			(tracks not_allowed)
			(vias allowed)
			(pads allowed)
			(copperpour not_allowed)
			(footprints allowed)
		)
		(placement
			(enabled no)
			(sheetname "")
		)
		(fill yes
			(thermal_gap 0.5)
			(thermal_bridge_width 0.5)
			(island_removal_mode 0)
		)
		(polygon
			(pts
				(arc
					(start 271.653 -125.095)
					(mid 269.875 -125.095)
					(end 271.653 -125.095)
				)
			)
		)
	)
	(zone
		(layers "In1.Cu" "In3.Cu" "In6.Cu" "In8.Cu")
		(hatch none 0.5)
		(connect_pads
			(clearance 0)
		)
		(min_thickness 0.25)
		(keepout
			(tracks not_allowed)
			(vias allowed)
			(pads allowed)
			(copperpour not_allowed)
			(footprints allowed)
		)
		(placement
			(enabled no)
			(sheetname "")
		)
		(fill yes
			(thermal_gap 0.5)
			(thermal_bridge_width 0.5)
			(island_removal_mode 0)
		)
		(polygon
			(pts
				(arc
					(start 270.129 -87.376)
					(mid 268.351 -87.376)
					(end 270.129 -87.376)
				)
			)
		)
	)
	(zone
		(layers "In1.Cu" "In3.Cu" "In6.Cu" "In8.Cu")
		(hatch none 0.5)
		(connect_pads
			(clearance 0)
		)
		(min_thickness 0.25)
		(keepout
			(tracks not_allowed)
			(vias allowed)
			(pads allowed)
			(copperpour not_allowed)
			(footprints allowed)
		)
		(placement
			(enabled no)
			(sheetname "")
		)
		(fill yes
			(thermal_gap 0.5)
			(thermal_bridge_width 0.5)
			(island_removal_mode 0)
		)
		(polygon
			(pts
				(arc
					(start 50.96764 -52.8828)
					(mid 49.18964 -52.8828)
					(end 50.96764 -52.8828)
				)
			)
		)
	)
	(zone
		(layers "In1.Cu" "In3.Cu" "In6.Cu" "In8.Cu")
		(hatch none 0.5)
		(connect_pads
			(clearance 0)
		)
		(min_thickness 0.25)
		(keepout
			(tracks not_allowed)
			(vias allowed)
			(pads allowed)
			(copperpour not_allowed)
			(footprints allowed)
		)
		(placement
			(enabled no)
			(sheetname "")
		)
		(fill yes
			(thermal_gap 0.5)
			(thermal_bridge_width 0.5)
			(island_removal_mode 0)
		)
		(polygon
			(pts
				(arc
					(start 270.891 -86.614)
					(mid 269.113 -86.614)
					(end 270.891 -86.614)
				)
			)
		)
	)
	(zone
		(layers "In1.Cu" "In3.Cu" "In6.Cu" "In8.Cu")
		(hatch none 0.5)
		(connect_pads
			(clearance 0)
		)
		(min_thickness 0.25)
		(keepout
			(tracks not_allowed)
			(vias allowed)
			(pads allowed)
			(copperpour not_allowed)
			(footprints allowed)
		)
		(placement
			(enabled no)
			(sheetname "")
		)
		(fill yes
			(thermal_gap 0.5)
			(thermal_bridge_width 0.5)
			(island_removal_mode 0)
		)
		(polygon
			(pts
				(arc
					(start 108.183426 -126.492)
					(mid 106.405426 -126.492)
					(end 108.183426 -126.492)
				)
			)
		)
	)
	(zone
		(layers "In1.Cu" "In3.Cu" "In6.Cu" "In8.Cu")
		(hatch none 0.5)
		(connect_pads
			(clearance 0)
		)
		(min_thickness 0.25)
		(keepout
			(tracks not_allowed)
			(vias allowed)
			(pads allowed)
			(copperpour not_allowed)
			(footprints allowed)
		)
		(placement
			(enabled no)
			(sheetname "")
		)
		(fill yes
			(thermal_gap 0.5)
			(thermal_bridge_width 0.5)
			(island_removal_mode 0)
		)
		(polygon
			(pts
				(arc
					(start 271.653 -124.333)
					(mid 269.875 -124.333)
					(end 271.653 -124.333)
				)
			)
		)
	)
	(zone
		(layers "In1.Cu" "In3.Cu" "In6.Cu" "In8.Cu")
		(hatch none 0.5)
		(connect_pads
			(clearance 0)
		)
		(min_thickness 0.25)
		(keepout
			(tracks not_allowed)
			(vias allowed)
			(pads allowed)
			(copperpour not_allowed)
			(footprints allowed)
		)
		(placement
			(enabled no)
			(sheetname "")
		)
		(fill yes
			(thermal_gap 0.5)
			(thermal_bridge_width 0.5)
			(island_removal_mode 0)
		)
		(polygon
			(pts
				(arc
					(start 41.656 -106.045)
					(mid 39.878 -106.045)
					(end 41.656 -106.045)
				)
			)
		)
	)
	(zone
		(layers "In1.Cu" "In3.Cu" "In6.Cu" "In8.Cu")
		(hatch none 0.5)
		(connect_pads
			(clearance 0)
		)
		(min_thickness 0.25)
		(keepout
			(tracks not_allowed)
			(vias allowed)
			(pads allowed)
			(copperpour not_allowed)
			(footprints allowed)
		)
		(placement
			(enabled no)
			(sheetname "")
		)
		(fill yes
			(thermal_gap 0.5)
			(thermal_bridge_width 0.5)
			(island_removal_mode 0)
		)
		(polygon
			(pts
				(arc
					(start 223.74987 -97.985834)
					(mid 221.97187 -97.985834)
					(end 223.74987 -97.985834)
				)
			)
		)
	)
	(zone
		(layers "In1.Cu" "In3.Cu" "In6.Cu" "In8.Cu")
		(hatch none 0.5)
		(connect_pads
			(clearance 0)
		)
		(min_thickness 0.25)
		(keepout
			(tracks not_allowed)
			(vias allowed)
			(pads allowed)
			(copperpour not_allowed)
			(footprints allowed)
		)
		(placement
			(enabled no)
			(sheetname "")
		)
		(fill yes
			(thermal_gap 0.5)
			(thermal_bridge_width 0.5)
			(island_removal_mode 0)
		)
		(polygon
			(pts
				(arc
					(start 271.653 -89.662)
					(mid 269.875 -89.662)
					(end 271.653 -89.662)
				)
			)
		)
	)
	(zone
		(layers "In1.Cu" "In3.Cu" "In6.Cu" "In8.Cu")
		(hatch none 0.5)
		(connect_pads
			(clearance 0)
		)
		(min_thickness 0.25)
		(keepout
			(tracks not_allowed)
			(vias allowed)
			(pads allowed)
			(copperpour not_allowed)
			(footprints allowed)
		)
		(placement
			(enabled no)
			(sheetname "")
		)
		(fill yes
			(thermal_gap 0.5)
			(thermal_bridge_width 0.5)
			(island_removal_mode 0)
		)
		(polygon
			(pts
				(arc
					(start 222.950278 -122.047762)
					(mid 221.172278 -122.047762)
					(end 222.950278 -122.047762)
				)
			)
		)
	)
	(zone
		(layers "In1.Cu" "In3.Cu" "In6.Cu" "In8.Cu")
		(hatch none 0.5)
		(connect_pads
			(clearance 0)
		)
		(min_thickness 0.25)
		(keepout
			(tracks not_allowed)
			(vias allowed)
			(pads allowed)
			(copperpour not_allowed)
			(footprints allowed)
		)
		(placement
			(enabled no)
			(sheetname "")
		)
		(fill yes
			(thermal_gap 0.5)
			(thermal_bridge_width 0.5)
			(island_removal_mode 0)
		)
		(polygon
			(pts
				(arc
					(start 272.542 -136.652)
					(mid 270.764 -136.652)
					(end 272.542 -136.652)
				)
			)
		)
	)
	(zone
		(layers "In1.Cu" "In3.Cu" "In6.Cu" "In8.Cu")
		(hatch none 0.5)
		(connect_pads
			(clearance 0)
		)
		(min_thickness 0.25)
		(keepout
			(tracks not_allowed)
			(vias allowed)
			(pads allowed)
			(copperpour not_allowed)
			(footprints allowed)
		)
		(placement
			(enabled no)
			(sheetname "")
		)
		(fill yes
			(thermal_gap 0.5)
			(thermal_bridge_width 0.5)
			(island_removal_mode 0)
		)
		(polygon
			(pts
				(arc
					(start 218.378278 -122.809762)
					(mid 216.600278 -122.809762)
					(end 218.378278 -122.809762)
				)
			)
		)
	)
	(zone
		(layers "In1.Cu" "In3.Cu" "In6.Cu" "In8.Cu")
		(hatch none 0.5)
		(connect_pads
			(clearance 0)
		)
		(min_thickness 0.25)
		(keepout
			(tracks not_allowed)
			(vias allowed)
			(pads allowed)
			(copperpour not_allowed)
			(footprints allowed)
		)
		(placement
			(enabled no)
			(sheetname "")
		)
		(fill yes
			(thermal_gap 0.5)
			(thermal_bridge_width 0.5)
			(island_removal_mode 0)
		)
		(polygon
			(pts
				(arc
					(start 178.17846 -51.562)
					(mid 176.40046 -51.562)
					(end 178.17846 -51.562)
				)
			)
		)
	)
	(zone
		(layers "In1.Cu" "In3.Cu" "In6.Cu" "In8.Cu")
		(hatch none 0.5)
		(connect_pads
			(clearance 0)
		)
		(min_thickness 0.25)
		(keepout
			(tracks not_allowed)
			(vias allowed)
			(pads allowed)
			(copperpour not_allowed)
			(footprints allowed)
		)
		(placement
			(enabled no)
			(sheetname "")
		)
		(fill yes
			(thermal_gap 0.5)
			(thermal_bridge_width 0.5)
			(island_removal_mode 0)
		)
		(polygon
			(pts
				(arc
					(start 218.378278 -122.047762)
					(mid 216.600278 -122.047762)
					(end 218.378278 -122.047762)
				)
			)
		)
	)
	(zone
		(layers "In1.Cu" "In3.Cu" "In6.Cu" "In8.Cu")
		(hatch none 0.5)
		(connect_pads
			(clearance 0)
		)
		(min_thickness 0.25)
		(keepout
			(tracks not_allowed)
			(vias allowed)
			(pads allowed)
			(copperpour not_allowed)
			(footprints allowed)
		)
		(placement
			(enabled no)
			(sheetname "")
		)
		(fill yes
			(thermal_gap 0.5)
			(thermal_bridge_width 0.5)
			(island_removal_mode 0)
		)
		(polygon
			(pts
				(arc
					(start 124.5616 -131.572)
					(mid 122.7836 -131.572)
					(end 124.5616 -131.572)
				)
			)
		)
	)
	(zone
		(layers "In1.Cu" "In3.Cu" "In6.Cu" "In8.Cu")
		(hatch none 0.5)
		(connect_pads
			(clearance 0)
		)
		(min_thickness 0.25)
		(keepout
			(tracks not_allowed)
			(vias allowed)
			(pads allowed)
			(copperpour not_allowed)
			(footprints allowed)
		)
		(placement
			(enabled no)
			(sheetname "")
		)
		(fill yes
			(thermal_gap 0.5)
			(thermal_bridge_width 0.5)
			(island_removal_mode 0)
		)
		(polygon
			(pts
				(arc
					(start 203.23937 -122.047762)
					(mid 201.46137 -122.047762)
					(end 203.23937 -122.047762)
				)
			)
		)
	)
	(zone
		(layers "In1.Cu" "In3.Cu" "In6.Cu" "In8.Cu")
		(hatch none 0.5)
		(connect_pads
			(clearance 0)
		)
		(min_thickness 0.25)
		(keepout
			(tracks not_allowed)
			(vias allowed)
			(pads allowed)
			(copperpour not_allowed)
			(footprints allowed)
		)
		(placement
			(enabled no)
			(sheetname "")
		)
		(fill yes
			(thermal_gap 0.5)
			(thermal_bridge_width 0.5)
			(island_removal_mode 0)
		)
		(polygon
			(pts
				(arc
					(start 51.72964 -52.1208)
					(mid 49.95164 -52.1208)
					(end 51.72964 -52.1208)
				)
			)
		)
	)
	(zone
		(layers "In1.Cu" "In3.Cu" "In6.Cu" "In8.Cu")
		(hatch none 0.5)
		(connect_pads
			(clearance 0)
		)
		(min_thickness 0.25)
		(keepout
			(tracks not_allowed)
			(vias allowed)
			(pads allowed)
			(copperpour not_allowed)
			(footprints allowed)
		)
		(placement
			(enabled no)
			(sheetname "")
		)
		(fill yes
			(thermal_gap 0.5)
			(thermal_bridge_width 0.5)
			(island_removal_mode 0)
		)
		(polygon
			(pts
				(arc
					(start 270.129 -97.917)
					(mid 268.351 -97.917)
					(end 270.129 -97.917)
				)
			)
		)
	)
	(zone
		(layers "In1.Cu" "In3.Cu" "In6.Cu" "In8.Cu")
		(hatch none 0.5)
		(connect_pads
			(clearance 0)
		)
		(min_thickness 0.25)
		(keepout
			(tracks not_allowed)
			(vias allowed)
			(pads allowed)
			(copperpour not_allowed)
			(footprints allowed)
		)
		(placement
			(enabled no)
			(sheetname "")
		)
		(fill yes
			(thermal_gap 0.5)
			(thermal_bridge_width 0.5)
			(island_removal_mode 0)
		)
		(polygon
			(pts
				(arc
					(start 203.2254 -102.894638)
					(mid 201.4474 -102.894638)
					(end 203.2254 -102.894638)
				)
			)
		)
	)
	(zone
		(layers "In1.Cu" "In3.Cu" "In6.Cu" "In8.Cu")
		(hatch none 0.5)
		(connect_pads
			(clearance 0)
		)
		(min_thickness 0.25)
		(keepout
			(tracks not_allowed)
			(vias allowed)
			(pads allowed)
			(copperpour not_allowed)
			(footprints allowed)
		)
		(placement
			(enabled no)
			(sheetname "")
		)
		(fill yes
			(thermal_gap 0.5)
			(thermal_bridge_width 0.5)
			(island_removal_mode 0)
		)
		(polygon
			(pts
				(arc
					(start 121.412 -60.96)
					(mid 118.618 -60.96)
					(end 121.412 -60.96)
				)
			)
		)
	)
	(zone
		(layers "In1.Cu" "In3.Cu" "In6.Cu" "In8.Cu")
		(hatch none 0.5)
		(connect_pads
			(clearance 0)
		)
		(min_thickness 0.25)
		(keepout
			(tracks not_allowed)
			(vias allowed)
			(pads allowed)
			(copperpour not_allowed)
			(footprints allowed)
		)
		(placement
			(enabled no)
			(sheetname "")
		)
		(fill yes
			(thermal_gap 0.5)
			(thermal_bridge_width 0.5)
			(island_removal_mode 0)
		)
		(polygon
			(pts
				(arc
					(start 217.708226 -103.656638)
					(mid 215.930226 -103.656638)
					(end 217.708226 -103.656638)
				)
			)
		)
	)
	(zone
		(layers "In1.Cu" "In3.Cu" "In6.Cu" "In8.Cu")
		(hatch none 0.5)
		(connect_pads
			(clearance 0)
		)
		(min_thickness 0.25)
		(keepout
			(tracks not_allowed)
			(vias allowed)
			(pads allowed)
			(copperpour not_allowed)
			(footprints allowed)
		)
		(placement
			(enabled no)
			(sheetname "")
		)
		(fill yes
			(thermal_gap 0.5)
			(thermal_bridge_width 0.5)
			(island_removal_mode 0)
		)
		(polygon
			(pts
				(arc
					(start 221.447868 -104.4321)
					(mid 219.669868 -104.4321)
					(end 221.447868 -104.4321)
				)
			)
		)
	)
	(zone
		(layers "In1.Cu" "In3.Cu" "In6.Cu" "In8.Cu")
		(hatch none 0.5)
		(connect_pads
			(clearance 0)
		)
		(min_thickness 0.25)
		(keepout
			(tracks not_allowed)
			(vias allowed)
			(pads allowed)
			(copperpour not_allowed)
			(footprints allowed)
		)
		(placement
			(enabled no)
			(sheetname "")
		)
		(fill yes
			(thermal_gap 0.5)
			(thermal_bridge_width 0.5)
			(island_removal_mode 0)
		)
		(polygon
			(pts
				(arc
					(start 84.561426 -131.572)
					(mid 82.783426 -131.572)
					(end 84.561426 -131.572)
				)
			)
		)
	)
	(zone
		(layers "In1.Cu" "In3.Cu" "In6.Cu" "In8.Cu")
		(hatch none 0.5)
		(connect_pads
			(clearance 0)
		)
		(min_thickness 0.25)
		(keepout
			(tracks not_allowed)
			(vias allowed)
			(pads allowed)
			(copperpour not_allowed)
			(footprints allowed)
		)
		(placement
			(enabled no)
			(sheetname "")
		)
		(fill yes
			(thermal_gap 0.5)
			(thermal_bridge_width 0.5)
			(island_removal_mode 0)
		)
		(polygon
			(pts
				(arc
					(start 208.445862 -104.418384)
					(mid 206.667862 -104.418384)
					(end 208.445862 -104.418384)
				)
			)
		)
	)
	(zone
		(layers "In1.Cu" "In3.Cu" "In6.Cu" "In8.Cu")
		(hatch none 0.5)
		(connect_pads
			(clearance 0)
		)
		(min_thickness 0.25)
		(keepout
			(tracks not_allowed)
			(vias allowed)
			(pads allowed)
			(copperpour not_allowed)
			(footprints allowed)
		)
		(placement
			(enabled no)
			(sheetname "")
		)
		(fill yes
			(thermal_gap 0.5)
			(thermal_bridge_width 0.5)
			(island_removal_mode 0)
		)
		(polygon
			(pts
				(arc
					(start 270.891 -101.727)
					(mid 269.113 -101.727)
					(end 270.891 -101.727)
				)
			)
		)
	)
	(zone
		(layers "In1.Cu" "In3.Cu" "In6.Cu" "In8.Cu")
		(hatch none 0.5)
		(connect_pads
			(clearance 0)
		)
		(min_thickness 0.25)
		(keepout
			(tracks not_allowed)
			(vias allowed)
			(pads allowed)
			(copperpour not_allowed)
			(footprints allowed)
		)
		(placement
			(enabled no)
			(sheetname "")
		)
		(fill yes
			(thermal_gap 0.5)
			(thermal_bridge_width 0.5)
			(island_removal_mode 0)
		)
		(polygon
			(pts
				(arc
					(start 207.04937 -120.569736)
					(mid 205.27137 -120.569736)
					(end 207.04937 -120.569736)
				)
			)
		)
	)
	(zone
		(layers "In1.Cu" "In3.Cu" "In6.Cu" "In8.Cu")
		(hatch none 0.5)
		(connect_pads
			(clearance 0)
		)
		(min_thickness 0.25)
		(keepout
			(tracks not_allowed)
			(vias allowed)
			(pads allowed)
			(copperpour not_allowed)
			(footprints allowed)
		)
		(placement
			(enabled no)
			(sheetname "")
		)
		(fill yes
			(thermal_gap 0.5)
			(thermal_bridge_width 0.5)
			(island_removal_mode 0)
		)
		(polygon
			(pts
				(arc
					(start 222.209868 -105.134664)
					(mid 220.431868 -105.134664)
					(end 222.209868 -105.134664)
				)
			)
		)
	)
	(zone
		(layers "In1.Cu" "In3.Cu" "In6.Cu" "In8.Cu")
		(hatch none 0.5)
		(connect_pads
			(clearance 0)
		)
		(min_thickness 0.25)
		(keepout
			(tracks not_allowed)
			(vias allowed)
			(pads allowed)
			(copperpour not_allowed)
			(footprints allowed)
		)
		(placement
			(enabled no)
			(sheetname "")
		)
		(fill yes
			(thermal_gap 0.5)
			(thermal_bridge_width 0.5)
			(island_removal_mode 0)
		)
		(polygon
			(pts
				(arc
					(start 89.154 -49.784)
					(mid 87.376 -49.784)
					(end 89.154 -49.784)
				)
			)
		)
	)
	(zone
		(layers "In1.Cu" "In3.Cu" "In6.Cu" "In8.Cu")
		(hatch none 0.5)
		(connect_pads
			(clearance 0)
		)
		(min_thickness 0.25)
		(keepout
			(tracks not_allowed)
			(vias allowed)
			(pads allowed)
			(copperpour not_allowed)
			(footprints allowed)
		)
		(placement
			(enabled no)
			(sheetname "")
		)
		(fill yes
			(thermal_gap 0.5)
			(thermal_bridge_width 0.5)
			(island_removal_mode 0)
		)
		(polygon
			(pts
				(arc
					(start 220.664278 -122.047762)
					(mid 218.886278 -122.047762)
					(end 220.664278 -122.047762)
				)
			)
		)
	)
	(zone
		(layers "In1.Cu" "In3.Cu" "In6.Cu" "In8.Cu")
		(hatch none 0.5)
		(connect_pads
			(clearance 0)
		)
		(min_thickness 0.25)
		(keepout
			(tracks not_allowed)
			(vias allowed)
			(pads allowed)
			(copperpour not_allowed)
			(footprints allowed)
		)
		(placement
			(enabled no)
			(sheetname "")
		)
		(fill yes
			(thermal_gap 0.5)
			(thermal_bridge_width 0.5)
			(island_removal_mode 0)
		)
		(polygon
			(pts
				(arc
					(start 206.28737 -121.331736)
					(mid 204.50937 -121.331736)
					(end 206.28737 -121.331736)
				)
			)
		)
	)
	(zone
		(layers "In1.Cu" "In3.Cu" "In6.Cu" "In8.Cu")
		(hatch none 0.5)
		(connect_pads
			(clearance 0)
		)
		(min_thickness 0.25)
		(keepout
			(tracks not_allowed)
			(vias allowed)
			(pads allowed)
			(copperpour not_allowed)
			(footprints allowed)
		)
		(placement
			(enabled no)
			(sheetname "")
		)
		(fill yes
			(thermal_gap 0.5)
			(thermal_bridge_width 0.5)
			(island_removal_mode 0)
		)
		(polygon
			(pts
				(arc
					(start 70.477126 -70.409816)
					(mid 66.082926 -70.409816)
					(end 70.477126 -70.409816)
				)
			)
		)
	)
	(zone
		(layers "In1.Cu" "In3.Cu" "In6.Cu" "In8.Cu")
		(hatch none 0.5)
		(connect_pads
			(clearance 0)
		)
		(min_thickness 0.25)
		(keepout
			(tracks not_allowed)
			(vias allowed)
			(pads allowed)
			(copperpour not_allowed)
			(footprints allowed)
		)
		(placement
			(enabled no)
			(sheetname "")
		)
		(fill yes
			(thermal_gap 0.5)
			(thermal_bridge_width 0.5)
			(island_removal_mode 0)
		)
		(polygon
			(pts
				(arc
					(start 216.347802 -129.13614)
					(mid 214.569802 -129.13614)
					(end 216.347802 -129.13614)
				)
			)
		)
	)
	(zone
		(layers "In1.Cu" "In3.Cu" "In6.Cu" "In8.Cu")
		(hatch none 0.5)
		(connect_pads
			(clearance 0)
		)
		(min_thickness 0.25)
		(keepout
			(tracks not_allowed)
			(vias allowed)
			(pads allowed)
			(copperpour not_allowed)
			(footprints allowed)
		)
		(placement
			(enabled no)
			(sheetname "")
		)
		(fill yes
			(thermal_gap 0.5)
			(thermal_bridge_width 0.5)
			(island_removal_mode 0)
		)
		(polygon
			(pts
				(arc
					(start 272.415 -109.982)
					(mid 270.637 -109.982)
					(end 272.415 -109.982)
				)
			)
		)
	)
	(zone
		(layers "In1.Cu" "In3.Cu" "In6.Cu" "In8.Cu")
		(hatch none 0.5)
		(connect_pads
			(clearance 0)
		)
		(min_thickness 0.25)
		(keepout
			(tracks not_allowed)
			(vias allowed)
			(pads allowed)
			(copperpour not_allowed)
			(footprints allowed)
		)
		(placement
			(enabled no)
			(sheetname "")
		)
		(fill yes
			(thermal_gap 0.5)
			(thermal_bridge_width 0.5)
			(island_removal_mode 0)
		)
		(polygon
			(pts
				(arc
					(start 83.799426 -131.572)
					(mid 82.021426 -131.572)
					(end 83.799426 -131.572)
				)
			)
		)
	)
	(zone
		(layers "In1.Cu" "In3.Cu" "In6.Cu" "In8.Cu")
		(hatch none 0.5)
		(connect_pads
			(clearance 0)
		)
		(min_thickness 0.25)
		(keepout
			(tracks not_allowed)
			(vias allowed)
			(pads allowed)
			(copperpour not_allowed)
			(footprints allowed)
		)
		(placement
			(enabled no)
			(sheetname "")
		)
		(fill yes
			(thermal_gap 0.5)
			(thermal_bridge_width 0.5)
			(island_removal_mode 0)
		)
		(polygon
			(pts
				(arc
					(start 217.616278 -120.569736)
					(mid 215.838278 -120.569736)
					(end 217.616278 -120.569736)
				)
			)
		)
	)
	(zone
		(layers "In1.Cu" "In3.Cu" "In6.Cu" "In8.Cu")
		(hatch none 0.5)
		(connect_pads
			(clearance 0)
		)
		(min_thickness 0.25)
		(keepout
			(tracks not_allowed)
			(vias allowed)
			(pads allowed)
			(copperpour not_allowed)
			(footprints allowed)
		)
		(placement
			(enabled no)
			(sheetname "")
		)
		(fill yes
			(thermal_gap 0.5)
			(thermal_bridge_width 0.5)
			(island_removal_mode 0)
		)
		(polygon
			(pts
				(arc
					(start 233.242104 -128.062736)
					(mid 231.464104 -128.062736)
					(end 233.242104 -128.062736)
				)
			)
		)
	)
	(zone
		(layers "In1.Cu" "In3.Cu" "In6.Cu" "In8.Cu")
		(hatch none 0.5)
		(connect_pads
			(clearance 0)
		)
		(min_thickness 0.25)
		(keepout
			(tracks not_allowed)
			(vias allowed)
			(pads allowed)
			(copperpour not_allowed)
			(footprints allowed)
		)
		(placement
			(enabled no)
			(sheetname "")
		)
		(fill yes
			(thermal_gap 0.5)
			(thermal_bridge_width 0.5)
			(island_removal_mode 0)
		)
		(polygon
			(pts
				(arc
					(start 167.259 -52.197)
					(mid 165.481 -52.197)
					(end 167.259 -52.197)
				)
			)
		)
	)
	(zone
		(layers "In1.Cu" "In3.Cu" "In6.Cu" "In8.Cu")
		(hatch none 0.5)
		(connect_pads
			(clearance 0)
		)
		(min_thickness 0.25)
		(keepout
			(tracks not_allowed)
			(vias allowed)
			(pads allowed)
			(copperpour not_allowed)
			(footprints allowed)
		)
		(placement
			(enabled no)
			(sheetname "")
		)
		(fill yes
			(thermal_gap 0.5)
			(thermal_bridge_width 0.5)
			(island_removal_mode 0)
		)
		(polygon
			(pts
				(arc
					(start 56.753506 -131.572)
					(mid 54.975506 -131.572)
					(end 56.753506 -131.572)
				)
			)
		)
	)
	(zone
		(layers "In1.Cu" "In3.Cu" "In6.Cu" "In8.Cu")
		(hatch none 0.5)
		(connect_pads
			(clearance 0)
		)
		(min_thickness 0.25)
		(keepout
			(tracks not_allowed)
			(vias allowed)
			(pads allowed)
			(copperpour not_allowed)
			(footprints allowed)
		)
		(placement
			(enabled no)
			(sheetname "")
		)
		(fill yes
			(thermal_gap 0.5)
			(thermal_bridge_width 0.5)
			(island_removal_mode 0)
		)
		(polygon
			(pts
				(arc
					(start 270.129 -110.744)
					(mid 268.351 -110.744)
					(end 270.129 -110.744)
				)
			)
		)
	)
	(zone
		(layers "In1.Cu" "In3.Cu" "In6.Cu" "In8.Cu")
		(hatch none 0.5)
		(connect_pads
			(clearance 0)
		)
		(min_thickness 0.25)
		(keepout
			(tracks not_allowed)
			(vias allowed)
			(pads allowed)
			(copperpour not_allowed)
			(footprints allowed)
		)
		(placement
			(enabled no)
			(sheetname "")
		)
		(fill yes
			(thermal_gap 0.5)
			(thermal_bridge_width 0.5)
			(island_removal_mode 0)
		)
		(polygon
			(pts
				(arc
					(start 203.917042 -102.9081)
					(mid 202.139042 -102.9081)
					(end 203.917042 -102.9081)
				)
			)
		)
	)
	(zone
		(layers "In1.Cu" "In3.Cu" "In6.Cu" "In8.Cu")
		(hatch none 0.5)
		(connect_pads
			(clearance 0)
		)
		(min_thickness 0.25)
		(keepout
			(tracks not_allowed)
			(vias allowed)
			(pads allowed)
			(copperpour not_allowed)
			(footprints allowed)
		)
		(placement
			(enabled no)
			(sheetname "")
		)
		(fill yes
			(thermal_gap 0.5)
			(thermal_bridge_width 0.5)
			(island_removal_mode 0)
		)
		(polygon
			(pts
				(arc
					(start 214.867236 -132.959856)
					(mid 213.089236 -132.959856)
					(end 214.867236 -132.959856)
				)
			)
		)
	)
	(zone
		(layers "In1.Cu" "In3.Cu" "In6.Cu" "In8.Cu")
		(hatch none 0.5)
		(connect_pads
			(clearance 0)
		)
		(min_thickness 0.25)
		(keepout
			(tracks not_allowed)
			(vias allowed)
			(pads allowed)
			(copperpour not_allowed)
			(footprints allowed)
		)
		(placement
			(enabled no)
			(sheetname "")
		)
		(fill yes
			(thermal_gap 0.5)
			(thermal_bridge_width 0.5)
			(island_removal_mode 0)
		)
		(polygon
			(pts
				(arc
					(start 69.469 -60.96)
					(mid 66.675 -60.96)
					(end 69.469 -60.96)
				)
			)
		)
	)
	(zone
		(layers "In1.Cu" "In3.Cu" "In6.Cu" "In8.Cu")
		(hatch none 0.5)
		(connect_pads
			(clearance 0)
		)
		(min_thickness 0.25)
		(keepout
			(tracks not_allowed)
			(vias allowed)
			(pads allowed)
			(copperpour not_allowed)
			(footprints allowed)
		)
		(placement
			(enabled no)
			(sheetname "")
		)
		(fill yes
			(thermal_gap 0.5)
			(thermal_bridge_width 0.5)
			(island_removal_mode 0)
		)
		(polygon
			(pts
				(arc
					(start 203.23937 -120.569736)
					(mid 201.46137 -120.569736)
					(end 203.23937 -120.569736)
				)
			)
		)
	)
	(zone
		(layers "In1.Cu" "In3.Cu" "In6.Cu" "In8.Cu")
		(hatch none 0.5)
		(connect_pads
			(clearance 0)
		)
		(min_thickness 0.25)
		(keepout
			(tracks not_allowed)
			(vias allowed)
			(pads allowed)
			(copperpour not_allowed)
			(footprints allowed)
		)
		(placement
			(enabled no)
			(sheetname "")
		)
		(fill yes
			(thermal_gap 0.5)
			(thermal_bridge_width 0.5)
			(island_removal_mode 0)
		)
		(polygon
			(pts
				(arc
					(start 217.063828 -127.61214)
					(mid 215.285828 -127.61214)
					(end 217.063828 -127.61214)
				)
			)
		)
	)
	(zone
		(layers "In1.Cu" "In3.Cu" "In6.Cu" "In8.Cu")
		(hatch none 0.5)
		(connect_pads
			(clearance 0)
		)
		(min_thickness 0.25)
		(keepout
			(tracks not_allowed)
			(vias allowed)
			(pads allowed)
			(copperpour not_allowed)
			(footprints allowed)
		)
		(placement
			(enabled no)
			(sheetname "")
		)
		(fill yes
			(thermal_gap 0.5)
			(thermal_bridge_width 0.5)
			(island_removal_mode 0)
		)
		(polygon
			(pts
				(arc
					(start 217.616278 -121.331736)
					(mid 215.838278 -121.331736)
					(end 217.616278 -121.331736)
				)
			)
		)
	)
	(zone
		(layers "In1.Cu" "In3.Cu" "In6.Cu" "In8.Cu")
		(hatch none 0.5)
		(connect_pads
			(clearance 0)
		)
		(min_thickness 0.25)
		(keepout
			(tracks not_allowed)
			(vias allowed)
			(pads allowed)
			(copperpour not_allowed)
			(footprints allowed)
		)
		(placement
			(enabled no)
			(sheetname "")
		)
		(fill yes
			(thermal_gap 0.5)
			(thermal_bridge_width 0.5)
			(island_removal_mode 0)
		)
		(polygon
			(pts
				(arc
					(start 270.891 -111.506)
					(mid 269.113 -111.506)
					(end 270.891 -111.506)
				)
			)
		)
	)
	(zone
		(layers "In1.Cu" "In3.Cu" "In6.Cu" "In8.Cu")
		(hatch none 0.5)
		(connect_pads
			(clearance 0)
		)
		(min_thickness 0.25)
		(keepout
			(tracks not_allowed)
			(vias allowed)
			(pads allowed)
			(copperpour not_allowed)
			(footprints allowed)
		)
		(placement
			(enabled no)
			(sheetname "")
		)
		(fill yes
			(thermal_gap 0.5)
			(thermal_bridge_width 0.5)
			(island_removal_mode 0)
		)
		(polygon
			(pts
				(arc
					(start 232.493566 -126.609094)
					(mid 230.715566 -126.609094)
					(end 232.493566 -126.609094)
				)
			)
		)
	)
	(zone
		(layers "In1.Cu" "In3.Cu" "In6.Cu" "In8.Cu")
		(hatch none 0.5)
		(connect_pads
			(clearance 0)
		)
		(min_thickness 0.25)
		(keepout
			(tracks not_allowed)
			(vias allowed)
			(pads allowed)
			(copperpour not_allowed)
			(footprints allowed)
		)
		(placement
			(enabled no)
			(sheetname "")
		)
		(fill yes
			(thermal_gap 0.5)
			(thermal_bridge_width 0.5)
			(island_removal_mode 0)
		)
		(polygon
			(pts
				(arc
					(start 123.4694 -136.906)
					(mid 120.6246 -136.906)
					(end 123.4694 -136.906)
				)
			)
		)
	)
	(zone
		(layers "In1.Cu" "In3.Cu" "In6.Cu" "In8.Cu")
		(hatch none 0.5)
		(connect_pads
			(clearance 0)
		)
		(min_thickness 0.25)
		(keepout
			(tracks not_allowed)
			(vias allowed)
			(pads allowed)
			(copperpour not_allowed)
			(footprints allowed)
		)
		(placement
			(enabled no)
			(sheetname "")
		)
		(fill yes
			(thermal_gap 0.5)
			(thermal_bridge_width 0.5)
			(island_removal_mode 0)
		)
		(polygon
			(pts
				(arc
					(start 207.727042 -103.6701)
					(mid 205.949042 -103.6701)
					(end 207.727042 -103.6701)
				)
			)
		)
	)
	(zone
		(layers "In1.Cu" "In3.Cu" "In6.Cu" "In8.Cu")
		(hatch none 0.5)
		(connect_pads
			(clearance 0)
		)
		(min_thickness 0.25)
		(keepout
			(tracks not_allowed)
			(vias allowed)
			(pads allowed)
			(copperpour not_allowed)
			(footprints allowed)
		)
		(placement
			(enabled no)
			(sheetname "")
		)
		(fill yes
			(thermal_gap 0.5)
			(thermal_bridge_width 0.5)
			(island_removal_mode 0)
		)
		(polygon
			(pts
				(arc
					(start 92.075 -60.96)
					(mid 89.281 -60.96)
					(end 92.075 -60.96)
				)
			)
		)
	)
	(zone
		(layers "In1.Cu" "In3.Cu" "In6.Cu" "In8.Cu")
		(hatch none 0.5)
		(connect_pads
			(clearance 0)
		)
		(min_thickness 0.25)
		(keepout
			(tracks not_allowed)
			(vias allowed)
			(pads allowed)
			(copperpour not_allowed)
			(footprints allowed)
		)
		(placement
			(enabled no)
			(sheetname "")
		)
		(fill yes
			(thermal_gap 0.5)
			(thermal_bridge_width 0.5)
			(island_removal_mode 0)
		)
		(polygon
			(pts
				(arc
					(start 270.891 -88.138)
					(mid 269.113 -88.138)
					(end 270.891 -88.138)
				)
			)
		)
	)
	(zone
		(layers "In1.Cu" "In3.Cu" "In6.Cu" "In8.Cu")
		(hatch none 0.5)
		(connect_pads
			(clearance 0)
		)
		(min_thickness 0.25)
		(keepout
			(tracks not_allowed)
			(vias allowed)
			(pads allowed)
			(copperpour not_allowed)
			(footprints allowed)
		)
		(placement
			(enabled no)
			(sheetname "")
		)
		(fill yes
			(thermal_gap 0.5)
			(thermal_bridge_width 0.5)
			(island_removal_mode 0)
		)
		(polygon
			(pts
				(arc
					(start 207.04937 -122.047762)
					(mid 205.27137 -122.047762)
					(end 207.04937 -122.047762)
				)
			)
		)
	)
	(zone
		(layers "In1.Cu" "In3.Cu" "In6.Cu" "In8.Cu")
		(hatch none 0.5)
		(connect_pads
			(clearance 0)
		)
		(min_thickness 0.25)
		(keepout
			(tracks not_allowed)
			(vias allowed)
			(pads allowed)
			(copperpour not_allowed)
			(footprints allowed)
		)
		(placement
			(enabled no)
			(sheetname "")
		)
		(fill yes
			(thermal_gap 0.5)
			(thermal_bridge_width 0.5)
			(island_removal_mode 0)
		)
		(polygon
			(pts
				(arc
					(start 273.177 -88.9)
					(mid 271.399 -88.9)
					(end 273.177 -88.9)
				)
			)
		)
	)
	(zone
		(layers "In1.Cu" "In3.Cu" "In6.Cu" "In8.Cu")
		(hatch none 0.5)
		(connect_pads
			(clearance 0)
		)
		(min_thickness 0.25)
		(keepout
			(tracks not_allowed)
			(vias allowed)
			(pads allowed)
			(copperpour not_allowed)
			(footprints allowed)
		)
		(placement
			(enabled no)
			(sheetname "")
		)
		(fill yes
			(thermal_gap 0.5)
			(thermal_bridge_width 0.5)
			(island_removal_mode 0)
		)
		(polygon
			(pts
				(arc
					(start 221.426278 -121.331736)
					(mid 219.648278 -121.331736)
					(end 221.426278 -121.331736)
				)
			)
		)
	)
	(zone
		(layers "In1.Cu" "In3.Cu" "In6.Cu" "In8.Cu")
		(hatch none 0.5)
		(connect_pads
			(clearance 0)
		)
		(min_thickness 0.25)
		(keepout
			(tracks not_allowed)
			(vias allowed)
			(pads allowed)
			(copperpour not_allowed)
			(footprints allowed)
		)
		(placement
			(enabled no)
			(sheetname "")
		)
		(fill yes
			(thermal_gap 0.5)
			(thermal_bridge_width 0.5)
			(island_removal_mode 0)
		)
		(polygon
			(pts
				(arc
					(start 220.664278 -122.809762)
					(mid 218.886278 -122.809762)
					(end 220.664278 -122.809762)
				)
			)
		)
	)
	(zone
		(layers "In1.Cu" "In3.Cu" "In6.Cu" "In8.Cu")
		(hatch none 0.5)
		(connect_pads
			(clearance 0)
		)
		(min_thickness 0.25)
		(keepout
			(tracks not_allowed)
			(vias allowed)
			(pads allowed)
			(copperpour not_allowed)
			(footprints allowed)
		)
		(placement
			(enabled no)
			(sheetname "")
		)
		(fill yes
			(thermal_gap 0.5)
			(thermal_bridge_width 0.5)
			(island_removal_mode 0)
		)
		(polygon
			(pts
				(arc
					(start 273.177 -85.852)
					(mid 271.399 -85.852)
					(end 273.177 -85.852)
				)
			)
		)
	)
	(zone
		(layers "In1.Cu" "In3.Cu" "In6.Cu" "In8.Cu")
		(hatch none 0.5)
		(connect_pads
			(clearance 0)
		)
		(min_thickness 0.25)
		(keepout
			(tracks not_allowed)
			(vias allowed)
			(pads allowed)
			(copperpour not_allowed)
			(footprints allowed)
		)
		(placement
			(enabled no)
			(sheetname "")
		)
		(fill yes
			(thermal_gap 0.5)
			(thermal_bridge_width 0.5)
			(island_removal_mode 0)
		)
		(polygon
			(pts
				(arc
					(start 205.52537 -122.809762)
					(mid 203.74737 -122.809762)
					(end 205.52537 -122.809762)
				)
			)
		)
	)
	(zone
		(layers "In1.Cu" "In3.Cu" "In6.Cu" "In8.Cu")
		(hatch none 0.5)
		(connect_pads
			(clearance 0)
		)
		(min_thickness 0.25)
		(keepout
			(tracks not_allowed)
			(vias allowed)
			(pads allowed)
			(copperpour not_allowed)
			(footprints allowed)
		)
		(placement
			(enabled no)
			(sheetname "")
		)
		(fill yes
			(thermal_gap 0.5)
			(thermal_bridge_width 0.5)
			(island_removal_mode 0)
		)
		(polygon
			(pts
				(arc
					(start 273.177 -125.095)
					(mid 271.399 -125.095)
					(end 273.177 -125.095)
				)
			)
		)
	)
	(zone
		(layers "In1.Cu" "In3.Cu" "In6.Cu" "In8.Cu")
		(hatch none 0.5)
		(connect_pads
			(clearance 0)
		)
		(min_thickness 0.25)
		(keepout
			(tracks not_allowed)
			(vias allowed)
			(pads allowed)
			(copperpour not_allowed)
			(footprints allowed)
		)
		(placement
			(enabled no)
			(sheetname "")
		)
		(fill yes
			(thermal_gap 0.5)
			(thermal_bridge_width 0.5)
			(island_removal_mode 0)
		)
		(polygon
			(pts
				(arc
					(start 275.315172 -94.8944)
					(mid 273.537172 -94.8944)
					(end 275.315172 -94.8944)
				)
			)
		)
	)
	(zone
		(layers "In1.Cu" "In3.Cu" "In6.Cu" "In8.Cu")
		(hatch none 0.5)
		(connect_pads
			(clearance 0)
		)
		(min_thickness 0.25)
		(keepout
			(tracks not_allowed)
			(vias allowed)
			(pads allowed)
			(copperpour not_allowed)
			(footprints allowed)
		)
		(placement
			(enabled no)
			(sheetname "")
		)
		(fill yes
			(thermal_gap 0.5)
			(thermal_bridge_width 0.5)
			(island_removal_mode 0)
		)
		(polygon
			(pts
				(arc
					(start 96.753426 -131.572)
					(mid 94.975426 -131.572)
					(end 96.753426 -131.572)
				)
			)
		)
	)
	(zone
		(layers "In1.Cu" "In3.Cu" "In6.Cu" "In8.Cu")
		(hatch none 0.5)
		(connect_pads
			(clearance 0)
		)
		(min_thickness 0.25)
		(keepout
			(tracks not_allowed)
			(vias allowed)
			(pads allowed)
			(copperpour not_allowed)
			(footprints allowed)
		)
		(placement
			(enabled no)
			(sheetname "")
		)
		(fill yes
			(thermal_gap 0.5)
			(thermal_bridge_width 0.5)
			(island_removal_mode 0)
		)
		(polygon
			(pts
				(arc
					(start 207.727042 -105.896664)
					(mid 205.949042 -105.896664)
					(end 207.727042 -105.896664)
				)
			)
		)
	)
	(zone
		(layers "In1.Cu" "In3.Cu" "In6.Cu" "In8.Cu")
		(hatch none 0.5)
		(connect_pads
			(clearance 0)
		)
		(min_thickness 0.25)
		(keepout
			(tracks not_allowed)
			(vias allowed)
			(pads allowed)
			(copperpour not_allowed)
			(footprints allowed)
		)
		(placement
			(enabled no)
			(sheetname "")
		)
		(fill yes
			(thermal_gap 0.5)
			(thermal_bridge_width 0.5)
			(island_removal_mode 0)
		)
		(polygon
			(pts
				(arc
					(start 227.734114 -97.985834)
					(mid 225.956114 -97.985834)
					(end 227.734114 -97.985834)
				)
			)
		)
	)
	(zone
		(layers "In1.Cu" "In3.Cu" "In6.Cu" "In8.Cu")
		(hatch none 0.5)
		(connect_pads
			(clearance 0)
		)
		(min_thickness 0.25)
		(keepout
			(tracks not_allowed)
			(vias allowed)
			(pads allowed)
			(copperpour not_allowed)
			(footprints allowed)
		)
		(placement
			(enabled no)
			(sheetname "")
		)
		(fill yes
			(thermal_gap 0.5)
			(thermal_bridge_width 0.5)
			(island_removal_mode 0)
		)
		(polygon
			(pts
				(arc
					(start 271.653 -64.77)
					(mid 269.875 -64.77)
					(end 271.653 -64.77)
				)
			)
		)
	)
	(zone
		(layers "In1.Cu" "In3.Cu" "In6.Cu" "In8.Cu")
		(hatch none 0.5)
		(connect_pads
			(clearance 0)
		)
		(min_thickness 0.25)
		(keepout
			(tracks not_allowed)
			(vias allowed)
			(pads allowed)
			(copperpour not_allowed)
			(footprints allowed)
		)
		(placement
			(enabled no)
			(sheetname "")
		)
		(fill yes
			(thermal_gap 0.5)
			(thermal_bridge_width 0.5)
			(island_removal_mode 0)
		)
		(polygon
			(pts
				(arc
					(start 233.242104 -131.110736)
					(mid 231.464104 -131.110736)
					(end 233.242104 -131.110736)
				)
			)
		)
	)
	(zone
		(layers "In1.Cu" "In3.Cu" "In6.Cu" "In8.Cu")
		(hatch none 0.5)
		(connect_pads
			(clearance 0)
		)
		(min_thickness 0.25)
		(keepout
			(tracks not_allowed)
			(vias allowed)
			(pads allowed)
			(copperpour not_allowed)
			(footprints allowed)
		)
		(placement
			(enabled no)
			(sheetname "")
		)
		(fill yes
			(thermal_gap 0.5)
			(thermal_bridge_width 0.5)
			(island_removal_mode 0)
		)
		(polygon
			(pts
				(arc
					(start 83.693 -52.324)
					(mid 81.915 -52.324)
					(end 83.693 -52.324)
				)
			)
		)
	)
	(zone
		(layers "In1.Cu" "In3.Cu" "In6.Cu" "In8.Cu")
		(hatch none 0.5)
		(connect_pads
			(clearance 0)
		)
		(min_thickness 0.25)
		(keepout
			(tracks not_allowed)
			(vias allowed)
			(pads allowed)
			(copperpour not_allowed)
			(footprints allowed)
		)
		(placement
			(enabled no)
			(sheetname "")
		)
		(fill yes
			(thermal_gap 0.5)
			(thermal_bridge_width 0.5)
			(island_removal_mode 0)
		)
		(polygon
			(pts
				(arc
					(start 271.653 -125.857)
					(mid 269.875 -125.857)
					(end 271.653 -125.857)
				)
			)
		)
	)
	(zone
		(layers "In1.Cu" "In3.Cu" "In6.Cu" "In8.Cu")
		(hatch none 0.5)
		(connect_pads
			(clearance 0)
		)
		(min_thickness 0.25)
		(keepout
			(tracks not_allowed)
			(vias allowed)
			(pads allowed)
			(copperpour not_allowed)
			(footprints allowed)
		)
		(placement
			(enabled no)
			(sheetname "")
		)
		(fill yes
			(thermal_gap 0.5)
			(thermal_bridge_width 0.5)
			(island_removal_mode 0)
		)
		(polygon
			(pts
				(arc
					(start 32.131 -106.807)
					(mid 30.353 -106.807)
					(end 32.131 -106.807)
				)
			)
		)
	)
	(zone
		(layers "In1.Cu" "In3.Cu" "In6.Cu" "In8.Cu")
		(hatch none 0.5)
		(connect_pads
			(clearance 0)
		)
		(min_thickness 0.25)
		(keepout
			(tracks not_allowed)
			(vias allowed)
			(pads allowed)
			(copperpour not_allowed)
			(footprints allowed)
		)
		(placement
			(enabled no)
			(sheetname "")
		)
		(fill yes
			(thermal_gap 0.5)
			(thermal_bridge_width 0.5)
			(island_removal_mode 0)
		)
		(polygon
			(pts
				(arc
					(start 233.255566 -126.609094)
					(mid 231.477566 -126.609094)
					(end 233.255566 -126.609094)
				)
			)
		)
	)
	(zone
		(layers "In1.Cu" "In3.Cu" "In6.Cu" "In8.Cu")
		(hatch none 0.5)
		(connect_pads
			(clearance 0)
		)
		(min_thickness 0.25)
		(keepout
			(tracks not_allowed)
			(vias allowed)
			(pads allowed)
			(copperpour not_allowed)
			(footprints allowed)
		)
		(placement
			(enabled no)
			(sheetname "")
		)
		(fill yes
			(thermal_gap 0.5)
			(thermal_bridge_width 0.5)
			(island_removal_mode 0)
		)
		(polygon
			(pts
				(arc
					(start 219.139262 -98.013012)
					(mid 217.361262 -98.013012)
					(end 219.139262 -98.013012)
				)
			)
		)
	)
	(zone
		(layers "In1.Cu" "In3.Cu" "In6.Cu" "In8.Cu")
		(hatch none 0.5)
		(connect_pads
			(clearance 0)
		)
		(min_thickness 0.25)
		(keepout
			(tracks not_allowed)
			(vias allowed)
			(pads allowed)
			(copperpour not_allowed)
			(footprints allowed)
		)
		(placement
			(enabled no)
			(sheetname "")
		)
		(fill yes
			(thermal_gap 0.5)
			(thermal_bridge_width 0.5)
			(island_removal_mode 0)
		)
		(polygon
			(pts
				(arc
					(start 206.301086 -123.528328)
					(mid 204.523086 -123.528328)
					(end 206.301086 -123.528328)
				)
			)
		)
	)
	(zone
		(layers "In1.Cu" "In3.Cu" "In6.Cu" "In8.Cu")
		(hatch none 0.5)
		(connect_pads
			(clearance 0)
		)
		(min_thickness 0.25)
		(keepout
			(tracks not_allowed)
			(vias allowed)
			(pads allowed)
			(copperpour not_allowed)
			(footprints allowed)
		)
		(placement
			(enabled no)
			(sheetname "")
		)
		(fill yes
			(thermal_gap 0.5)
			(thermal_bridge_width 0.5)
			(island_removal_mode 0)
		)
		(polygon
			(pts
				(arc
					(start 95.991426 -131.572)
					(mid 94.213426 -131.572)
					(end 95.991426 -131.572)
				)
			)
		)
	)
	(zone
		(layers "In1.Cu" "In3.Cu" "In6.Cu" "In8.Cu")
		(hatch none 0.5)
		(connect_pads
			(clearance 0)
		)
		(min_thickness 0.25)
		(keepout
			(tracks not_allowed)
			(vias allowed)
			(pads allowed)
			(copperpour not_allowed)
			(footprints allowed)
		)
		(placement
			(enabled no)
			(sheetname "")
		)
		(fill yes
			(thermal_gap 0.5)
			(thermal_bridge_width 0.5)
			(island_removal_mode 0)
		)
		(polygon
			(pts
				(arc
					(start 11.22172 -69.239892)
					(mid 8.47852 -69.239892)
					(end 11.22172 -69.239892)
				)
			)
		)
	)
	(zone
		(layers "In1.Cu" "In3.Cu" "In6.Cu" "In8.Cu")
		(hatch none 0.5)
		(connect_pads
			(clearance 0)
		)
		(min_thickness 0.25)
		(keepout
			(tracks not_allowed)
			(vias allowed)
			(pads allowed)
			(copperpour not_allowed)
			(footprints allowed)
		)
		(placement
			(enabled no)
			(sheetname "")
		)
		(fill yes
			(thermal_gap 0.5)
			(thermal_bridge_width 0.5)
			(island_removal_mode 0)
		)
		(polygon
			(pts
				(arc
					(start 235.482384 -131.829556)
					(mid 233.704384 -131.829556)
					(end 235.482384 -131.829556)
				)
			)
		)
	)
	(zone
		(layers "In1.Cu" "In3.Cu" "In6.Cu" "In8.Cu")
		(hatch none 0.5)
		(connect_pads
			(clearance 0)
		)
		(min_thickness 0.25)
		(keepout
			(tracks not_allowed)
			(vias allowed)
			(pads allowed)
			(copperpour not_allowed)
			(footprints allowed)
		)
		(placement
			(enabled no)
			(sheetname "")
		)
		(fill yes
			(thermal_gap 0.5)
			(thermal_bridge_width 0.5)
			(island_removal_mode 0)
		)
		(polygon
			(pts
				(arc
					(start 272.415 -88.9)
					(mid 270.637 -88.9)
					(end 272.415 -88.9)
				)
			)
		)
	)
	(zone
		(layers "In1.Cu" "In3.Cu" "In6.Cu" "In8.Cu")
		(hatch none 0.5)
		(connect_pads
			(clearance 0)
		)
		(min_thickness 0.25)
		(keepout
			(tracks not_allowed)
			(vias allowed)
			(pads allowed)
			(copperpour not_allowed)
			(footprints allowed)
		)
		(placement
			(enabled no)
			(sheetname "")
		)
		(fill yes
			(thermal_gap 0.5)
			(thermal_bridge_width 0.5)
			(island_removal_mode 0)
		)
		(polygon
			(pts
				(arc
					(start 207.825086 -123.528328)
					(mid 206.047086 -123.528328)
					(end 207.825086 -123.528328)
				)
			)
		)
	)
	(zone
		(layers "In1.Cu" "In3.Cu" "In6.Cu" "In8.Cu")
		(hatch none 0.5)
		(connect_pads
			(clearance 0)
		)
		(min_thickness 0.25)
		(keepout
			(tracks not_allowed)
			(vias allowed)
			(pads allowed)
			(copperpour not_allowed)
			(footprints allowed)
		)
		(placement
			(enabled no)
			(sheetname "")
		)
		(fill yes
			(thermal_gap 0.5)
			(thermal_bridge_width 0.5)
			(island_removal_mode 0)
		)
		(polygon
			(pts
				(arc
					(start 270.5354 -70.165468)
					(mid 268.7574 -70.165468)
					(end 270.5354 -70.165468)
				)
			)
		)
	)
	(zone
		(layers "In1.Cu" "In3.Cu" "In6.Cu" "In8.Cu")
		(hatch none 0.5)
		(connect_pads
			(clearance 0)
		)
		(min_thickness 0.25)
		(keepout
			(tracks not_allowed)
			(vias allowed)
			(pads allowed)
			(copperpour not_allowed)
			(footprints allowed)
		)
		(placement
			(enabled no)
			(sheetname "")
		)
		(fill yes
			(thermal_gap 0.5)
			(thermal_bridge_width 0.5)
			(island_removal_mode 0)
		)
		(polygon
			(pts
				(arc
					(start 230.419148 -98.012758)
					(mid 228.641148 -98.012758)
					(end 230.419148 -98.012758)
				)
			)
		)
	)
	(zone
		(layers "In1.Cu" "In3.Cu" "In6.Cu" "In8.Cu")
		(hatch none 0.5)
		(connect_pads
			(clearance 0)
		)
		(min_thickness 0.25)
		(keepout
			(tracks not_allowed)
			(vias allowed)
			(pads allowed)
			(copperpour not_allowed)
			(footprints allowed)
		)
		(placement
			(enabled no)
			(sheetname "")
		)
		(fill yes
			(thermal_gap 0.5)
			(thermal_bridge_width 0.5)
			(island_removal_mode 0)
		)
		(polygon
			(pts
				(arc
					(start 32.131 -103.759)
					(mid 30.353 -103.759)
					(end 32.131 -103.759)
				)
			)
		)
	)
	(zone
		(layers "In1.Cu" "In3.Cu" "In6.Cu" "In8.Cu")
		(hatch none 0.5)
		(connect_pads
			(clearance 0)
		)
		(min_thickness 0.25)
		(keepout
			(tracks not_allowed)
			(vias allowed)
			(pads allowed)
			(copperpour not_allowed)
			(footprints allowed)
		)
		(placement
			(enabled no)
			(sheetname "")
		)
		(fill yes
			(thermal_gap 0.5)
			(thermal_bridge_width 0.5)
			(island_removal_mode 0)
		)
		(polygon
			(pts
				(arc
					(start 297.4594 -46.863)
					(mid 295.6814 -46.863)
					(end 297.4594 -46.863)
				)
			)
		)
	)
	(zone
		(layers "In1.Cu" "In3.Cu" "In6.Cu" "In8.Cu")
		(hatch none 0.5)
		(connect_pads
			(clearance 0)
		)
		(min_thickness 0.25)
		(keepout
			(tracks not_allowed)
			(vias allowed)
			(pads allowed)
			(copperpour not_allowed)
			(footprints allowed)
		)
		(placement
			(enabled no)
			(sheetname "")
		)
		(fill yes
			(thermal_gap 0.5)
			(thermal_bridge_width 0.5)
			(island_removal_mode 0)
		)
		(polygon
			(pts
				(arc
					(start 72.318626 -71.901812)
					(mid 70.540626 -71.901812)
					(end 72.318626 -71.901812)
				)
			)
		)
	)
	(zone
		(layers "In1.Cu" "In3.Cu" "In6.Cu" "In8.Cu")
		(hatch none 0.5)
		(connect_pads
			(clearance 0)
		)
		(min_thickness 0.25)
		(keepout
			(tracks not_allowed)
			(vias allowed)
			(pads allowed)
			(copperpour not_allowed)
			(footprints allowed)
		)
		(placement
			(enabled no)
			(sheetname "")
		)
		(fill yes
			(thermal_gap 0.5)
			(thermal_bridge_width 0.5)
			(island_removal_mode 0)
		)
		(polygon
			(pts
				(arc
					(start 205.539086 -123.528328)
					(mid 203.761086 -123.528328)
					(end 205.539086 -123.528328)
				)
			)
		)
	)
	(zone
		(layers "In1.Cu" "In3.Cu" "In6.Cu" "In8.Cu")
		(hatch none 0.5)
		(connect_pads
			(clearance 0)
		)
		(min_thickness 0.25)
		(keepout
			(tracks not_allowed)
			(vias allowed)
			(pads allowed)
			(copperpour not_allowed)
			(footprints allowed)
		)
		(placement
			(enabled no)
			(sheetname "")
		)
		(fill yes
			(thermal_gap 0.5)
			(thermal_bridge_width 0.5)
			(island_removal_mode 0)
		)
		(polygon
			(pts
				(arc
					(start 216.347802 -132.18414)
					(mid 214.569802 -132.18414)
					(end 216.347802 -132.18414)
				)
			)
		)
	)
	(zone
		(layers "In1.Cu" "In3.Cu" "In6.Cu" "In8.Cu")
		(hatch none 0.5)
		(connect_pads
			(clearance 0)
		)
		(min_thickness 0.25)
		(keepout
			(tracks not_allowed)
			(vias allowed)
			(pads allowed)
			(copperpour not_allowed)
			(footprints allowed)
		)
		(placement
			(enabled no)
			(sheetname "")
		)
		(fill yes
			(thermal_gap 0.5)
			(thermal_bridge_width 0.5)
			(island_removal_mode 0)
		)
		(polygon
			(pts
				(arc
					(start 175.661574 -136.906)
					(mid 172.816774 -136.906)
					(end 175.661574 -136.906)
				)
			)
		)
	)
	(zone
		(layers "In1.Cu" "In3.Cu" "In6.Cu" "In8.Cu")
		(hatch none 0.5)
		(connect_pads
			(clearance 0)
		)
		(min_thickness 0.25)
		(keepout
			(tracks not_allowed)
			(vias allowed)
			(pads allowed)
			(copperpour not_allowed)
			(footprints allowed)
		)
		(placement
			(enabled no)
			(sheetname "")
		)
		(fill yes
			(thermal_gap 0.5)
			(thermal_bridge_width 0.5)
			(island_removal_mode 0)
		)
		(polygon
			(pts
				(arc
					(start 216.347802 -128.37414)
					(mid 214.569802 -128.37414)
					(end 216.347802 -128.37414)
				)
			)
		)
	)
	(zone
		(layers "In1.Cu" "In3.Cu" "In6.Cu" "In8.Cu")
		(hatch none 0.5)
		(connect_pads
			(clearance 0)
		)
		(min_thickness 0.25)
		(keepout
			(tracks not_allowed)
			(vias allowed)
			(pads allowed)
			(copperpour not_allowed)
			(footprints allowed)
		)
		(placement
			(enabled no)
			(sheetname "")
		)
		(fill yes
			(thermal_gap 0.5)
			(thermal_bridge_width 0.5)
			(island_removal_mode 0)
		)
		(polygon
			(pts
				(arc
					(start 226.244912 -97.985834)
					(mid 224.466912 -97.985834)
					(end 226.244912 -97.985834)
				)
			)
		)
	)
	(zone
		(layers "In1.Cu" "In3.Cu" "In6.Cu" "In8.Cu")
		(hatch none 0.5)
		(connect_pads
			(clearance 0)
		)
		(min_thickness 0.25)
		(keepout
			(tracks not_allowed)
			(vias allowed)
			(pads allowed)
			(copperpour not_allowed)
			(footprints allowed)
		)
		(placement
			(enabled no)
			(sheetname "")
		)
		(fill yes
			(thermal_gap 0.5)
			(thermal_bridge_width 0.5)
			(island_removal_mode 0)
		)
		(polygon
			(pts
				(arc
					(start 188.945774 -131.572)
					(mid 187.167774 -131.572)
					(end 188.945774 -131.572)
				)
			)
		)
	)
	(zone
		(layers "In1.Cu" "In3.Cu" "In6.Cu" "In8.Cu")
		(hatch none 0.5)
		(connect_pads
			(clearance 0)
		)
		(min_thickness 0.25)
		(keepout
			(tracks not_allowed)
			(vias allowed)
			(pads allowed)
			(copperpour not_allowed)
			(footprints allowed)
		)
		(placement
			(enabled no)
			(sheetname "")
		)
		(fill yes
			(thermal_gap 0.5)
			(thermal_bridge_width 0.5)
			(island_removal_mode 0)
		)
		(polygon
			(pts
				(arc
					(start 203.917042 -105.134664)
					(mid 202.139042 -105.134664)
					(end 203.917042 -105.134664)
				)
			)
		)
	)
	(zone
		(layers "In1.Cu" "In3.Cu" "In6.Cu" "In8.Cu")
		(hatch none 0.5)
		(connect_pads
			(clearance 0)
		)
		(min_thickness 0.25)
		(keepout
			(tracks not_allowed)
			(vias allowed)
			(pads allowed)
			(copperpour not_allowed)
			(footprints allowed)
		)
		(placement
			(enabled no)
			(sheetname "")
		)
		(fill yes
			(thermal_gap 0.5)
			(thermal_bridge_width 0.5)
			(island_removal_mode 0)
		)
		(polygon
			(pts
				(arc
					(start 233.242104 -127.300736)
					(mid 231.464104 -127.300736)
					(end 233.242104 -127.300736)
				)
			)
		)
	)
	(zone
		(layers "In1.Cu" "In3.Cu" "In6.Cu" "In8.Cu")
		(hatch none 0.5)
		(connect_pads
			(clearance 0)
		)
		(min_thickness 0.25)
		(keepout
			(tracks not_allowed)
			(vias allowed)
			(pads allowed)
			(copperpour not_allowed)
			(footprints allowed)
		)
		(placement
			(enabled no)
			(sheetname "")
		)
		(fill yes
			(thermal_gap 0.5)
			(thermal_bridge_width 0.5)
			(island_removal_mode 0)
		)
		(polygon
			(pts
				(arc
					(start 188.183774 -131.572)
					(mid 186.405774 -131.572)
					(end 188.183774 -131.572)
				)
			)
		)
	)
	(zone
		(layers "In1.Cu" "In3.Cu" "In6.Cu" "In8.Cu")
		(hatch none 0.5)
		(connect_pads
			(clearance 0)
		)
		(min_thickness 0.25)
		(keepout
			(tracks not_allowed)
			(vias allowed)
			(pads allowed)
			(copperpour not_allowed)
			(footprints allowed)
		)
		(placement
			(enabled no)
			(sheetname "")
		)
		(fill yes
			(thermal_gap 0.5)
			(thermal_bridge_width 0.5)
			(island_removal_mode 0)
		)
		(polygon
			(pts
				(arc
					(start 217.629994 -123.528328)
					(mid 215.851994 -123.528328)
					(end 217.629994 -123.528328)
				)
			)
		)
	)
	(zone
		(layers "In1.Cu" "In3.Cu" "In6.Cu" "In8.Cu")
		(hatch none 0.5)
		(connect_pads
			(clearance 0)
		)
		(min_thickness 0.25)
		(keepout
			(tracks not_allowed)
			(vias allowed)
			(pads allowed)
			(copperpour not_allowed)
			(footprints allowed)
		)
		(placement
			(enabled no)
			(sheetname "")
		)
		(fill yes
			(thermal_gap 0.5)
			(thermal_bridge_width 0.5)
			(island_removal_mode 0)
		)
		(polygon
			(pts
				(arc
					(start 217.708226 -105.121202)
					(mid 215.930226 -105.121202)
					(end 217.708226 -105.121202)
				)
			)
		)
	)
	(zone
		(layers "In1.Cu" "In3.Cu" "In6.Cu" "In8.Cu")
		(hatch none 0.5)
		(connect_pads
			(clearance 0)
		)
		(min_thickness 0.25)
		(keepout
			(tracks not_allowed)
			(vias allowed)
			(pads allowed)
			(copperpour not_allowed)
			(footprints allowed)
		)
		(placement
			(enabled no)
			(sheetname "")
		)
		(fill yes
			(thermal_gap 0.5)
			(thermal_bridge_width 0.5)
			(island_removal_mode 0)
		)
		(polygon
			(pts
				(arc
					(start 232.67035 -98.012758)
					(mid 230.89235 -98.012758)
					(end 232.67035 -98.012758)
				)
			)
		)
	)
	(zone
		(layers "In1.Cu" "In3.Cu" "In6.Cu" "In8.Cu")
		(hatch none 0.5)
		(connect_pads
			(clearance 0)
		)
		(min_thickness 0.25)
		(keepout
			(tracks not_allowed)
			(vias allowed)
			(pads allowed)
			(copperpour not_allowed)
			(footprints allowed)
		)
		(placement
			(enabled no)
			(sheetname "")
		)
		(fill yes
			(thermal_gap 0.5)
			(thermal_bridge_width 0.5)
			(island_removal_mode 0)
		)
		(polygon
			(pts
				(arc
					(start 221.498668 -97.985834)
					(mid 219.720668 -97.985834)
					(end 221.498668 -97.985834)
				)
			)
		)
	)
	(zone
		(layers "In1.Cu" "In3.Cu" "In6.Cu" "In8.Cu")
		(hatch none 0.5)
		(connect_pads
			(clearance 0)
		)
		(min_thickness 0.25)
		(keepout
			(tracks not_allowed)
			(vias allowed)
			(pads allowed)
			(copperpour not_allowed)
			(footprints allowed)
		)
		(placement
			(enabled no)
			(sheetname "")
		)
		(fill yes
			(thermal_gap 0.5)
			(thermal_bridge_width 0.5)
			(island_removal_mode 0)
		)
		(polygon
			(pts
				(arc
					(start 222.188278 -120.569736)
					(mid 220.410278 -120.569736)
					(end 222.188278 -120.569736)
				)
			)
		)
	)
	(zone
		(layers "In1.Cu" "In3.Cu" "In6.Cu" "In8.Cu")
		(hatch none 0.5)
		(connect_pads
			(clearance 0)
		)
		(min_thickness 0.25)
		(keepout
			(tracks not_allowed)
			(vias allowed)
			(pads allowed)
			(copperpour not_allowed)
			(footprints allowed)
		)
		(placement
			(enabled no)
			(sheetname "")
		)
		(fill yes
			(thermal_gap 0.5)
			(thermal_bridge_width 0.5)
			(island_removal_mode 0)
		)
		(polygon
			(pts
				(arc
					(start 239.965738 -98.012758)
					(mid 238.187738 -98.012758)
					(end 239.965738 -98.012758)
				)
			)
		)
	)
	(zone
		(layers "In1.Cu" "In3.Cu" "In6.Cu" "In8.Cu")
		(hatch none 0.5)
		(connect_pads
			(clearance 0)
		)
		(min_thickness 0.25)
		(keepout
			(tracks not_allowed)
			(vias allowed)
			(pads allowed)
			(copperpour not_allowed)
			(footprints allowed)
		)
		(placement
			(enabled no)
			(sheetname "")
		)
		(fill yes
			(thermal_gap 0.5)
			(thermal_bridge_width 0.5)
			(island_removal_mode 0)
		)
		(polygon
			(pts
				(arc
					(start 270.129 -64.008)
					(mid 268.351 -64.008)
					(end 270.129 -64.008)
				)
			)
		)
	)
	(zone
		(layers "In1.Cu" "In3.Cu" "In6.Cu" "In8.Cu")
		(hatch none 0.5)
		(connect_pads
			(clearance 0)
		)
		(min_thickness 0.25)
		(keepout
			(tracks not_allowed)
			(vias allowed)
			(pads allowed)
			(copperpour not_allowed)
			(footprints allowed)
		)
		(placement
			(enabled no)
			(sheetname "")
		)
		(fill yes
			(thermal_gap 0.5)
			(thermal_bridge_width 0.5)
			(island_removal_mode 0)
		)
		(polygon
			(pts
				(arc
					(start 188.183774 -126.492)
					(mid 186.405774 -126.492)
					(end 188.183774 -126.492)
				)
			)
		)
	)
	(zone
		(layers "In1.Cu" "In3.Cu" "In6.Cu" "In8.Cu")
		(hatch none 0.5)
		(connect_pads
			(clearance 0)
		)
		(min_thickness 0.25)
		(keepout
			(tracks not_allowed)
			(vias allowed)
			(pads allowed)
			(copperpour not_allowed)
			(footprints allowed)
		)
		(placement
			(enabled no)
			(sheetname "")
		)
		(fill yes
			(thermal_gap 0.5)
			(thermal_bridge_width 0.5)
			(island_removal_mode 0)
		)
		(polygon
			(pts
				(arc
					(start 272.079466 -80.757268)
					(mid 270.301466 -80.757268)
					(end 272.079466 -80.757268)
				)
			)
		)
	)
	(zone
		(layers "In1.Cu" "In3.Cu" "In6.Cu" "In8.Cu")
		(hatch none 0.5)
		(connect_pads
			(clearance 0)
		)
		(min_thickness 0.25)
		(keepout
			(tracks not_allowed)
			(vias allowed)
			(pads allowed)
			(copperpour not_allowed)
			(footprints allowed)
		)
		(placement
			(enabled no)
			(sheetname "")
		)
		(fill yes
			(thermal_gap 0.5)
			(thermal_bridge_width 0.5)
			(island_removal_mode 0)
		)
		(polygon
			(pts
				(arc
					(start 273.177 -98.679)
					(mid 271.399 -98.679)
					(end 273.177 -98.679)
				)
			)
		)
	)
	(zone
		(layers "In1.Cu" "In3.Cu" "In6.Cu" "In8.Cu")
		(hatch none 0.5)
		(connect_pads
			(clearance 0)
		)
		(min_thickness 0.25)
		(keepout
			(tracks not_allowed)
			(vias allowed)
			(pads allowed)
			(copperpour not_allowed)
			(footprints allowed)
		)
		(placement
			(enabled no)
			(sheetname "")
		)
		(fill yes
			(thermal_gap 0.5)
			(thermal_bridge_width 0.5)
			(island_removal_mode 0)
		)
		(polygon
			(pts
				(arc
					(start 273.177 -74.549)
					(mid 271.399 -74.549)
					(end 273.177 -74.549)
				)
			)
		)
	)
	(zone
		(layers "In1.Cu" "In3.Cu" "In6.Cu" "In8.Cu")
		(hatch none 0.5)
		(connect_pads
			(clearance 0)
		)
		(min_thickness 0.25)
		(keepout
			(tracks not_allowed)
			(vias allowed)
			(pads allowed)
			(copperpour not_allowed)
			(footprints allowed)
		)
		(placement
			(enabled no)
			(sheetname "")
		)
		(fill yes
			(thermal_gap 0.5)
			(thermal_bridge_width 0.5)
			(island_removal_mode 0)
		)
		(polygon
			(pts
				(arc
					(start 271.653 -76.073)
					(mid 269.875 -76.073)
					(end 271.653 -76.073)
				)
			)
		)
	)
	(zone
		(layers "In1.Cu" "In3.Cu" "In6.Cu" "In8.Cu")
		(hatch none 0.5)
		(connect_pads
			(clearance 0)
		)
		(min_thickness 0.25)
		(keepout
			(tracks not_allowed)
			(vias allowed)
			(pads allowed)
			(copperpour not_allowed)
			(footprints allowed)
		)
		(placement
			(enabled no)
			(sheetname "")
		)
		(fill yes
			(thermal_gap 0.5)
			(thermal_bridge_width 0.5)
			(island_removal_mode 0)
		)
		(polygon
			(pts
				(arc
					(start 55.991506 -126.492)
					(mid 54.213506 -126.492)
					(end 55.991506 -126.492)
				)
			)
		)
	)
	(zone
		(layers "In1.Cu" "In3.Cu" "In6.Cu" "In8.Cu")
		(hatch none 0.5)
		(connect_pads
			(clearance 0)
		)
		(min_thickness 0.25)
		(keepout
			(tracks not_allowed)
			(vias allowed)
			(pads allowed)
			(copperpour not_allowed)
			(footprints allowed)
		)
		(placement
			(enabled no)
			(sheetname "")
		)
		(fill yes
			(thermal_gap 0.5)
			(thermal_bridge_width 0.5)
			(island_removal_mode 0)
		)
		(polygon
			(pts
				(arc
					(start 31.242 -104.521)
					(mid 29.464 -104.521)
					(end 31.242 -104.521)
				)
			)
		)
	)
	(zone
		(layers "In1.Cu" "In3.Cu" "In6.Cu" "In8.Cu")
		(hatch none 0.5)
		(connect_pads
			(clearance 0)
		)
		(min_thickness 0.25)
		(keepout
			(tracks not_allowed)
			(vias allowed)
			(pads allowed)
			(copperpour not_allowed)
			(footprints allowed)
		)
		(placement
			(enabled no)
			(sheetname "")
		)
		(fill yes
			(thermal_gap 0.5)
			(thermal_bridge_width 0.5)
			(island_removal_mode 0)
		)
		(polygon
			(pts
				(arc
					(start 233.944668 -128.824736)
					(mid 232.166668 -128.824736)
					(end 233.944668 -128.824736)
				)
			)
		)
	)
	(zone
		(layers "In1.Cu" "In3.Cu" "In6.Cu" "In8.Cu")
		(hatch none 0.5)
		(connect_pads
			(clearance 0)
		)
		(min_thickness 0.25)
		(keepout
			(tracks not_allowed)
			(vias allowed)
			(pads allowed)
			(copperpour not_allowed)
			(footprints allowed)
		)
		(placement
			(enabled no)
			(sheetname "")
		)
		(fill yes
			(thermal_gap 0.5)
			(thermal_bridge_width 0.5)
			(island_removal_mode 0)
		)
		(polygon
			(pts
				(arc
					(start 234.706668 -129.586736)
					(mid 232.928668 -129.586736)
					(end 234.706668 -129.586736)
				)
			)
		)
	)
	(zone
		(layers "In1.Cu" "In3.Cu" "In6.Cu" "In8.Cu")
		(hatch none 0.5)
		(connect_pads
			(clearance 0)
		)
		(min_thickness 0.25)
		(keepout
			(tracks not_allowed)
			(vias allowed)
			(pads allowed)
			(copperpour not_allowed)
			(footprints allowed)
		)
		(placement
			(enabled no)
			(sheetname "")
		)
		(fill yes
			(thermal_gap 0.5)
			(thermal_bridge_width 0.5)
			(island_removal_mode 0)
		)
		(polygon
			(pts
				(arc
					(start 270.129 -124.333)
					(mid 268.351 -124.333)
					(end 270.129 -124.333)
				)
			)
		)
	)
	(zone
		(layers "In1.Cu" "In3.Cu" "In6.Cu" "In8.Cu")
		(hatch none 0.5)
		(connect_pads
			(clearance 0)
		)
		(min_thickness 0.25)
		(keepout
			(tracks not_allowed)
			(vias allowed)
			(pads allowed)
			(copperpour not_allowed)
			(footprints allowed)
		)
		(placement
			(enabled no)
			(sheetname "")
		)
		(fill yes
			(thermal_gap 0.5)
			(thermal_bridge_width 0.5)
			(island_removal_mode 0)
		)
		(polygon
			(pts
				(arc
					(start 219.915994 -123.528328)
					(mid 218.137994 -123.528328)
					(end 219.915994 -123.528328)
				)
			)
		)
	)
	(zone
		(layers "In1.Cu" "In3.Cu" "In6.Cu" "In8.Cu")
		(hatch none 0.5)
		(connect_pads
			(clearance 0)
		)
		(min_thickness 0.25)
		(keepout
			(tracks not_allowed)
			(vias allowed)
			(pads allowed)
			(copperpour not_allowed)
			(footprints allowed)
		)
		(placement
			(enabled no)
			(sheetname "")
		)
		(fill yes
			(thermal_gap 0.5)
			(thermal_bridge_width 0.5)
			(island_removal_mode 0)
		)
		(polygon
			(pts
				(arc
					(start 143.637 -112.268)
					(mid 141.859 -112.268)
					(end 143.637 -112.268)
				)
			)
		)
	)
	(zone
		(layers "In1.Cu" "In3.Cu" "In6.Cu" "In8.Cu")
		(hatch none 0.5)
		(connect_pads
			(clearance 0)
		)
		(min_thickness 0.25)
		(keepout
			(tracks not_allowed)
			(vias allowed)
			(pads allowed)
			(copperpour not_allowed)
			(footprints allowed)
		)
		(placement
			(enabled no)
			(sheetname "")
		)
		(fill yes
			(thermal_gap 0.5)
			(thermal_bridge_width 0.5)
			(island_removal_mode 0)
		)
		(polygon
			(pts
				(arc
					(start 272.415 -61.722)
					(mid 270.637 -61.722)
					(end 272.415 -61.722)
				)
			)
		)
	)
	(zone
		(layers "In1.Cu" "In3.Cu" "In6.Cu" "In8.Cu")
		(hatch none 0.5)
		(connect_pads
			(clearance 0)
		)
		(min_thickness 0.25)
		(keepout
			(tracks not_allowed)
			(vias allowed)
			(pads allowed)
			(copperpour not_allowed)
			(footprints allowed)
		)
		(placement
			(enabled no)
			(sheetname "")
		)
		(fill yes
			(thermal_gap 0.5)
			(thermal_bridge_width 0.5)
			(island_removal_mode 0)
		)
		(polygon
			(pts
				(arc
					(start 270.891 -99.441)
					(mid 269.113 -99.441)
					(end 270.891 -99.441)
				)
			)
		)
	)
	(zone
		(layers "In1.Cu" "In3.Cu" "In6.Cu" "In8.Cu")
		(hatch none 0.5)
		(connect_pads
			(clearance 0)
		)
		(min_thickness 0.25)
		(keepout
			(tracks not_allowed)
			(vias allowed)
			(pads allowed)
			(copperpour not_allowed)
			(footprints allowed)
		)
		(placement
			(enabled no)
			(sheetname "")
		)
		(fill yes
			(thermal_gap 0.5)
			(thermal_bridge_width 0.5)
			(island_removal_mode 0)
		)
		(polygon
			(pts
				(arc
					(start 293.624 -47.371)
					(mid 291.846 -47.371)
					(end 293.624 -47.371)
				)
			)
		)
	)
	(zone
		(layers "In1.Cu" "In3.Cu" "In6.Cu" "In8.Cu")
		(hatch none 0.5)
		(connect_pads
			(clearance 0)
		)
		(min_thickness 0.25)
		(keepout
			(tracks not_allowed)
			(vias allowed)
			(pads allowed)
			(copperpour not_allowed)
			(footprints allowed)
		)
		(placement
			(enabled no)
			(sheetname "")
		)
		(fill yes
			(thermal_gap 0.5)
			(thermal_bridge_width 0.5)
			(island_removal_mode 0)
		)
		(polygon
			(pts
				(arc
					(start 208.587086 -123.528328)
					(mid 206.809086 -123.528328)
					(end 208.587086 -123.528328)
				)
			)
		)
	)
	(zone
		(layers "In1.Cu" "In3.Cu" "In6.Cu" "In8.Cu")
		(hatch none 0.5)
		(connect_pads
			(clearance 0)
		)
		(min_thickness 0.25)
		(keepout
			(tracks not_allowed)
			(vias allowed)
			(pads allowed)
			(copperpour not_allowed)
			(footprints allowed)
		)
		(placement
			(enabled no)
			(sheetname "")
		)
		(fill yes
			(thermal_gap 0.5)
			(thermal_bridge_width 0.5)
			(island_removal_mode 0)
		)
		(polygon
			(pts
				(arc
					(start 271.653 -73.787)
					(mid 269.875 -73.787)
					(end 271.653 -73.787)
				)
			)
		)
	)
	(zone
		(layers "In1.Cu" "In3.Cu" "In6.Cu" "In8.Cu")
		(hatch none 0.5)
		(connect_pads
			(clearance 0)
		)
		(min_thickness 0.25)
		(keepout
			(tracks not_allowed)
			(vias allowed)
			(pads allowed)
			(copperpour not_allowed)
			(footprints allowed)
		)
		(placement
			(enabled no)
			(sheetname "")
		)
		(fill yes
			(thermal_gap 0.5)
			(thermal_bridge_width 0.5)
			(island_removal_mode 0)
		)
		(polygon
			(pts
				(arc
					(start 270.129 -98.679)
					(mid 268.351 -98.679)
					(end 270.129 -98.679)
				)
			)
		)
	)
	(zone
		(layers "In1.Cu" "In3.Cu" "In6.Cu" "In8.Cu")
		(hatch none 0.5)
		(connect_pads
			(clearance 0)
		)
		(min_thickness 0.25)
		(keepout
			(tracks not_allowed)
			(vias allowed)
			(pads allowed)
			(copperpour not_allowed)
			(footprints allowed)
		)
		(placement
			(enabled no)
			(sheetname "")
		)
		(fill yes
			(thermal_gap 0.5)
			(thermal_bridge_width 0.5)
			(island_removal_mode 0)
		)
		(polygon
			(pts
				(arc
					(start 94.615 -49.784)
					(mid 92.837 -49.784)
					(end 94.615 -49.784)
				)
			)
		)
	)
	(zone
		(layers "In1.Cu" "In3.Cu" "In6.Cu" "In8.Cu")
		(hatch none 0.5)
		(connect_pads
			(clearance 0)
		)
		(min_thickness 0.25)
		(keepout
			(tracks not_allowed)
			(vias allowed)
			(pads allowed)
			(copperpour not_allowed)
			(footprints allowed)
		)
		(placement
			(enabled no)
			(sheetname "")
		)
		(fill yes
			(thermal_gap 0.5)
			(thermal_bridge_width 0.5)
			(island_removal_mode 0)
		)
		(polygon
			(pts
				(arc
					(start 167.259 -51.562)
					(mid 165.481 -51.562)
					(end 167.259 -51.562)
				)
			)
		)
	)
	(zone
		(layers "In1.Cu" "In3.Cu" "In6.Cu" "In8.Cu")
		(hatch none 0.5)
		(connect_pads
			(clearance 0)
		)
		(min_thickness 0.25)
		(keepout
			(tracks not_allowed)
			(vias allowed)
			(pads allowed)
			(copperpour not_allowed)
			(footprints allowed)
		)
		(placement
			(enabled no)
			(sheetname "")
		)
		(fill yes
			(thermal_gap 0.5)
			(thermal_bridge_width 0.5)
			(island_removal_mode 0)
		)
		(polygon
			(pts
				(arc
					(start 32.131 -104.521)
					(mid 30.353 -104.521)
					(end 32.131 -104.521)
				)
			)
		)
	)
	(zone
		(layers "In1.Cu" "In3.Cu" "In6.Cu" "In8.Cu")
		(hatch none 0.5)
		(connect_pads
			(clearance 0)
		)
		(min_thickness 0.25)
		(keepout
			(tracks not_allowed)
			(vias allowed)
			(pads allowed)
			(copperpour not_allowed)
			(footprints allowed)
		)
		(placement
			(enabled no)
			(sheetname "")
		)
		(fill yes
			(thermal_gap 0.5)
			(thermal_bridge_width 0.5)
			(island_removal_mode 0)
		)
		(polygon
			(pts
				(arc
					(start 203.253086 -123.528328)
					(mid 201.475086 -123.528328)
					(end 203.253086 -123.528328)
				)
			)
		)
	)
	(zone
		(layers "In1.Cu" "In3.Cu" "In6.Cu" "In8.Cu")
		(hatch none 0.5)
		(connect_pads
			(clearance 0)
		)
		(min_thickness 0.25)
		(keepout
			(tracks not_allowed)
			(vias allowed)
			(pads allowed)
			(copperpour not_allowed)
			(footprints allowed)
		)
		(placement
			(enabled no)
			(sheetname "")
		)
		(fill yes
			(thermal_gap 0.5)
			(thermal_bridge_width 0.5)
			(island_removal_mode 0)
		)
		(polygon
			(pts
				(arc
					(start 221.447868 -102.9081)
					(mid 219.669868 -102.9081)
					(end 221.447868 -102.9081)
				)
			)
		)
	)
	(zone
		(layers "In1.Cu" "In3.Cu" "In6.Cu" "In8.Cu")
		(hatch none 0.5)
		(connect_pads
			(clearance 0)
		)
		(min_thickness 0.25)
		(keepout
			(tracks not_allowed)
			(vias allowed)
			(pads allowed)
			(copperpour not_allowed)
			(footprints allowed)
		)
		(placement
			(enabled no)
			(sheetname "")
		)
		(fill yes
			(thermal_gap 0.5)
			(thermal_bridge_width 0.5)
			(island_removal_mode 0)
		)
		(polygon
			(pts
				(arc
					(start 40.767 -104.521)
					(mid 38.989 -104.521)
					(end 40.767 -104.521)
				)
			)
		)
	)
	(zone
		(layers "In1.Cu" "In3.Cu" "In6.Cu" "In8.Cu")
		(hatch none 0.5)
		(connect_pads
			(clearance 0)
		)
		(min_thickness 0.25)
		(keepout
			(tracks not_allowed)
			(vias allowed)
			(pads allowed)
			(copperpour not_allowed)
			(footprints allowed)
		)
		(placement
			(enabled no)
			(sheetname "")
		)
		(fill yes
			(thermal_gap 0.5)
			(thermal_bridge_width 0.5)
			(island_removal_mode 0)
		)
		(polygon
			(pts
				(arc
					(start 207.727042 -102.9081)
					(mid 205.949042 -102.9081)
					(end 207.727042 -102.9081)
				)
			)
		)
	)
	(zone
		(layers "In1.Cu" "In3.Cu" "In6.Cu" "In8.Cu")
		(hatch none 0.5)
		(connect_pads
			(clearance 0)
		)
		(min_thickness 0.25)
		(keepout
			(tracks not_allowed)
			(vias allowed)
			(pads allowed)
			(copperpour not_allowed)
			(footprints allowed)
		)
		(placement
			(enabled no)
			(sheetname "")
		)
		(fill yes
			(thermal_gap 0.5)
			(thermal_bridge_width 0.5)
			(island_removal_mode 0)
		)
		(polygon
			(pts
				(arc
					(start 42.8879 -55.904892)
					(mid 41.1099 -55.904892)
					(end 42.8879 -55.904892)
				)
			)
		)
	)
	(zone
		(layers "In1.Cu" "In3.Cu" "In6.Cu" "In8.Cu")
		(hatch none 0.5)
		(connect_pads
			(clearance 0)
		)
		(min_thickness 0.25)
		(keepout
			(tracks not_allowed)
			(vias allowed)
			(pads allowed)
			(copperpour not_allowed)
			(footprints allowed)
		)
		(placement
			(enabled no)
			(sheetname "")
		)
		(fill yes
			(thermal_gap 0.5)
			(thermal_bridge_width 0.5)
			(island_removal_mode 0)
		)
		(polygon
			(pts
				(arc
					(start 271.653 -85.852)
					(mid 269.875 -85.852)
					(end 271.653 -85.852)
				)
			)
		)
	)
	(zone
		(layers "In1.Cu" "In3.Cu" "In6.Cu" "In8.Cu")
		(hatch none 0.5)
		(connect_pads
			(clearance 0)
		)
		(min_thickness 0.25)
		(keepout
			(tracks not_allowed)
			(vias allowed)
			(pads allowed)
			(copperpour not_allowed)
			(footprints allowed)
		)
		(placement
			(enabled no)
			(sheetname "")
		)
		(fill yes
			(thermal_gap 0.5)
			(thermal_bridge_width 0.5)
			(island_removal_mode 0)
		)
		(polygon
			(pts
				(arc
					(start 146.28622 -121.209816)
					(mid 142.65402 -121.209816)
					(end 146.28622 -121.209816)
				)
			)
		)
	)
	(zone
		(layers "In1.Cu" "In3.Cu" "In6.Cu" "In8.Cu")
		(hatch none 0.5)
		(connect_pads
			(clearance 0)
		)
		(min_thickness 0.25)
		(keepout
			(tracks not_allowed)
			(vias allowed)
			(pads allowed)
			(copperpour not_allowed)
			(footprints allowed)
		)
		(placement
			(enabled no)
			(sheetname "")
		)
		(fill yes
			(thermal_gap 0.5)
			(thermal_bridge_width 0.5)
			(island_removal_mode 0)
		)
		(polygon
			(pts
				(arc
					(start 270.129 -74.549)
					(mid 268.351 -74.549)
					(end 270.129 -74.549)
				)
			)
		)
	)
	(zone
		(layers "In1.Cu" "In3.Cu" "In6.Cu" "In8.Cu")
		(hatch none 0.5)
		(connect_pads
			(clearance 0)
		)
		(min_thickness 0.25)
		(keepout
			(tracks not_allowed)
			(vias allowed)
			(pads allowed)
			(copperpour not_allowed)
			(footprints allowed)
		)
		(placement
			(enabled no)
			(sheetname "")
		)
		(fill yes
			(thermal_gap 0.5)
			(thermal_bridge_width 0.5)
			(island_removal_mode 0)
		)
		(polygon
			(pts
				(arc
					(start 272.041874 -104.887268)
					(mid 270.263874 -104.887268)
					(end 272.041874 -104.887268)
				)
			)
		)
	)
	(zone
		(layers "In1.Cu" "In3.Cu" "In6.Cu" "In8.Cu")
		(hatch none 0.5)
		(connect_pads
			(clearance 0)
		)
		(min_thickness 0.25)
		(keepout
			(tracks not_allowed)
			(vias allowed)
			(pads allowed)
			(copperpour not_allowed)
			(footprints allowed)
		)
		(placement
			(enabled no)
			(sheetname "")
		)
		(fill yes
			(thermal_gap 0.5)
			(thermal_bridge_width 0.5)
			(island_removal_mode 0)
		)
		(polygon
			(pts
				(arc
					(start 221.447868 -105.134664)
					(mid 219.669868 -105.134664)
					(end 221.447868 -105.134664)
				)
			)
		)
	)
	(zone
		(layers "In1.Cu" "In3.Cu" "In6.Cu" "In8.Cu")
		(hatch none 0.5)
		(connect_pads
			(clearance 0)
		)
		(min_thickness 0.25)
		(keepout
			(tracks not_allowed)
			(vias allowed)
			(pads allowed)
			(copperpour not_allowed)
			(footprints allowed)
		)
		(placement
			(enabled no)
			(sheetname "")
		)
		(fill yes
			(thermal_gap 0.5)
			(thermal_bridge_width 0.5)
			(island_removal_mode 0)
		)
		(polygon
			(pts
				(arc
					(start 156.337 -51.562)
					(mid 154.559 -51.562)
					(end 156.337 -51.562)
				)
			)
		)
	)
	(zone
		(layers "In1.Cu" "In3.Cu" "In6.Cu" "In8.Cu")
		(hatch none 0.5)
		(connect_pads
			(clearance 0)
		)
		(min_thickness 0.25)
		(keepout
			(tracks not_allowed)
			(vias allowed)
			(pads allowed)
			(copperpour not_allowed)
			(footprints allowed)
		)
		(placement
			(enabled no)
			(sheetname "")
		)
		(fill yes
			(thermal_gap 0.5)
			(thermal_bridge_width 0.5)
			(island_removal_mode 0)
		)
		(polygon
			(pts
				(arc
					(start 42.2529 -55.904892)
					(mid 40.4749 -55.904892)
					(end 42.2529 -55.904892)
				)
			)
		)
	)
	(zone
		(layers "In1.Cu" "In3.Cu" "In6.Cu" "In8.Cu")
		(hatch none 0.5)
		(connect_pads
			(clearance 0)
		)
		(min_thickness 0.25)
		(keepout
			(tracks not_allowed)
			(vias allowed)
			(pads allowed)
			(copperpour not_allowed)
			(footprints allowed)
		)
		(placement
			(enabled no)
			(sheetname "")
		)
		(fill yes
			(thermal_gap 0.5)
			(thermal_bridge_width 0.5)
			(island_removal_mode 0)
		)
		(polygon
			(pts
				(arc
					(start 217.063828 -130.66014)
					(mid 215.285828 -130.66014)
					(end 217.063828 -130.66014)
				)
			)
		)
	)
	(zone
		(layers "In1.Cu" "In3.Cu" "In6.Cu" "In8.Cu")
		(hatch none 0.5)
		(connect_pads
			(clearance 0)
		)
		(min_thickness 0.25)
		(keepout
			(tracks not_allowed)
			(vias allowed)
			(pads allowed)
			(copperpour not_allowed)
			(footprints allowed)
		)
		(placement
			(enabled no)
			(sheetname "")
		)
		(fill yes
			(thermal_gap 0.5)
			(thermal_bridge_width 0.5)
			(island_removal_mode 0)
		)
		(polygon
			(pts
				(arc
					(start 219.902278 -121.331736)
					(mid 218.124278 -121.331736)
					(end 219.902278 -121.331736)
				)
			)
		)
	)
	(zone
		(layers "In1.Cu" "In3.Cu" "In6.Cu" "In8.Cu")
		(hatch none 0.5)
		(connect_pads
			(clearance 0)
		)
		(min_thickness 0.25)
		(keepout
			(tracks not_allowed)
			(vias allowed)
			(pads allowed)
			(copperpour not_allowed)
			(footprints allowed)
		)
		(placement
			(enabled no)
			(sheetname "")
		)
		(fill yes
			(thermal_gap 0.5)
			(thermal_bridge_width 0.5)
			(island_removal_mode 0)
		)
		(polygon
			(pts
				(arc
					(start 271.653 -112.268)
					(mid 269.875 -112.268)
					(end 271.653 -112.268)
				)
			)
		)
	)
	(zone
		(layers "In1.Cu" "In3.Cu" "In6.Cu" "In8.Cu")
		(hatch none 0.5)
		(connect_pads
			(clearance 0)
		)
		(min_thickness 0.25)
		(keepout
			(tracks not_allowed)
			(vias allowed)
			(pads allowed)
			(copperpour not_allowed)
			(footprints allowed)
		)
		(placement
			(enabled no)
			(sheetname "")
		)
		(fill yes
			(thermal_gap 0.5)
			(thermal_bridge_width 0.5)
			(island_removal_mode 0)
		)
		(polygon
			(pts
				(arc
					(start 235.468668 -129.586736)
					(mid 233.690668 -129.586736)
					(end 235.468668 -129.586736)
				)
			)
		)
	)
	(zone
		(layers "In1.Cu" "In3.Cu" "In6.Cu" "In8.Cu")
		(hatch none 0.5)
		(connect_pads
			(clearance 0)
		)
		(min_thickness 0.25)
		(keepout
			(tracks not_allowed)
			(vias allowed)
			(pads allowed)
			(copperpour not_allowed)
			(footprints allowed)
		)
		(placement
			(enabled no)
			(sheetname "")
		)
		(fill yes
			(thermal_gap 0.5)
			(thermal_bridge_width 0.5)
			(island_removal_mode 0)
		)
		(polygon
			(pts
				(arc
					(start 271.653 -86.614)
					(mid 269.875 -86.614)
					(end 271.653 -86.614)
				)
			)
		)
	)
	(zone
		(layers "In1.Cu" "In3.Cu" "In6.Cu" "In8.Cu")
		(hatch none 0.5)
		(connect_pads
			(clearance 0)
		)
		(min_thickness 0.25)
		(keepout
			(tracks not_allowed)
			(vias allowed)
			(pads allowed)
			(copperpour not_allowed)
			(footprints allowed)
		)
		(placement
			(enabled no)
			(sheetname "")
		)
		(fill yes
			(thermal_gap 0.5)
			(thermal_bridge_width 0.5)
			(island_removal_mode 0)
		)
		(polygon
			(pts
				(arc
					(start 72.318626 -68.853812)
					(mid 70.540626 -68.853812)
					(end 72.318626 -68.853812)
				)
			)
		)
	)
	(zone
		(layers "In1.Cu" "In3.Cu" "In6.Cu" "In8.Cu")
		(hatch none 0.5)
		(connect_pads
			(clearance 0)
		)
		(min_thickness 0.25)
		(keepout
			(tracks not_allowed)
			(vias allowed)
			(pads allowed)
			(copperpour not_allowed)
			(footprints allowed)
		)
		(placement
			(enabled no)
			(sheetname "")
		)
		(fill yes
			(thermal_gap 0.5)
			(thermal_bridge_width 0.5)
			(island_removal_mode 0)
		)
		(polygon
			(pts
				(arc
					(start 219.161868 -104.4321)
					(mid 217.383868 -104.4321)
					(end 219.161868 -104.4321)
				)
			)
		)
	)
	(zone
		(layers "In1.Cu" "In3.Cu" "In6.Cu" "In8.Cu")
		(hatch none 0.5)
		(connect_pads
			(clearance 0)
		)
		(min_thickness 0.25)
		(keepout
			(tracks not_allowed)
			(vias allowed)
			(pads allowed)
			(copperpour not_allowed)
			(footprints allowed)
		)
		(placement
			(enabled no)
			(sheetname "")
		)
		(fill yes
			(thermal_gap 0.5)
			(thermal_bridge_width 0.5)
			(island_removal_mode 0)
		)
		(polygon
			(pts
				(arc
					(start 271.78 -138.176)
					(mid 270.002 -138.176)
					(end 271.78 -138.176)
				)
			)
		)
	)
	(zone
		(layers "In1.Cu" "In3.Cu" "In6.Cu" "In8.Cu")
		(hatch none 0.5)
		(connect_pads
			(clearance 0)
		)
		(min_thickness 0.25)
		(keepout
			(tracks not_allowed)
			(vias allowed)
			(pads allowed)
			(copperpour not_allowed)
			(footprints allowed)
		)
		(placement
			(enabled no)
			(sheetname "")
		)
		(fill yes
			(thermal_gap 0.5)
			(thermal_bridge_width 0.5)
			(island_removal_mode 0)
		)
		(polygon
			(pts
				(arc
					(start 41.656 -103.759)
					(mid 39.878 -103.759)
					(end 41.656 -103.759)
				)
			)
		)
	)
	(zone
		(layers "In1.Cu" "In3.Cu" "In6.Cu" "In8.Cu")
		(hatch none 0.5)
		(connect_pads
			(clearance 0)
		)
		(min_thickness 0.25)
		(keepout
			(tracks not_allowed)
			(vias allowed)
			(pads allowed)
			(copperpour not_allowed)
			(footprints allowed)
		)
		(placement
			(enabled no)
			(sheetname "")
		)
		(fill yes
			(thermal_gap 0.5)
			(thermal_bridge_width 0.5)
			(island_removal_mode 0)
		)
		(polygon
			(pts
				(arc
					(start 84.561426 -126.492)
					(mid 82.783426 -126.492)
					(end 84.561426 -126.492)
				)
			)
		)
	)
	(zone
		(layers "In1.Cu" "In3.Cu" "In6.Cu" "In8.Cu")
		(hatch none 0.5)
		(connect_pads
			(clearance 0)
		)
		(min_thickness 0.25)
		(keepout
			(tracks not_allowed)
			(vias allowed)
			(pads allowed)
			(copperpour not_allowed)
			(footprints allowed)
		)
		(placement
			(enabled no)
			(sheetname "")
		)
		(fill yes
			(thermal_gap 0.5)
			(thermal_bridge_width 0.5)
			(island_removal_mode 0)
		)
		(polygon
			(pts
				(arc
					(start 219.161868 -105.896664)
					(mid 217.383868 -105.896664)
					(end 219.161868 -105.896664)
				)
			)
		)
	)
	(zone
		(layers "In1.Cu" "In3.Cu" "In6.Cu" "In8.Cu")
		(hatch none 0.5)
		(connect_pads
			(clearance 0)
		)
		(min_thickness 0.25)
		(keepout
			(tracks not_allowed)
			(vias allowed)
			(pads allowed)
			(copperpour not_allowed)
			(footprints allowed)
		)
		(placement
			(enabled no)
			(sheetname "")
		)
		(fill yes
			(thermal_gap 0.5)
			(thermal_bridge_width 0.5)
			(island_removal_mode 0)
		)
		(polygon
			(pts
				(arc
					(start 83.693 -50.419)
					(mid 81.915 -50.419)
					(end 83.693 -50.419)
				)
			)
		)
	)
	(zone
		(layers "In1.Cu" "In3.Cu" "In6.Cu" "In8.Cu")
		(hatch none 0.5)
		(connect_pads
			(clearance 0)
		)
		(min_thickness 0.25)
		(keepout
			(tracks not_allowed)
			(vias allowed)
			(pads allowed)
			(copperpour not_allowed)
			(footprints allowed)
		)
		(placement
			(enabled no)
			(sheetname "")
		)
		(fill yes
			(thermal_gap 0.5)
			(thermal_bridge_width 0.5)
			(island_removal_mode 0)
		)
		(polygon
			(pts
				(arc
					(start 156.337 -49.657)
					(mid 154.559 -49.657)
					(end 156.337 -49.657)
				)
			)
		)
	)
	(zone
		(layers "In1.Cu" "In3.Cu" "In6.Cu" "In8.Cu")
		(hatch none 0.5)
		(connect_pads
			(clearance 0)
		)
		(min_thickness 0.25)
		(keepout
			(tracks not_allowed)
			(vias allowed)
			(pads allowed)
			(copperpour not_allowed)
			(footprints allowed)
		)
		(placement
			(enabled no)
			(sheetname "")
		)
		(fill yes
			(thermal_gap 0.5)
			(thermal_bridge_width 0.5)
			(island_removal_mode 0)
		)
		(polygon
			(pts
				(arc
					(start 270.129 -100.965)
					(mid 268.351 -100.965)
					(end 270.129 -100.965)
				)
			)
		)
	)
	(zone
		(layers "In1.Cu" "In3.Cu" "In6.Cu" "In8.Cu")
		(hatch none 0.5)
		(connect_pads
			(clearance 0)
		)
		(min_thickness 0.25)
		(keepout
			(tracks not_allowed)
			(vias allowed)
			(pads allowed)
			(copperpour not_allowed)
			(footprints allowed)
		)
		(placement
			(enabled no)
			(sheetname "")
		)
		(fill yes
			(thermal_gap 0.5)
			(thermal_bridge_width 0.5)
			(island_removal_mode 0)
		)
		(polygon
			(pts
				(arc
					(start 272.415 -86.614)
					(mid 270.637 -86.614)
					(end 272.415 -86.614)
				)
			)
		)
	)
	(zone
		(layers "In1.Cu" "In3.Cu" "In6.Cu" "In8.Cu")
		(hatch none 0.5)
		(connect_pads
			(clearance 0)
		)
		(min_thickness 0.25)
		(keepout
			(tracks not_allowed)
			(vias allowed)
			(pads allowed)
			(copperpour not_allowed)
			(footprints allowed)
		)
		(placement
			(enabled no)
			(sheetname "")
		)
		(fill yes
			(thermal_gap 0.5)
			(thermal_bridge_width 0.5)
			(island_removal_mode 0)
		)
		(polygon
			(pts
				(arc
					(start 272.085054 -68.692268)
					(mid 270.307054 -68.692268)
					(end 272.085054 -68.692268)
				)
			)
		)
	)
	(zone
		(layers "In1.Cu" "In3.Cu" "In6.Cu" "In8.Cu")
		(hatch none 0.5)
		(connect_pads
			(clearance 0)
		)
		(min_thickness 0.25)
		(keepout
			(tracks not_allowed)
			(vias allowed)
			(pads allowed)
			(copperpour not_allowed)
			(footprints allowed)
		)
		(placement
			(enabled no)
			(sheetname "")
		)
		(fill yes
			(thermal_gap 0.5)
			(thermal_bridge_width 0.5)
			(island_removal_mode 0)
		)
		(polygon
			(pts
				(arc
					(start 73.334626 -69.869812)
					(mid 71.556626 -69.869812)
					(end 73.334626 -69.869812)
				)
			)
		)
	)
	(zone
		(layers "In1.Cu" "In3.Cu" "In6.Cu" "In8.Cu")
		(hatch none 0.5)
		(connect_pads
			(clearance 0)
		)
		(min_thickness 0.25)
		(keepout
			(tracks not_allowed)
			(vias allowed)
			(pads allowed)
			(copperpour not_allowed)
			(footprints allowed)
		)
		(placement
			(enabled no)
			(sheetname "")
		)
		(fill yes
			(thermal_gap 0.5)
			(thermal_bridge_width 0.5)
			(island_removal_mode 0)
		)
		(polygon
			(pts
				(arc
					(start 172.72 -50.292)
					(mid 170.942 -50.292)
					(end 172.72 -50.292)
				)
			)
		)
	)
	(zone
		(layers "In1.Cu" "In3.Cu" "In6.Cu" "In8.Cu")
		(hatch none 0.5)
		(connect_pads
			(clearance 0)
		)
		(min_thickness 0.25)
		(keepout
			(tracks not_allowed)
			(vias allowed)
			(pads allowed)
			(copperpour not_allowed)
			(footprints allowed)
		)
		(placement
			(enabled no)
			(sheetname "")
		)
		(fill yes
			(thermal_gap 0.5)
			(thermal_bridge_width 0.5)
			(island_removal_mode 0)
		)
		(polygon
			(pts
				(arc
					(start 78.232 -51.689)
					(mid 76.454 -51.689)
					(end 78.232 -51.689)
				)
			)
		)
	)
	(zone
		(layers "In1.Cu" "In3.Cu" "In6.Cu" "In8.Cu")
		(hatch none 0.5)
		(connect_pads
			(clearance 0)
		)
		(min_thickness 0.25)
		(keepout
			(tracks not_allowed)
			(vias allowed)
			(pads allowed)
			(copperpour not_allowed)
			(footprints allowed)
		)
		(placement
			(enabled no)
			(sheetname "")
		)
		(fill yes
			(thermal_gap 0.5)
			(thermal_bridge_width 0.5)
			(island_removal_mode 0)
		)
		(polygon
			(pts
				(arc
					(start 42.73804 -54.1147)
					(mid 40.96004 -54.1147)
					(end 42.73804 -54.1147)
				)
			)
		)
	)
	(zone
		(layers "In1.Cu" "In3.Cu" "In6.Cu" "In8.Cu")
		(hatch none 0.5)
		(connect_pads
			(clearance 0)
		)
		(min_thickness 0.25)
		(keepout
			(tracks not_allowed)
			(vias allowed)
			(pads allowed)
			(copperpour not_allowed)
			(footprints allowed)
		)
		(placement
			(enabled no)
			(sheetname "")
		)
		(fill yes
			(thermal_gap 0.5)
			(thermal_bridge_width 0.5)
			(island_removal_mode 0)
		)
		(polygon
			(pts
				(arc
					(start 233.944668 -128.062736)
					(mid 232.166668 -128.062736)
					(end 233.944668 -128.062736)
				)
			)
		)
	)
	(zone
		(layers "In1.Cu" "In3.Cu" "In6.Cu" "In8.Cu")
		(hatch none 0.5)
		(connect_pads
			(clearance 0)
		)
		(min_thickness 0.25)
		(keepout
			(tracks not_allowed)
			(vias allowed)
			(pads allowed)
			(copperpour not_allowed)
			(footprints allowed)
		)
		(placement
			(enabled no)
			(sheetname "")
		)
		(fill yes
			(thermal_gap 0.5)
			(thermal_bridge_width 0.5)
			(island_removal_mode 0)
		)
		(polygon
			(pts
				(arc
					(start 234.706668 -131.110736)
					(mid 232.928668 -131.110736)
					(end 234.706668 -131.110736)
				)
			)
		)
	)
	(zone
		(layers "In1.Cu" "In3.Cu" "In6.Cu" "In8.Cu")
		(hatch none 0.5)
		(connect_pads
			(clearance 0)
		)
		(min_thickness 0.25)
		(keepout
			(tracks not_allowed)
			(vias allowed)
			(pads allowed)
			(copperpour not_allowed)
			(footprints allowed)
		)
		(placement
			(enabled no)
			(sheetname "")
		)
		(fill yes
			(thermal_gap 0.5)
			(thermal_bridge_width 0.5)
			(island_removal_mode 0)
		)
		(polygon
			(pts
				(arc
					(start 78.232 -50.419)
					(mid 76.454 -50.419)
					(end 78.232 -50.419)
				)
			)
		)
	)
	(zone
		(layers "In1.Cu" "In3.Cu" "In6.Cu" "In8.Cu")
		(hatch none 0.5)
		(connect_pads
			(clearance 0)
		)
		(min_thickness 0.25)
		(keepout
			(tracks not_allowed)
			(vias allowed)
			(pads allowed)
			(copperpour not_allowed)
			(footprints allowed)
		)
		(placement
			(enabled no)
			(sheetname "")
		)
		(fill yes
			(thermal_gap 0.5)
			(thermal_bridge_width 0.5)
			(island_removal_mode 0)
		)
		(polygon
			(pts
				(arc
					(start 207.81137 -121.331736)
					(mid 206.03337 -121.331736)
					(end 207.81137 -121.331736)
				)
			)
		)
	)
	(zone
		(layers "In1.Cu" "In3.Cu" "In6.Cu" "In8.Cu")
		(hatch none 0.5)
		(connect_pads
			(clearance 0)
		)
		(min_thickness 0.25)
		(keepout
			(tracks not_allowed)
			(vias allowed)
			(pads allowed)
			(copperpour not_allowed)
			(footprints allowed)
		)
		(placement
			(enabled no)
			(sheetname "")
		)
		(fill yes
			(thermal_gap 0.5)
			(thermal_bridge_width 0.5)
			(island_removal_mode 0)
		)
		(polygon
			(pts
				(arc
					(start 216.88806 -98.013012)
					(mid 215.11006 -98.013012)
					(end 216.88806 -98.013012)
				)
			)
		)
	)
	(zone
		(layers "In1.Cu" "In3.Cu" "In6.Cu" "In8.Cu")
		(hatch none 0.5)
		(connect_pads
			(clearance 0)
		)
		(min_thickness 0.25)
		(keepout
			(tracks not_allowed)
			(vias allowed)
			(pads allowed)
			(copperpour not_allowed)
			(footprints allowed)
		)
		(placement
			(enabled no)
			(sheetname "")
		)
		(fill yes
			(thermal_gap 0.5)
			(thermal_bridge_width 0.5)
			(island_removal_mode 0)
		)
		(polygon
			(pts
				(arc
					(start 222.928688 -102.894384)
					(mid 221.150688 -102.894384)
					(end 222.928688 -102.894384)
				)
			)
		)
	)
	(zone
		(layers "In1.Cu" "In3.Cu" "In6.Cu" "In8.Cu")
		(hatch none 0.5)
		(connect_pads
			(clearance 0)
		)
		(min_thickness 0.25)
		(keepout
			(tracks not_allowed)
			(vias allowed)
			(pads allowed)
			(copperpour not_allowed)
			(footprints allowed)
		)
		(placement
			(enabled no)
			(sheetname "")
		)
		(fill yes
			(thermal_gap 0.5)
			(thermal_bridge_width 0.5)
			(island_removal_mode 0)
		)
		(polygon
			(pts
				(arc
					(start 42.8879 -57.70499)
					(mid 41.1099 -57.70499)
					(end 42.8879 -57.70499)
				)
			)
		)
	)
	(zone
		(layers "In1.Cu" "In3.Cu" "In6.Cu" "In8.Cu")
		(hatch none 0.5)
		(connect_pads
			(clearance 0)
		)
		(min_thickness 0.25)
		(keepout
			(tracks not_allowed)
			(vias allowed)
			(pads allowed)
			(copperpour not_allowed)
			(footprints allowed)
		)
		(placement
			(enabled no)
			(sheetname "")
		)
		(fill yes
			(thermal_gap 0.5)
			(thermal_bridge_width 0.5)
			(island_removal_mode 0)
		)
		(polygon
			(pts
				(arc
					(start 216.535 -101.346)
					(mid 214.757 -101.346)
					(end 216.535 -101.346)
				)
			)
		)
	)
	(zone
		(layers "In1.Cu" "In3.Cu" "In6.Cu" "In8.Cu")
		(hatch none 0.5)
		(connect_pads
			(clearance 0)
		)
		(min_thickness 0.25)
		(keepout
			(tracks not_allowed)
			(vias allowed)
			(pads allowed)
			(copperpour not_allowed)
			(footprints allowed)
		)
		(placement
			(enabled no)
			(sheetname "")
		)
		(fill yes
			(thermal_gap 0.5)
			(thermal_bridge_width 0.5)
			(island_removal_mode 0)
		)
		(polygon
			(pts
				(arc
					(start 148.1836 -126.492)
					(mid 146.4056 -126.492)
					(end 148.1836 -126.492)
				)
			)
		)
	)
	(zone
		(layers "In1.Cu" "In3.Cu" "In6.Cu" "In8.Cu")
		(hatch none 0.5)
		(connect_pads
			(clearance 0)
		)
		(min_thickness 0.25)
		(keepout
			(tracks not_allowed)
			(vias allowed)
			(pads allowed)
			(copperpour not_allowed)
			(footprints allowed)
		)
		(placement
			(enabled no)
			(sheetname "")
		)
		(fill yes
			(thermal_gap 0.5)
			(thermal_bridge_width 0.5)
			(island_removal_mode 0)
		)
		(polygon
			(pts
				(arc
					(start 237.443518 -97.985834)
					(mid 235.665518 -97.985834)
					(end 237.443518 -97.985834)
				)
			)
		)
	)
	(zone
		(layers "In1.Cu" "In3.Cu" "In6.Cu" "In8.Cu")
		(hatch none 0.5)
		(connect_pads
			(clearance 0)
		)
		(min_thickness 0.25)
		(keepout
			(tracks not_allowed)
			(vias allowed)
			(pads allowed)
			(copperpour not_allowed)
			(footprints allowed)
		)
		(placement
			(enabled no)
			(sheetname "")
		)
		(fill yes
			(thermal_gap 0.5)
			(thermal_bridge_width 0.5)
			(island_removal_mode 0)
		)
		(polygon
			(pts
				(arc
					(start 164.561774 -131.572)
					(mid 162.783774 -131.572)
					(end 164.561774 -131.572)
				)
			)
		)
	)
	(zone
		(layers "In1.Cu" "In3.Cu" "In6.Cu" "In8.Cu")
		(hatch none 0.5)
		(connect_pads
			(clearance 0)
		)
		(min_thickness 0.25)
		(keepout
			(tracks not_allowed)
			(vias allowed)
			(pads allowed)
			(copperpour not_allowed)
			(footprints allowed)
		)
		(placement
			(enabled no)
			(sheetname "")
		)
		(fill yes
			(thermal_gap 0.5)
			(thermal_bridge_width 0.5)
			(island_removal_mode 0)
		)
		(polygon
			(pts
				(arc
					(start 216.347802 -127.61214)
					(mid 214.569802 -127.61214)
					(end 216.347802 -127.61214)
				)
			)
		)
	)
	(zone
		(layers "In1.Cu" "In3.Cu" "In6.Cu" "In8.Cu")
		(hatch none 0.5)
		(connect_pads
			(clearance 0)
		)
		(min_thickness 0.25)
		(keepout
			(tracks not_allowed)
			(vias allowed)
			(pads allowed)
			(copperpour not_allowed)
			(footprints allowed)
		)
		(placement
			(enabled no)
			(sheetname "")
		)
		(fill yes
			(thermal_gap 0.5)
			(thermal_bridge_width 0.5)
			(island_removal_mode 0)
		)
		(polygon
			(pts
				(arc
					(start 161.798 -52.197)
					(mid 160.02 -52.197)
					(end 161.798 -52.197)
				)
			)
		)
	)
	(zone
		(layers "In1.Cu" "In3.Cu" "In6.Cu" "In8.Cu")
		(hatch none 0.5)
		(connect_pads
			(clearance 0)
		)
		(min_thickness 0.25)
		(keepout
			(tracks not_allowed)
			(vias allowed)
			(pads allowed)
			(copperpour not_allowed)
			(footprints allowed)
		)
		(placement
			(enabled no)
			(sheetname "")
		)
		(fill yes
			(thermal_gap 0.5)
			(thermal_bridge_width 0.5)
			(island_removal_mode 0)
		)
		(polygon
			(pts
				(arc
					(start 273.177 -101.727)
					(mid 271.399 -101.727)
					(end 273.177 -101.727)
				)
			)
		)
	)
	(zone
		(layers "In1.Cu" "In3.Cu" "In6.Cu" "In8.Cu")
		(hatch none 0.5)
		(connect_pads
			(clearance 0)
		)
		(min_thickness 0.25)
		(keepout
			(tracks not_allowed)
			(vias allowed)
			(pads allowed)
			(copperpour not_allowed)
			(footprints allowed)
		)
		(placement
			(enabled no)
			(sheetname "")
		)
		(fill yes
			(thermal_gap 0.5)
			(thermal_bridge_width 0.5)
			(island_removal_mode 0)
		)
		(polygon
			(pts
				(arc
					(start 271.653 -87.376)
					(mid 269.875 -87.376)
					(end 271.653 -87.376)
				)
			)
		)
	)
	(zone
		(layers "In1.Cu" "In3.Cu" "In6.Cu" "In8.Cu")
		(hatch none 0.5)
		(connect_pads
			(clearance 0)
		)
		(min_thickness 0.25)
		(keepout
			(tracks not_allowed)
			(vias allowed)
			(pads allowed)
			(copperpour not_allowed)
			(footprints allowed)
		)
		(placement
			(enabled no)
			(sheetname "")
		)
		(fill yes
			(thermal_gap 0.5)
			(thermal_bridge_width 0.5)
			(island_removal_mode 0)
		)
		(polygon
			(pts
				(arc
					(start 207.81137 -122.047762)
					(mid 206.03337 -122.047762)
					(end 207.81137 -122.047762)
				)
			)
		)
	)
	(zone
		(layers "In1.Cu" "In3.Cu" "In6.Cu" "In8.Cu")
		(hatch none 0.5)
		(connect_pads
			(clearance 0)
		)
		(min_thickness 0.25)
		(keepout
			(tracks not_allowed)
			(vias allowed)
			(pads allowed)
			(copperpour not_allowed)
			(footprints allowed)
		)
		(placement
			(enabled no)
			(sheetname "")
		)
		(fill yes
			(thermal_gap 0.5)
			(thermal_bridge_width 0.5)
			(island_removal_mode 0)
		)
		(polygon
			(pts
				(arc
					(start 67.853306 -136.906)
					(mid 65.008506 -136.906)
					(end 67.853306 -136.906)
				)
			)
		)
	)
	(zone
		(layers "In1.Cu" "In3.Cu" "In6.Cu" "In8.Cu")
		(hatch none 0.5)
		(connect_pads
			(clearance 0)
		)
		(min_thickness 0.25)
		(keepout
			(tracks not_allowed)
			(vias allowed)
			(pads allowed)
			(copperpour not_allowed)
			(footprints allowed)
		)
		(placement
			(enabled no)
			(sheetname "")
		)
		(fill yes
			(thermal_gap 0.5)
			(thermal_bridge_width 0.5)
			(island_removal_mode 0)
		)
		(polygon
			(pts
				(arc
					(start 271.653 -62.484)
					(mid 269.875 -62.484)
					(end 271.653 -62.484)
				)
			)
		)
	)
	(zone
		(layers "In1.Cu" "In3.Cu" "In6.Cu" "In8.Cu")
		(hatch none 0.5)
		(connect_pads
			(clearance 0)
		)
		(min_thickness 0.25)
		(keepout
			(tracks not_allowed)
			(vias allowed)
			(pads allowed)
			(copperpour not_allowed)
			(footprints allowed)
		)
		(placement
			(enabled no)
			(sheetname "")
		)
		(fill yes
			(thermal_gap 0.5)
			(thermal_bridge_width 0.5)
			(island_removal_mode 0)
		)
		(polygon
			(pts
				(arc
					(start 297.4594 -45.847)
					(mid 295.6814 -45.847)
					(end 297.4594 -45.847)
				)
			)
		)
	)
	(zone
		(layers "In1.Cu" "In3.Cu" "In6.Cu" "In8.Cu")
		(hatch none 0.5)
		(connect_pads
			(clearance 0)
		)
		(min_thickness 0.25)
		(keepout
			(tracks not_allowed)
			(vias allowed)
			(pads allowed)
			(copperpour not_allowed)
			(footprints allowed)
		)
		(placement
			(enabled no)
			(sheetname "")
		)
		(fill yes
			(thermal_gap 0.5)
			(thermal_bridge_width 0.5)
			(island_removal_mode 0)
		)
		(polygon
			(pts
				(arc
					(start 235.954316 -97.985834)
					(mid 234.176316 -97.985834)
					(end 235.954316 -97.985834)
				)
			)
		)
	)
	(zone
		(layers "In1.Cu" "In3.Cu" "In6.Cu" "In8.Cu")
		(hatch none 0.5)
		(connect_pads
			(clearance 0)
		)
		(min_thickness 0.25)
		(keepout
			(tracks not_allowed)
			(vias allowed)
			(pads allowed)
			(copperpour not_allowed)
			(footprints allowed)
		)
		(placement
			(enabled no)
			(sheetname "")
		)
		(fill yes
			(thermal_gap 0.5)
			(thermal_bridge_width 0.5)
			(island_removal_mode 0)
		)
		(polygon
			(pts
				(arc
					(start 216.12606 -98.013012)
					(mid 214.34806 -98.013012)
					(end 216.12606 -98.013012)
				)
			)
		)
	)
	(zone
		(layers "In1.Cu" "In3.Cu" "In6.Cu" "In8.Cu")
		(hatch none 0.5)
		(connect_pads
			(clearance 0)
		)
		(min_thickness 0.25)
		(keepout
			(tracks not_allowed)
			(vias allowed)
			(pads allowed)
			(copperpour not_allowed)
			(footprints allowed)
		)
		(placement
			(enabled no)
			(sheetname "")
		)
		(fill yes
			(thermal_gap 0.5)
			(thermal_bridge_width 0.5)
			(island_removal_mode 0)
		)
		(polygon
			(pts
				(arc
					(start 234.706668 -128.062736)
					(mid 232.928668 -128.062736)
					(end 234.706668 -128.062736)
				)
			)
		)
	)
	(zone
		(layers "In1.Cu" "In3.Cu" "In6.Cu" "In8.Cu")
		(hatch none 0.5)
		(connect_pads
			(clearance 0)
		)
		(min_thickness 0.25)
		(keepout
			(tracks not_allowed)
			(vias allowed)
			(pads allowed)
			(copperpour not_allowed)
			(footprints allowed)
		)
		(placement
			(enabled no)
			(sheetname "")
		)
		(fill yes
			(thermal_gap 0.5)
			(thermal_bridge_width 0.5)
			(island_removal_mode 0)
		)
		(polygon
			(pts
				(arc
					(start 271.653 -99.441)
					(mid 269.875 -99.441)
					(end 271.653 -99.441)
				)
			)
		)
	)
	(zone
		(layers "In1.Cu" "In3.Cu" "In6.Cu" "In8.Cu")
		(hatch none 0.5)
		(connect_pads
			(clearance 0)
		)
		(min_thickness 0.25)
		(keepout
			(tracks not_allowed)
			(vias allowed)
			(pads allowed)
			(copperpour not_allowed)
			(footprints allowed)
		)
		(placement
			(enabled no)
			(sheetname "")
		)
		(fill yes
			(thermal_gap 0.5)
			(thermal_bridge_width 0.5)
			(island_removal_mode 0)
		)
		(polygon
			(pts
				(arc
					(start 31.242 -103.759)
					(mid 29.464 -103.759)
					(end 31.242 -103.759)
				)
			)
		)
	)
	(zone
		(layers "In1.Cu" "In3.Cu" "In6.Cu" "In8.Cu")
		(hatch none 0.5)
		(connect_pads
			(clearance 0)
		)
		(min_thickness 0.25)
		(keepout
			(tracks not_allowed)
			(vias allowed)
			(pads allowed)
			(copperpour not_allowed)
			(footprints allowed)
		)
		(placement
			(enabled no)
			(sheetname "")
		)
		(fill yes
			(thermal_gap 0.5)
			(thermal_bridge_width 0.5)
			(island_removal_mode 0)
		)
		(polygon
			(pts
				(arc
					(start 55.661306 -136.906)
					(mid 52.816506 -136.906)
					(end 55.661306 -136.906)
				)
			)
		)
	)
	(zone
		(layers "In1.Cu" "In3.Cu" "In6.Cu" "In8.Cu")
		(hatch none 0.5)
		(connect_pads
			(clearance 0)
		)
		(min_thickness 0.25)
		(keepout
			(tracks not_allowed)
			(vias allowed)
			(pads allowed)
			(copperpour not_allowed)
			(footprints allowed)
		)
		(placement
			(enabled no)
			(sheetname "")
		)
		(fill yes
			(thermal_gap 0.5)
			(thermal_bridge_width 0.5)
			(island_removal_mode 0)
		)
		(polygon
			(pts
				(arc
					(start 105.537 -52.324)
					(mid 103.759 -52.324)
					(end 105.537 -52.324)
				)
			)
		)
	)
	(zone
		(layers "In1.Cu" "In3.Cu" "In6.Cu" "In8.Cu")
		(hatch none 0.5)
		(connect_pads
			(clearance 0)
		)
		(min_thickness 0.25)
		(keepout
			(tracks not_allowed)
			(vias allowed)
			(pads allowed)
			(copperpour not_allowed)
			(footprints allowed)
		)
		(placement
			(enabled no)
			(sheetname "")
		)
		(fill yes
			(thermal_gap 0.5)
			(thermal_bridge_width 0.5)
			(island_removal_mode 0)
		)
		(polygon
			(pts
				(arc
					(start 222.201994 -123.528328)
					(mid 220.423994 -123.528328)
					(end 222.201994 -123.528328)
				)
			)
		)
	)
	(zone
		(layers "In1.Cu" "In3.Cu" "In6.Cu" "In8.Cu")
		(hatch none 0.5)
		(connect_pads
			(clearance 0)
		)
		(min_thickness 0.25)
		(keepout
			(tracks not_allowed)
			(vias allowed)
			(pads allowed)
			(copperpour not_allowed)
			(footprints allowed)
		)
		(placement
			(enabled no)
			(sheetname "")
		)
		(fill yes
			(thermal_gap 0.5)
			(thermal_bridge_width 0.5)
			(island_removal_mode 0)
		)
		(polygon
			(pts
				(arc
					(start 270.378936 -106.360468)
					(mid 268.600936 -106.360468)
					(end 270.378936 -106.360468)
				)
			)
		)
	)
	(zone
		(layers "In1.Cu" "In3.Cu" "In6.Cu" "In8.Cu")
		(hatch none 0.5)
		(connect_pads
			(clearance 0)
		)
		(min_thickness 0.25)
		(keepout
			(tracks not_allowed)
			(vias allowed)
			(pads allowed)
			(copperpour not_allowed)
			(footprints allowed)
		)
		(placement
			(enabled no)
			(sheetname "")
		)
		(fill yes
			(thermal_gap 0.5)
			(thermal_bridge_width 0.5)
			(island_removal_mode 0)
		)
		(polygon
			(pts
				(arc
					(start 89.154 -51.689)
					(mid 87.376 -51.689)
					(end 89.154 -51.689)
				)
			)
		)
	)
	(zone
		(layers "In1.Cu" "In3.Cu" "In6.Cu" "In8.Cu")
		(hatch none 0.5)
		(connect_pads
			(clearance 0)
		)
		(min_thickness 0.25)
		(keepout
			(tracks not_allowed)
			(vias allowed)
			(pads allowed)
			(copperpour not_allowed)
			(footprints allowed)
		)
		(placement
			(enabled no)
			(sheetname "")
		)
		(fill yes
			(thermal_gap 0.5)
			(thermal_bridge_width 0.5)
			(island_removal_mode 0)
		)
		(polygon
			(pts
				(arc
					(start 271.653 -100.203)
					(mid 269.875 -100.203)
					(end 271.653 -100.203)
				)
			)
		)
	)
	(zone
		(layers "In1.Cu" "In3.Cu" "In6.Cu" "In8.Cu")
		(hatch none 0.5)
		(connect_pads
			(clearance 0)
		)
		(min_thickness 0.25)
		(keepout
			(tracks not_allowed)
			(vias allowed)
			(pads allowed)
			(copperpour not_allowed)
			(footprints allowed)
		)
		(placement
			(enabled no)
			(sheetname "")
		)
		(fill yes
			(thermal_gap 0.5)
			(thermal_bridge_width 0.5)
			(island_removal_mode 0)
		)
		(polygon
			(pts
				(arc
					(start 272.415 -100.965)
					(mid 270.637 -100.965)
					(end 272.415 -100.965)
				)
			)
		)
	)
	(zone
		(layers "In1.Cu" "In3.Cu" "In6.Cu" "In8.Cu")
		(hatch none 0.5)
		(connect_pads
			(clearance 0)
		)
		(min_thickness 0.25)
		(keepout
			(tracks not_allowed)
			(vias allowed)
			(pads allowed)
			(copperpour not_allowed)
			(footprints allowed)
		)
		(placement
			(enabled no)
			(sheetname "")
		)
		(fill yes
			(thermal_gap 0.5)
			(thermal_bridge_width 0.5)
			(island_removal_mode 0)
		)
		(polygon
			(pts
				(arc
					(start 136.7536 -126.492)
					(mid 134.9756 -126.492)
					(end 136.7536 -126.492)
				)
			)
		)
	)
	(zone
		(layers "In1.Cu" "In3.Cu" "In6.Cu" "In8.Cu")
		(hatch none 0.5)
		(connect_pads
			(clearance 0)
		)
		(min_thickness 0.25)
		(keepout
			(tracks not_allowed)
			(vias allowed)
			(pads allowed)
			(copperpour not_allowed)
			(footprints allowed)
		)
		(placement
			(enabled no)
			(sheetname "")
		)
		(fill yes
			(thermal_gap 0.5)
			(thermal_bridge_width 0.5)
			(island_removal_mode 0)
		)
		(polygon
			(pts
				(arc
					(start 272.542 -138.938)
					(mid 270.764 -138.938)
					(end 272.542 -138.938)
				)
			)
		)
	)
	(zone
		(layers "In1.Cu" "In3.Cu" "In6.Cu" "In8.Cu")
		(hatch none 0.5)
		(connect_pads
			(clearance 0)
		)
		(min_thickness 0.25)
		(keepout
			(tracks not_allowed)
			(vias allowed)
			(pads allowed)
			(copperpour not_allowed)
			(footprints allowed)
		)
		(placement
			(enabled no)
			(sheetname "")
		)
		(fill yes
			(thermal_gap 0.5)
			(thermal_bridge_width 0.5)
			(island_removal_mode 0)
		)
		(polygon
			(pts
				(arc
					(start 272.415 -122.047)
					(mid 270.637 -122.047)
					(end 272.415 -122.047)
				)
			)
		)
	)
	(zone
		(layers "In1.Cu" "In3.Cu" "In6.Cu" "In8.Cu")
		(hatch none 0.5)
		(connect_pads
			(clearance 0)
		)
		(min_thickness 0.25)
		(keepout
			(tracks not_allowed)
			(vias allowed)
			(pads allowed)
			(copperpour not_allowed)
			(footprints allowed)
		)
		(placement
			(enabled no)
			(sheetname "")
		)
		(fill yes
			(thermal_gap 0.5)
			(thermal_bridge_width 0.5)
			(island_removal_mode 0)
		)
		(polygon
			(pts
				(arc
					(start 271.653 -74.549)
					(mid 269.875 -74.549)
					(end 271.653 -74.549)
				)
			)
		)
	)
	(zone
		(layers "In1.Cu" "In3.Cu" "In6.Cu" "In8.Cu")
		(hatch none 0.5)
		(connect_pads
			(clearance 0)
		)
		(min_thickness 0.25)
		(keepout
			(tracks not_allowed)
			(vias allowed)
			(pads allowed)
			(copperpour not_allowed)
			(footprints allowed)
		)
		(placement
			(enabled no)
			(sheetname "")
		)
		(fill yes
			(thermal_gap 0.5)
			(thermal_bridge_width 0.5)
			(island_removal_mode 0)
		)
		(polygon
			(pts
				(arc
					(start 273.177 -113.03)
					(mid 271.399 -113.03)
					(end 273.177 -113.03)
				)
			)
		)
	)
	(zone
		(layers "In1.Cu" "In3.Cu" "In6.Cu" "In8.Cu")
		(hatch none 0.5)
		(connect_pads
			(clearance 0)
		)
		(min_thickness 0.25)
		(keepout
			(tracks not_allowed)
			(vias allowed)
			(pads allowed)
			(copperpour not_allowed)
			(footprints allowed)
		)
		(placement
			(enabled no)
			(sheetname "")
		)
		(fill yes
			(thermal_gap 0.5)
			(thermal_bridge_width 0.5)
			(island_removal_mode 0)
		)
		(polygon
			(pts
				(arc
					(start 78.232 -52.324)
					(mid 76.454 -52.324)
					(end 78.232 -52.324)
				)
			)
		)
	)
	(zone
		(layers "In1.Cu" "In3.Cu" "In6.Cu" "In8.Cu")
		(hatch none 0.5)
		(connect_pads
			(clearance 0)
		)
		(min_thickness 0.25)
		(keepout
			(tracks not_allowed)
			(vias allowed)
			(pads allowed)
			(copperpour not_allowed)
			(footprints allowed)
		)
		(placement
			(enabled no)
			(sheetname "")
		)
		(fill yes
			(thermal_gap 0.5)
			(thermal_bridge_width 0.5)
			(island_removal_mode 0)
		)
		(polygon
			(pts
				(arc
					(start 161.798 -50.292)
					(mid 160.02 -50.292)
					(end 161.798 -50.292)
				)
			)
		)
	)
	(zone
		(layers "In1.Cu" "In3.Cu" "In6.Cu" "In8.Cu")
		(hatch none 0.5)
		(connect_pads
			(clearance 0)
		)
		(min_thickness 0.25)
		(keepout
			(tracks not_allowed)
			(vias allowed)
			(pads allowed)
			(copperpour not_allowed)
			(footprints allowed)
		)
		(placement
			(enabled no)
			(sheetname "")
		)
		(fill yes
			(thermal_gap 0.5)
			(thermal_bridge_width 0.5)
			(island_removal_mode 0)
		)
		(polygon
			(pts
				(arc
					(start 161.798 -51.562)
					(mid 160.02 -51.562)
					(end 161.798 -51.562)
				)
			)
		)
	)
	(zone
		(layers "In1.Cu" "In3.Cu" "In6.Cu" "In8.Cu")
		(hatch none 0.5)
		(connect_pads
			(clearance 0)
		)
		(min_thickness 0.25)
		(keepout
			(tracks not_allowed)
			(vias allowed)
			(pads allowed)
			(copperpour not_allowed)
			(footprints allowed)
		)
		(placement
			(enabled no)
			(sheetname "")
		)
		(fill yes
			(thermal_gap 0.5)
			(thermal_bridge_width 0.5)
			(island_removal_mode 0)
		)
		(polygon
			(pts
				(arc
					(start 148.9456 -126.492)
					(mid 147.1676 -126.492)
					(end 148.9456 -126.492)
				)
			)
		)
	)
	(zone
		(layers "In1.Cu" "In3.Cu" "In6.Cu" "In8.Cu")
		(hatch none 0.5)
		(connect_pads
			(clearance 0)
		)
		(min_thickness 0.25)
		(keepout
			(tracks not_allowed)
			(vias allowed)
			(pads allowed)
			(copperpour not_allowed)
			(footprints allowed)
		)
		(placement
			(enabled no)
			(sheetname "")
		)
		(fill yes
			(thermal_gap 0.5)
			(thermal_bridge_width 0.5)
			(island_removal_mode 0)
		)
		(polygon
			(pts
				(arc
					(start 44.561506 -131.572)
					(mid 42.783506 -131.572)
					(end 44.561506 -131.572)
				)
			)
		)
	)
	(zone
		(layers "In1.Cu" "In3.Cu" "In6.Cu" "In8.Cu")
		(hatch none 0.5)
		(connect_pads
			(clearance 0)
		)
		(min_thickness 0.25)
		(keepout
			(tracks not_allowed)
			(vias allowed)
			(pads allowed)
			(copperpour not_allowed)
			(footprints allowed)
		)
		(placement
			(enabled no)
			(sheetname "")
		)
		(fill yes
			(thermal_gap 0.5)
			(thermal_bridge_width 0.5)
			(island_removal_mode 0)
		)
		(polygon
			(pts
				(arc
					(start 222.950278 -121.331736)
					(mid 221.172278 -121.331736)
					(end 222.950278 -121.331736)
				)
			)
		)
	)
	(zone
		(layers "In1.Cu" "In3.Cu" "In6.Cu" "In8.Cu")
		(hatch none 0.5)
		(connect_pads
			(clearance 0)
		)
		(min_thickness 0.25)
		(keepout
			(tracks not_allowed)
			(vias allowed)
			(pads allowed)
			(copperpour not_allowed)
			(footprints allowed)
		)
		(placement
			(enabled no)
			(sheetname "")
		)
		(fill yes
			(thermal_gap 0.5)
			(thermal_bridge_width 0.5)
			(island_removal_mode 0)
		)
		(polygon
			(pts
				(arc
					(start 217.825828 -130.66014)
					(mid 216.047828 -130.66014)
					(end 217.825828 -130.66014)
				)
			)
		)
	)
	(zone
		(layers "In1.Cu" "In3.Cu" "In6.Cu" "In8.Cu")
		(hatch none 0.5)
		(connect_pads
			(clearance 0)
		)
		(min_thickness 0.25)
		(keepout
			(tracks not_allowed)
			(vias allowed)
			(pads allowed)
			(copperpour not_allowed)
			(footprints allowed)
		)
		(placement
			(enabled no)
			(sheetname "")
		)
		(fill yes
			(thermal_gap 0.5)
			(thermal_bridge_width 0.5)
			(island_removal_mode 0)
		)
		(polygon
			(pts
				(arc
					(start 270.891 -109.982)
					(mid 269.113 -109.982)
					(end 270.891 -109.982)
				)
			)
		)
	)
	(zone
		(layers "In1.Cu" "In3.Cu" "In6.Cu" "In8.Cu")
		(hatch none 0.5)
		(connect_pads
			(clearance 0)
		)
		(min_thickness 0.25)
		(keepout
			(tracks not_allowed)
			(vias allowed)
			(pads allowed)
			(copperpour not_allowed)
			(footprints allowed)
		)
		(placement
			(enabled no)
			(sheetname "")
		)
		(fill yes
			(thermal_gap 0.5)
			(thermal_bridge_width 0.5)
			(island_removal_mode 0)
		)
		(polygon
			(pts
				(arc
					(start 83.693 -49.784)
					(mid 81.915 -49.784)
					(end 83.693 -49.784)
				)
			)
		)
	)
	(zone
		(layers "In1.Cu" "In3.Cu" "In6.Cu" "In8.Cu")
		(hatch none 0.5)
		(connect_pads
			(clearance 0)
		)
		(min_thickness 0.25)
		(keepout
			(tracks not_allowed)
			(vias allowed)
			(pads allowed)
			(copperpour not_allowed)
			(footprints allowed)
		)
		(placement
			(enabled no)
			(sheetname "")
		)
		(fill yes
			(thermal_gap 0.5)
			(thermal_bridge_width 0.5)
			(island_removal_mode 0)
		)
		(polygon
			(pts
				(arc
					(start 219.923868 -105.896664)
					(mid 218.145868 -105.896664)
					(end 219.923868 -105.896664)
				)
			)
		)
	)
	(zone
		(layers "In1.Cu" "In3.Cu" "In6.Cu" "In8.Cu")
		(hatch none 0.5)
		(connect_pads
			(clearance 0)
		)
		(min_thickness 0.25)
		(keepout
			(tracks not_allowed)
			(vias allowed)
			(pads allowed)
			(copperpour not_allowed)
			(footprints allowed)
		)
		(placement
			(enabled no)
			(sheetname "")
		)
		(fill yes
			(thermal_gap 0.5)
			(thermal_bridge_width 0.5)
			(island_removal_mode 0)
		)
		(polygon
			(pts
				(arc
					(start 220.736668 -97.985834)
					(mid 218.958668 -97.985834)
					(end 220.736668 -97.985834)
				)
			)
		)
	)
	(zone
		(layers "In1.Cu" "In3.Cu" "In6.Cu" "In8.Cu")
		(hatch none 0.5)
		(connect_pads
			(clearance 0)
		)
		(min_thickness 0.25)
		(keepout
			(tracks not_allowed)
			(vias allowed)
			(pads allowed)
			(copperpour not_allowed)
			(footprints allowed)
		)
		(placement
			(enabled no)
			(sheetname "")
		)
		(fill yes
			(thermal_gap 0.5)
			(thermal_bridge_width 0.5)
			(island_removal_mode 0)
		)
		(polygon
			(pts
				(arc
					(start 176.753774 -126.492)
					(mid 174.975774 -126.492)
					(end 176.753774 -126.492)
				)
			)
		)
	)
	(zone
		(layers "In1.Cu" "In3.Cu" "In6.Cu" "In8.Cu")
		(hatch none 0.5)
		(connect_pads
			(clearance 0)
		)
		(min_thickness 0.25)
		(keepout
			(tracks not_allowed)
			(vias allowed)
			(pads allowed)
			(copperpour not_allowed)
			(footprints allowed)
		)
		(placement
			(enabled no)
			(sheetname "")
		)
		(fill yes
			(thermal_gap 0.5)
			(thermal_bridge_width 0.5)
			(island_removal_mode 0)
		)
		(polygon
			(pts
				(arc
					(start 215.585802 -132.18414)
					(mid 213.807802 -132.18414)
					(end 215.585802 -132.18414)
				)
			)
		)
	)
	(zone
		(layers "In1.Cu" "In3.Cu" "In6.Cu" "In8.Cu")
		(hatch none 0.5)
		(connect_pads
			(clearance 0)
		)
		(min_thickness 0.25)
		(keepout
			(tracks not_allowed)
			(vias allowed)
			(pads allowed)
			(copperpour not_allowed)
			(footprints allowed)
		)
		(placement
			(enabled no)
			(sheetname "")
		)
		(fill yes
			(thermal_gap 0.5)
			(thermal_bridge_width 0.5)
			(island_removal_mode 0)
		)
		(polygon
			(pts
				(arc
					(start 271.653 -76.835)
					(mid 269.875 -76.835)
					(end 271.653 -76.835)
				)
			)
		)
	)
	(zone
		(layers "In1.Cu" "In3.Cu" "In6.Cu" "In8.Cu")
		(hatch none 0.5)
		(connect_pads
			(clearance 0)
		)
		(min_thickness 0.25)
		(keepout
			(tracks not_allowed)
			(vias allowed)
			(pads allowed)
			(copperpour not_allowed)
			(footprints allowed)
		)
		(placement
			(enabled no)
			(sheetname "")
		)
		(fill yes
			(thermal_gap 0.5)
			(thermal_bridge_width 0.5)
			(island_removal_mode 0)
		)
		(polygon
			(pts
				(arc
					(start 219.161868 -102.9081)
					(mid 217.383868 -102.9081)
					(end 219.161868 -102.9081)
				)
			)
		)
	)
	(zone
		(layers "In1.Cu" "In3.Cu" "In6.Cu" "In8.Cu")
		(hatch none 0.5)
		(connect_pads
			(clearance 0)
		)
		(min_thickness 0.25)
		(keepout
			(tracks not_allowed)
			(vias allowed)
			(pads allowed)
			(copperpour not_allowed)
			(footprints allowed)
		)
		(placement
			(enabled no)
			(sheetname "")
		)
		(fill yes
			(thermal_gap 0.5)
			(thermal_bridge_width 0.5)
			(island_removal_mode 0)
		)
		(polygon
			(pts
				(arc
					(start 204.00137 -120.569736)
					(mid 202.22337 -120.569736)
					(end 204.00137 -120.569736)
				)
			)
		)
	)
	(zone
		(layers "In1.Cu" "In3.Cu" "In6.Cu" "In8.Cu")
		(hatch none 0.5)
		(connect_pads
			(clearance 0)
		)
		(min_thickness 0.25)
		(keepout
			(tracks not_allowed)
			(vias allowed)
			(pads allowed)
			(copperpour not_allowed)
			(footprints allowed)
		)
		(placement
			(enabled no)
			(sheetname "")
		)
		(fill yes
			(thermal_gap 0.5)
			(thermal_bridge_width 0.5)
			(island_removal_mode 0)
		)
		(polygon
			(pts
				(arc
					(start 218.378278 -121.331736)
					(mid 216.600278 -121.331736)
					(end 218.378278 -121.331736)
				)
			)
		)
	)
	(zone
		(layers "In1.Cu" "In3.Cu" "In6.Cu" "In8.Cu")
		(hatch none 0.5)
		(connect_pads
			(clearance 0)
		)
		(min_thickness 0.25)
		(keepout
			(tracks not_allowed)
			(vias allowed)
			(pads allowed)
			(copperpour not_allowed)
			(footprints allowed)
		)
		(placement
			(enabled no)
			(sheetname "")
		)
		(fill yes
			(thermal_gap 0.5)
			(thermal_bridge_width 0.5)
			(island_removal_mode 0)
		)
		(polygon
			(pts
				(arc
					(start 135.9916 -126.492)
					(mid 134.2136 -126.492)
					(end 135.9916 -126.492)
				)
			)
		)
	)
	(zone
		(layers "In1.Cu" "In3.Cu" "In6.Cu" "In8.Cu")
		(hatch none 0.5)
		(connect_pads
			(clearance 0)
		)
		(min_thickness 0.25)
		(keepout
			(tracks not_allowed)
			(vias allowed)
			(pads allowed)
			(copperpour not_allowed)
			(footprints allowed)
		)
		(placement
			(enabled no)
			(sheetname "")
		)
		(fill yes
			(thermal_gap 0.5)
			(thermal_bridge_width 0.5)
			(island_removal_mode 0)
		)
		(polygon
			(pts
				(arc
					(start 124.5616 -126.492)
					(mid 122.7836 -126.492)
					(end 124.5616 -126.492)
				)
			)
		)
	)
	(zone
		(layers "In1.Cu" "In3.Cu" "In6.Cu" "In8.Cu")
		(hatch none 0.5)
		(connect_pads
			(clearance 0)
		)
		(min_thickness 0.25)
		(keepout
			(tracks not_allowed)
			(vias allowed)
			(pads allowed)
			(copperpour not_allowed)
			(footprints allowed)
		)
		(placement
			(enabled no)
			(sheetname "")
		)
		(fill yes
			(thermal_gap 0.5)
			(thermal_bridge_width 0.5)
			(island_removal_mode 0)
		)
		(polygon
			(pts
				(arc
					(start 40.767 -103.759)
					(mid 38.989 -103.759)
					(end 40.767 -103.759)
				)
			)
		)
	)
	(zone
		(layers "In1.Cu" "In3.Cu" "In6.Cu" "In8.Cu")
		(hatch none 0.5)
		(connect_pads
			(clearance 0)
		)
		(min_thickness 0.25)
		(keepout
			(tracks not_allowed)
			(vias allowed)
			(pads allowed)
			(copperpour not_allowed)
			(footprints allowed)
		)
		(placement
			(enabled no)
			(sheetname "")
		)
		(fill yes
			(thermal_gap 0.5)
			(thermal_bridge_width 0.5)
			(island_removal_mode 0)
		)
		(polygon
			(pts
				(arc
					(start 204.679042 -105.134664)
					(mid 202.901042 -105.134664)
					(end 204.679042 -105.134664)
				)
			)
		)
	)
	(zone
		(layers "In1.Cu" "In3.Cu" "In6.Cu" "In8.Cu")
		(hatch none 0.5)
		(connect_pads
			(clearance 0)
		)
		(min_thickness 0.25)
		(keepout
			(tracks not_allowed)
			(vias allowed)
			(pads allowed)
			(copperpour not_allowed)
			(footprints allowed)
		)
		(placement
			(enabled no)
			(sheetname "")
		)
		(fill yes
			(thermal_gap 0.5)
			(thermal_bridge_width 0.5)
			(island_removal_mode 0)
		)
		(polygon
			(pts
				(arc
					(start 220.685868 -103.6701)
					(mid 218.907868 -103.6701)
					(end 220.685868 -103.6701)
				)
			)
		)
	)
	(zone
		(layers "In1.Cu" "In3.Cu" "In6.Cu" "In8.Cu")
		(hatch none 0.5)
		(connect_pads
			(clearance 0)
		)
		(min_thickness 0.25)
		(keepout
			(tracks not_allowed)
			(vias allowed)
			(pads allowed)
			(copperpour not_allowed)
			(footprints allowed)
		)
		(placement
			(enabled no)
			(sheetname "")
		)
		(fill yes
			(thermal_gap 0.5)
			(thermal_bridge_width 0.5)
			(island_removal_mode 0)
		)
		(polygon
			(pts
				(arc
					(start 222.188278 -122.809762)
					(mid 220.410278 -122.809762)
					(end 222.188278 -122.809762)
				)
			)
		)
	)
	(zone
		(layers "In1.Cu" "In3.Cu" "In6.Cu" "In8.Cu")
		(hatch none 0.5)
		(connect_pads
			(clearance 0)
		)
		(min_thickness 0.25)
		(keepout
			(tracks not_allowed)
			(vias allowed)
			(pads allowed)
			(copperpour not_allowed)
			(footprints allowed)
		)
		(placement
			(enabled no)
			(sheetname "")
		)
		(fill yes
			(thermal_gap 0.5)
			(thermal_bridge_width 0.5)
			(island_removal_mode 0)
		)
		(polygon
			(pts
				(arc
					(start 217.825828 -132.94614)
					(mid 216.047828 -132.94614)
					(end 217.825828 -132.94614)
				)
			)
		)
	)
	(zone
		(layers "In1.Cu" "In3.Cu" "In6.Cu" "In8.Cu")
		(hatch none 0.5)
		(connect_pads
			(clearance 0)
		)
		(min_thickness 0.25)
		(keepout
			(tracks not_allowed)
			(vias allowed)
			(pads allowed)
			(copperpour not_allowed)
			(footprints allowed)
		)
		(placement
			(enabled no)
			(sheetname "")
		)
		(fill yes
			(thermal_gap 0.5)
			(thermal_bridge_width 0.5)
			(island_removal_mode 0)
		)
		(polygon
			(pts
				(arc
					(start 217.063828 -129.13614)
					(mid 215.285828 -129.13614)
					(end 217.063828 -129.13614)
				)
			)
		)
	)
	(zone
		(layers "In1.Cu" "In3.Cu" "In6.Cu" "In8.Cu")
		(hatch none 0.5)
		(connect_pads
			(clearance 0)
		)
		(min_thickness 0.25)
		(keepout
			(tracks not_allowed)
			(vias allowed)
			(pads allowed)
			(copperpour not_allowed)
			(footprints allowed)
		)
		(placement
			(enabled no)
			(sheetname "")
		)
		(fill yes
			(thermal_gap 0.5)
			(thermal_bridge_width 0.5)
			(island_removal_mode 0)
		)
		(polygon
			(pts
				(arc
					(start 270.891 -76.073)
					(mid 269.113 -76.073)
					(end 270.891 -76.073)
				)
			)
		)
	)
	(zone
		(layers "In1.Cu" "In3.Cu" "In6.Cu" "In8.Cu")
		(hatch none 0.5)
		(connect_pads
			(clearance 0)
		)
		(min_thickness 0.25)
		(keepout
			(tracks not_allowed)
			(vias allowed)
			(pads allowed)
			(copperpour not_allowed)
			(footprints allowed)
		)
		(placement
			(enabled no)
			(sheetname "")
		)
		(fill yes
			(thermal_gap 0.5)
			(thermal_bridge_width 0.5)
			(island_removal_mode 0)
		)
		(polygon
			(pts
				(arc
					(start 222.928688 -105.120948)
					(mid 221.150688 -105.120948)
					(end 222.928688 -105.120948)
				)
			)
		)
	)
	(zone
		(layers "In1.Cu" "In3.Cu" "In6.Cu" "In8.Cu")
		(hatch none 0.5)
		(connect_pads
			(clearance 0)
		)
		(min_thickness 0.25)
		(keepout
			(tracks not_allowed)
			(vias allowed)
			(pads allowed)
			(copperpour not_allowed)
			(footprints allowed)
		)
		(placement
			(enabled no)
			(sheetname "")
		)
		(fill yes
			(thermal_gap 0.5)
			(thermal_bridge_width 0.5)
			(island_removal_mode 0)
		)
		(polygon
			(pts
				(arc
					(start 233.95813 -126.609094)
					(mid 232.18013 -126.609094)
					(end 233.95813 -126.609094)
				)
			)
		)
	)
	(zone
		(layers "In1.Cu" "In3.Cu" "In6.Cu" "In8.Cu")
		(hatch none 0.5)
		(connect_pads
			(clearance 0)
		)
		(min_thickness 0.25)
		(keepout
			(tracks not_allowed)
			(vias allowed)
			(pads allowed)
			(copperpour not_allowed)
			(footprints allowed)
		)
		(placement
			(enabled no)
			(sheetname "")
		)
		(fill yes
			(thermal_gap 0.5)
			(thermal_bridge_width 0.5)
			(island_removal_mode 0)
		)
		(polygon
			(pts
				(arc
					(start 204.00137 -122.047762)
					(mid 202.22337 -122.047762)
					(end 204.00137 -122.047762)
				)
			)
		)
	)
	(zone
		(layers "In1.Cu" "In3.Cu" "In6.Cu" "In8.Cu")
		(hatch none 0.5)
		(connect_pads
			(clearance 0)
		)
		(min_thickness 0.25)
		(keepout
			(tracks not_allowed)
			(vias allowed)
			(pads allowed)
			(copperpour not_allowed)
			(footprints allowed)
		)
		(placement
			(enabled no)
			(sheetname "")
		)
		(fill yes
			(thermal_gap 0.5)
			(thermal_bridge_width 0.5)
			(island_removal_mode 0)
		)
		(polygon
			(pts
				(arc
					(start 219.140278 -122.809762)
					(mid 217.362278 -122.809762)
					(end 219.140278 -122.809762)
				)
			)
		)
	)
	(zone
		(layers "In1.Cu" "In3.Cu" "In6.Cu" "In8.Cu")
		(hatch none 0.5)
		(connect_pads
			(clearance 0)
		)
		(min_thickness 0.25)
		(keepout
			(tracks not_allowed)
			(vias allowed)
			(pads allowed)
			(copperpour not_allowed)
			(footprints allowed)
		)
		(placement
			(enabled no)
			(sheetname "")
		)
		(fill yes
			(thermal_gap 0.5)
			(thermal_bridge_width 0.5)
			(island_removal_mode 0)
		)
		(polygon
			(pts
				(arc
					(start 32.131 -106.045)
					(mid 30.353 -106.045)
					(end 32.131 -106.045)
				)
			)
		)
	)
	(zone
		(layers "In1.Cu" "In3.Cu" "In6.Cu" "In8.Cu")
		(hatch none 0.5)
		(connect_pads
			(clearance 0)
		)
		(min_thickness 0.25)
		(keepout
			(tracks not_allowed)
			(vias allowed)
			(pads allowed)
			(copperpour not_allowed)
			(footprints allowed)
		)
		(placement
			(enabled no)
			(sheetname "")
		)
		(fill yes
			(thermal_gap 0.5)
			(thermal_bridge_width 0.5)
			(island_removal_mode 0)
		)
		(polygon
			(pts
				(arc
					(start 218.399868 -105.134664)
					(mid 216.621868 -105.134664)
					(end 218.399868 -105.134664)
				)
			)
		)
	)
	(zone
		(layers "In1.Cu" "In3.Cu" "In6.Cu" "In8.Cu")
		(hatch none 0.5)
		(connect_pads
			(clearance 0)
		)
		(min_thickness 0.25)
		(keepout
			(tracks not_allowed)
			(vias allowed)
			(pads allowed)
			(copperpour not_allowed)
			(footprints allowed)
		)
		(placement
			(enabled no)
			(sheetname "")
		)
		(fill yes
			(thermal_gap 0.5)
			(thermal_bridge_width 0.5)
			(island_removal_mode 0)
		)
		(polygon
			(pts
				(arc
					(start 272.415 -62.484)
					(mid 270.637 -62.484)
					(end 272.415 -62.484)
				)
			)
		)
	)
	(zone
		(layers "In1.Cu" "In3.Cu" "In6.Cu" "In8.Cu")
		(hatch none 0.5)
		(connect_pads
			(clearance 0)
		)
		(min_thickness 0.25)
		(keepout
			(tracks not_allowed)
			(vias allowed)
			(pads allowed)
			(copperpour not_allowed)
			(footprints allowed)
		)
		(placement
			(enabled no)
			(sheetname "")
		)
		(fill yes
			(thermal_gap 0.5)
			(thermal_bridge_width 0.5)
			(island_removal_mode 0)
		)
		(polygon
			(pts
				(arc
					(start 222.950278 -120.569736)
					(mid 221.172278 -120.569736)
					(end 222.950278 -120.569736)
				)
			)
		)
	)
	(zone
		(layers "In1.Cu" "In3.Cu" "In6.Cu" "In8.Cu")
		(hatch none 0.5)
		(connect_pads
			(clearance 0)
		)
		(min_thickness 0.25)
		(keepout
			(tracks not_allowed)
			(vias allowed)
			(pads allowed)
			(copperpour not_allowed)
			(footprints allowed)
		)
		(placement
			(enabled no)
			(sheetname "")
		)
		(fill yes
			(thermal_gap 0.5)
			(thermal_bridge_width 0.5)
			(island_removal_mode 0)
		)
		(polygon
			(pts
				(arc
					(start 178.17846 -50.292)
					(mid 176.40046 -50.292)
					(end 178.17846 -50.292)
				)
			)
		)
	)
	(zone
		(layers "In1.Cu" "In3.Cu" "In6.Cu" "In8.Cu")
		(hatch none 0.5)
		(connect_pads
			(clearance 0)
		)
		(min_thickness 0.25)
		(keepout
			(tracks not_allowed)
			(vias allowed)
			(pads allowed)
			(copperpour not_allowed)
			(footprints allowed)
		)
		(placement
			(enabled no)
			(sheetname "")
		)
		(fill yes
			(thermal_gap 0.5)
			(thermal_bridge_width 0.5)
			(island_removal_mode 0)
		)
		(polygon
			(pts
				(arc
					(start 204.679042 -105.896664)
					(mid 202.901042 -105.896664)
					(end 204.679042 -105.896664)
				)
			)
		)
	)
	(zone
		(layers "In1.Cu" "In3.Cu" "In6.Cu" "In8.Cu")
		(hatch none 0.5)
		(connect_pads
			(clearance 0)
		)
		(min_thickness 0.25)
		(keepout
			(tracks not_allowed)
			(vias allowed)
			(pads allowed)
			(copperpour not_allowed)
			(footprints allowed)
		)
		(placement
			(enabled no)
			(sheetname "")
		)
		(fill yes
			(thermal_gap 0.5)
			(thermal_bridge_width 0.5)
			(island_removal_mode 0)
		)
		(polygon
			(pts
				(arc
					(start 270.891 -75.311)
					(mid 269.113 -75.311)
					(end 270.891 -75.311)
				)
			)
		)
	)
	(zone
		(layers "In1.Cu" "In3.Cu" "In6.Cu" "In8.Cu")
		(hatch none 0.5)
		(connect_pads
			(clearance 0)
		)
		(min_thickness 0.25)
		(keepout
			(tracks not_allowed)
			(vias allowed)
			(pads allowed)
			(copperpour not_allowed)
			(footprints allowed)
		)
		(placement
			(enabled no)
			(sheetname "")
		)
		(fill yes
			(thermal_gap 0.5)
			(thermal_bridge_width 0.5)
			(island_removal_mode 0)
		)
		(polygon
			(pts
				(arc
					(start 42.2529 -58.604912)
					(mid 40.4749 -58.604912)
					(end 42.2529 -58.604912)
				)
			)
		)
	)
	(zone
		(layers "In1.Cu" "In3.Cu" "In6.Cu" "In8.Cu")
		(hatch none 0.5)
		(connect_pads
			(clearance 0)
		)
		(min_thickness 0.25)
		(keepout
			(tracks not_allowed)
			(vias allowed)
			(pads allowed)
			(copperpour not_allowed)
			(footprints allowed)
		)
		(placement
			(enabled no)
			(sheetname "")
		)
		(fill yes
			(thermal_gap 0.5)
			(thermal_bridge_width 0.5)
			(island_removal_mode 0)
		)
		(polygon
			(pts
				(arc
					(start 215.585802 -128.37414)
					(mid 213.807802 -128.37414)
					(end 215.585802 -128.37414)
				)
			)
		)
	)
	(zone
		(layers "In1.Cu" "In3.Cu" "In6.Cu" "In8.Cu")
		(hatch none 0.5)
		(connect_pads
			(clearance 0)
		)
		(min_thickness 0.25)
		(keepout
			(tracks not_allowed)
			(vias allowed)
			(pads allowed)
			(copperpour not_allowed)
			(footprints allowed)
		)
		(placement
			(enabled no)
			(sheetname "")
		)
		(fill yes
			(thermal_gap 0.5)
			(thermal_bridge_width 0.5)
			(island_removal_mode 0)
		)
		(polygon
			(pts
				(arc
					(start 208.445862 -102.894384)
					(mid 206.667862 -102.894384)
					(end 208.445862 -102.894384)
				)
			)
		)
	)
	(zone
		(layers "In1.Cu" "In3.Cu" "In6.Cu" "In8.Cu")
		(hatch none 0.5)
		(connect_pads
			(clearance 0)
		)
		(min_thickness 0.25)
		(keepout
			(tracks not_allowed)
			(vias allowed)
			(pads allowed)
			(copperpour not_allowed)
			(footprints allowed)
		)
		(placement
			(enabled no)
			(sheetname "")
		)
		(fill yes
			(thermal_gap 0.5)
			(thermal_bridge_width 0.5)
			(island_removal_mode 0)
		)
		(polygon
			(pts
				(arc
					(start 205.52537 -120.569736)
					(mid 203.74737 -120.569736)
					(end 205.52537 -120.569736)
				)
			)
		)
	)
	(zone
		(layers "In1.Cu" "In3.Cu" "In6.Cu" "In8.Cu")
		(hatch none 0.5)
		(connect_pads
			(clearance 0)
		)
		(min_thickness 0.25)
		(keepout
			(tracks not_allowed)
			(vias allowed)
			(pads allowed)
			(copperpour not_allowed)
			(footprints allowed)
		)
		(placement
			(enabled no)
			(sheetname "")
		)
		(fill yes
			(thermal_gap 0.5)
			(thermal_bridge_width 0.5)
			(island_removal_mode 0)
		)
		(polygon
			(pts
				(arc
					(start 273.177 -125.857)
					(mid 271.399 -125.857)
					(end 273.177 -125.857)
				)
			)
		)
	)
	(zone
		(layers "In1.Cu" "In3.Cu" "In6.Cu" "In8.Cu")
		(hatch none 0.5)
		(connect_pads
			(clearance 0)
		)
		(min_thickness 0.25)
		(keepout
			(tracks not_allowed)
			(vias allowed)
			(pads allowed)
			(copperpour not_allowed)
			(footprints allowed)
		)
		(placement
			(enabled no)
			(sheetname "")
		)
		(fill yes
			(thermal_gap 0.5)
			(thermal_bridge_width 0.5)
			(island_removal_mode 0)
		)
		(polygon
			(pts
				(arc
					(start 172.72 -49.657)
					(mid 170.942 -49.657)
					(end 172.72 -49.657)
				)
			)
		)
	)
	(zone
		(layers "In1.Cu" "In3.Cu" "In6.Cu" "In8.Cu")
		(hatch none 0.5)
		(connect_pads
			(clearance 0)
		)
		(min_thickness 0.25)
		(keepout
			(tracks not_allowed)
			(vias allowed)
			(pads allowed)
			(copperpour not_allowed)
			(footprints allowed)
		)
		(placement
			(enabled no)
			(sheetname "")
		)
		(fill yes
			(thermal_gap 0.5)
			(thermal_bridge_width 0.5)
			(island_removal_mode 0)
		)
		(polygon
			(pts
				(arc
					(start 272.542 -139.7)
					(mid 270.764 -139.7)
					(end 272.542 -139.7)
				)
			)
		)
	)
	(zone
		(layers "In1.Cu" "In3.Cu" "In6.Cu" "In8.Cu")
		(hatch none 0.5)
		(connect_pads
			(clearance 0)
		)
		(min_thickness 0.25)
		(keepout
			(tracks not_allowed)
			(vias allowed)
			(pads allowed)
			(copperpour not_allowed)
			(footprints allowed)
		)
		(placement
			(enabled no)
			(sheetname "")
		)
		(fill yes
			(thermal_gap 0.5)
			(thermal_bridge_width 0.5)
			(island_removal_mode 0)
		)
		(polygon
			(pts
				(arc
					(start 222.209868 -104.4321)
					(mid 220.431868 -104.4321)
					(end 222.209868 -104.4321)
				)
			)
		)
	)
	(zone
		(layers "In1.Cu" "In3.Cu" "In6.Cu" "In8.Cu")
		(hatch none 0.5)
		(connect_pads
			(clearance 0)
		)
		(min_thickness 0.25)
		(keepout
			(tracks not_allowed)
			(vias allowed)
			(pads allowed)
			(copperpour not_allowed)
			(footprints allowed)
		)
		(placement
			(enabled no)
			(sheetname "")
		)
		(fill yes
			(thermal_gap 0.5)
			(thermal_bridge_width 0.5)
			(island_removal_mode 0)
		)
		(polygon
			(pts
				(arc
					(start 272.415 -122.809)
					(mid 270.637 -122.809)
					(end 272.415 -122.809)
				)
			)
		)
	)
	(zone
		(layers "In1.Cu" "In3.Cu" "In6.Cu" "In8.Cu")
		(hatch none 0.5)
		(connect_pads
			(clearance 0)
		)
		(min_thickness 0.25)
		(keepout
			(tracks not_allowed)
			(vias allowed)
			(pads allowed)
			(copperpour not_allowed)
			(footprints allowed)
		)
		(placement
			(enabled no)
			(sheetname "")
		)
		(fill yes
			(thermal_gap 0.5)
			(thermal_bridge_width 0.5)
			(island_removal_mode 0)
		)
		(polygon
			(pts
				(arc
					(start 203.917042 -103.6701)
					(mid 202.139042 -103.6701)
					(end 203.917042 -103.6701)
				)
			)
		)
	)
	(zone
		(layers "In1.Cu" "In3.Cu" "In6.Cu" "In8.Cu")
		(hatch none 0.5)
		(connect_pads
			(clearance 0)
		)
		(min_thickness 0.25)
		(keepout
			(tracks not_allowed)
			(vias allowed)
			(pads allowed)
			(copperpour not_allowed)
			(footprints allowed)
		)
		(placement
			(enabled no)
			(sheetname "")
		)
		(fill yes
			(thermal_gap 0.5)
			(thermal_bridge_width 0.5)
			(island_removal_mode 0)
		)
		(polygon
			(pts
				(arc
					(start 235.468668 -130.348736)
					(mid 233.690668 -130.348736)
					(end 235.468668 -130.348736)
				)
			)
		)
	)
	(zone
		(layers "In1.Cu" "In3.Cu" "In6.Cu" "In8.Cu")
		(hatch none 0.5)
		(connect_pads
			(clearance 0)
		)
		(min_thickness 0.25)
		(keepout
			(tracks not_allowed)
			(vias allowed)
			(pads allowed)
			(copperpour not_allowed)
			(footprints allowed)
		)
		(placement
			(enabled no)
			(sheetname "")
		)
		(fill yes
			(thermal_gap 0.5)
			(thermal_bridge_width 0.5)
			(island_removal_mode 0)
		)
		(polygon
			(pts
				(arc
					(start 271.653 -113.03)
					(mid 269.875 -113.03)
					(end 271.653 -113.03)
				)
			)
		)
	)
	(zone
		(layers "In1.Cu" "In3.Cu" "In6.Cu" "In8.Cu")
		(hatch none 0.5)
		(connect_pads
			(clearance 0)
		)
		(min_thickness 0.25)
		(keepout
			(tracks not_allowed)
			(vias allowed)
			(pads allowed)
			(copperpour not_allowed)
			(footprints allowed)
		)
		(placement
			(enabled no)
			(sheetname "")
		)
		(fill yes
			(thermal_gap 0.5)
			(thermal_bridge_width 0.5)
			(island_removal_mode 0)
		)
		(polygon
			(pts
				(arc
					(start 206.965042 -102.9081)
					(mid 205.187042 -102.9081)
					(end 206.965042 -102.9081)
				)
			)
		)
	)
	(zone
		(layers "In1.Cu" "In3.Cu" "In6.Cu" "In8.Cu")
		(hatch none 0.5)
		(connect_pads
			(clearance 0)
		)
		(min_thickness 0.25)
		(keepout
			(tracks not_allowed)
			(vias allowed)
			(pads allowed)
			(copperpour not_allowed)
			(footprints allowed)
		)
		(placement
			(enabled no)
			(sheetname "")
		)
		(fill yes
			(thermal_gap 0.5)
			(thermal_bridge_width 0.5)
			(island_removal_mode 0)
		)
		(polygon
			(pts
				(arc
					(start 273.177 -97.917)
					(mid 271.399 -97.917)
					(end 273.177 -97.917)
				)
			)
		)
	)
	(zone
		(layers "In1.Cu" "In3.Cu" "In6.Cu" "In8.Cu")
		(hatch none 0.5)
		(connect_pads
			(clearance 0)
		)
		(min_thickness 0.25)
		(keepout
			(tracks not_allowed)
			(vias allowed)
			(pads allowed)
			(copperpour not_allowed)
			(footprints allowed)
		)
		(placement
			(enabled no)
			(sheetname "")
		)
		(fill yes
			(thermal_gap 0.5)
			(thermal_bridge_width 0.5)
			(island_removal_mode 0)
		)
		(polygon
			(pts
				(arc
					(start 271.653 -65.532)
					(mid 269.875 -65.532)
					(end 271.653 -65.532)
				)
			)
		)
	)
	(zone
		(layers "In1.Cu" "In3.Cu" "In6.Cu" "In8.Cu")
		(hatch none 0.5)
		(connect_pads
			(clearance 0)
		)
		(min_thickness 0.25)
		(keepout
			(tracks not_allowed)
			(vias allowed)
			(pads allowed)
			(copperpour not_allowed)
			(footprints allowed)
		)
		(placement
			(enabled no)
			(sheetname "")
		)
		(fill yes
			(thermal_gap 0.5)
			(thermal_bridge_width 0.5)
			(island_removal_mode 0)
		)
		(polygon
			(pts
				(arc
					(start 203.23937 -121.331736)
					(mid 201.46137 -121.331736)
					(end 203.23937 -121.331736)
				)
			)
		)
	)
	(zone
		(layers "In1.Cu" "In3.Cu" "In6.Cu" "In8.Cu")
		(hatch none 0.5)
		(connect_pads
			(clearance 0)
		)
		(min_thickness 0.25)
		(keepout
			(tracks not_allowed)
			(vias allowed)
			(pads allowed)
			(copperpour not_allowed)
			(footprints allowed)
		)
		(placement
			(enabled no)
			(sheetname "")
		)
		(fill yes
			(thermal_gap 0.5)
			(thermal_bridge_width 0.5)
			(island_removal_mode 0)
		)
		(polygon
			(pts
				(arc
					(start 108.945426 -131.572)
					(mid 107.167426 -131.572)
					(end 108.945426 -131.572)
				)
			)
		)
	)
	(zone
		(layers "In1.Cu" "In3.Cu" "In6.Cu" "In8.Cu")
		(hatch none 0.5)
		(connect_pads
			(clearance 0)
		)
		(min_thickness 0.25)
		(keepout
			(tracks not_allowed)
			(vias allowed)
			(pads allowed)
			(copperpour not_allowed)
			(footprints allowed)
		)
		(placement
			(enabled no)
			(sheetname "")
		)
		(fill yes
			(thermal_gap 0.5)
			(thermal_bridge_width 0.5)
			(island_removal_mode 0)
		)
		(polygon
			(pts
				(arc
					(start 148.9456 -131.572)
					(mid 147.1676 -131.572)
					(end 148.9456 -131.572)
				)
			)
		)
	)
	(zone
		(layers "In1.Cu" "In3.Cu" "In6.Cu" "In8.Cu")
		(hatch none 0.5)
		(connect_pads
			(clearance 0)
		)
		(min_thickness 0.25)
		(keepout
			(tracks not_allowed)
			(vias allowed)
			(pads allowed)
			(copperpour not_allowed)
			(footprints allowed)
		)
		(placement
			(enabled no)
			(sheetname "")
		)
		(fill yes
			(thermal_gap 0.5)
			(thermal_bridge_width 0.5)
			(island_removal_mode 0)
		)
		(polygon
			(pts
				(arc
					(start 172.72 -51.562)
					(mid 170.942 -51.562)
					(end 172.72 -51.562)
				)
			)
		)
	)
	(zone
		(layers "In1.Cu" "In3.Cu" "In6.Cu" "In8.Cu")
		(hatch none 0.5)
		(connect_pads
			(clearance 0)
		)
		(min_thickness 0.25)
		(keepout
			(tracks not_allowed)
			(vias allowed)
			(pads allowed)
			(copperpour not_allowed)
			(footprints allowed)
		)
		(placement
			(enabled no)
			(sheetname "")
		)
		(fill yes
			(thermal_gap 0.5)
			(thermal_bridge_width 0.5)
			(island_removal_mode 0)
		)
		(polygon
			(pts
				(arc
					(start 233.242104 -128.824736)
					(mid 231.464104 -128.824736)
					(end 233.242104 -128.824736)
				)
			)
		)
	)
	(zone
		(layers "In1.Cu" "In3.Cu" "In6.Cu" "In8.Cu")
		(hatch none 0.5)
		(connect_pads
			(clearance 0)
		)
		(min_thickness 0.25)
		(keepout
			(tracks not_allowed)
			(vias allowed)
			(pads allowed)
			(copperpour not_allowed)
			(footprints allowed)
		)
		(placement
			(enabled no)
			(sheetname "")
		)
		(fill yes
			(thermal_gap 0.5)
			(thermal_bridge_width 0.5)
			(island_removal_mode 0)
		)
		(polygon
			(pts
				(arc
					(start 72.318626 -69.869812)
					(mid 70.540626 -69.869812)
					(end 72.318626 -69.869812)
				)
			)
		)
	)
	(zone
		(layers "In1.Cu" "In3.Cu" "In6.Cu" "In8.Cu")
		(hatch none 0.5)
		(connect_pads
			(clearance 0)
		)
		(min_thickness 0.25)
		(keepout
			(tracks not_allowed)
			(vias allowed)
			(pads allowed)
			(copperpour not_allowed)
			(footprints allowed)
		)
		(placement
			(enabled no)
			(sheetname "")
		)
		(fill yes
			(thermal_gap 0.5)
			(thermal_bridge_width 0.5)
			(island_removal_mode 0)
		)
		(polygon
			(pts
				(arc
					(start 218.391994 -123.528328)
					(mid 216.613994 -123.528328)
					(end 218.391994 -123.528328)
				)
			)
		)
	)
	(zone
		(layers "In1.Cu" "In3.Cu" "In6.Cu" "In8.Cu")
		(hatch none 0.5)
		(connect_pads
			(clearance 0)
		)
		(min_thickness 0.25)
		(keepout
			(tracks not_allowed)
			(vias allowed)
			(pads allowed)
			(copperpour not_allowed)
			(footprints allowed)
		)
		(placement
			(enabled no)
			(sheetname "")
		)
		(fill yes
			(thermal_gap 0.5)
			(thermal_bridge_width 0.5)
			(island_removal_mode 0)
		)
		(polygon
			(pts
				(arc
					(start 175.991774 -131.572)
					(mid 174.213774 -131.572)
					(end 175.991774 -131.572)
				)
			)
		)
	)
	(zone
		(layers "In1.Cu" "In3.Cu" "In6.Cu" "In8.Cu")
		(hatch none 0.5)
		(connect_pads
			(clearance 0)
		)
		(min_thickness 0.25)
		(keepout
			(tracks not_allowed)
			(vias allowed)
			(pads allowed)
			(copperpour not_allowed)
			(footprints allowed)
		)
		(placement
			(enabled no)
			(sheetname "")
		)
		(fill yes
			(thermal_gap 0.5)
			(thermal_bridge_width 0.5)
			(island_removal_mode 0)
		)
		(polygon
			(pts
				(arc
					(start 66.286126 -121.209816)
					(mid 62.653926 -121.209816)
					(end 66.286126 -121.209816)
				)
			)
		)
	)
	(zone
		(layers "In1.Cu" "In3.Cu" "In6.Cu" "In8.Cu")
		(hatch none 0.5)
		(connect_pads
			(clearance 0)
		)
		(min_thickness 0.25)
		(keepout
			(tracks not_allowed)
			(vias allowed)
			(pads allowed)
			(copperpour not_allowed)
			(footprints allowed)
		)
		(placement
			(enabled no)
			(sheetname "")
		)
		(fill yes
			(thermal_gap 0.5)
			(thermal_bridge_width 0.5)
			(island_removal_mode 0)
		)
		(polygon
			(pts
				(arc
					(start 270.129 -101.727)
					(mid 268.351 -101.727)
					(end 270.129 -101.727)
				)
			)
		)
	)
	(zone
		(layers "In1.Cu" "In3.Cu" "In6.Cu" "In8.Cu")
		(hatch none 0.5)
		(connect_pads
			(clearance 0)
		)
		(min_thickness 0.25)
		(keepout
			(tracks not_allowed)
			(vias allowed)
			(pads allowed)
			(copperpour not_allowed)
			(footprints allowed)
		)
		(placement
			(enabled no)
			(sheetname "")
		)
		(fill yes
			(thermal_gap 0.5)
			(thermal_bridge_width 0.5)
			(island_removal_mode 0)
		)
		(polygon
			(pts
				(arc
					(start 204.679042 -102.9081)
					(mid 202.901042 -102.9081)
					(end 204.679042 -102.9081)
				)
			)
		)
	)
	(zone
		(layers "In1.Cu" "In3.Cu" "In6.Cu" "In8.Cu")
		(hatch none 0.5)
		(connect_pads
			(clearance 0)
		)
		(min_thickness 0.25)
		(keepout
			(tracks not_allowed)
			(vias allowed)
			(pads allowed)
			(copperpour not_allowed)
			(footprints allowed)
		)
		(placement
			(enabled no)
			(sheetname "")
		)
		(fill yes
			(thermal_gap 0.5)
			(thermal_bridge_width 0.5)
			(island_removal_mode 0)
		)
		(polygon
			(pts
				(arc
					(start 271.653 -64.008)
					(mid 269.875 -64.008)
					(end 271.653 -64.008)
				)
			)
		)
	)
	(zone
		(layers "In1.Cu" "In3.Cu" "In6.Cu" "In8.Cu")
		(hatch none 0.5)
		(connect_pads
			(clearance 0)
		)
		(min_thickness 0.25)
		(keepout
			(tracks not_allowed)
			(vias allowed)
			(pads allowed)
			(copperpour not_allowed)
			(footprints allowed)
		)
		(placement
			(enabled no)
			(sheetname "")
		)
		(fill yes
			(thermal_gap 0.5)
			(thermal_bridge_width 0.5)
			(island_removal_mode 0)
		)
		(polygon
			(pts
				(arc
					(start 207.81137 -120.569736)
					(mid 206.03337 -120.569736)
					(end 207.81137 -120.569736)
				)
			)
		)
	)
	(zone
		(layers "In1.Cu" "In3.Cu" "In6.Cu" "In8.Cu")
		(hatch none 0.5)
		(connect_pads
			(clearance 0)
		)
		(min_thickness 0.25)
		(keepout
			(tracks not_allowed)
			(vias allowed)
			(pads allowed)
			(copperpour not_allowed)
			(footprints allowed)
		)
		(placement
			(enabled no)
			(sheetname "")
		)
		(fill yes
			(thermal_gap 0.5)
			(thermal_bridge_width 0.5)
			(island_removal_mode 0)
		)
		(polygon
			(pts
				(arc
					(start 235.48213 -126.609094)
					(mid 233.70413 -126.609094)
					(end 235.48213 -126.609094)
				)
			)
		)
	)
	(zone
		(layers "In1.Cu" "In3.Cu" "In6.Cu" "In8.Cu")
		(hatch none 0.5)
		(connect_pads
			(clearance 0)
		)
		(min_thickness 0.25)
		(keepout
			(tracks not_allowed)
			(vias allowed)
			(pads allowed)
			(copperpour not_allowed)
			(footprints allowed)
		)
		(placement
			(enabled no)
			(sheetname "")
		)
		(fill yes
			(thermal_gap 0.5)
			(thermal_bridge_width 0.5)
			(island_removal_mode 0)
		)
		(polygon
			(pts
				(arc
					(start 235.468668 -128.062736)
					(mid 233.690668 -128.062736)
					(end 235.468668 -128.062736)
				)
			)
		)
	)
	(zone
		(layers "In1.Cu" "In3.Cu" "In6.Cu" "In8.Cu")
		(hatch none 0.5)
		(connect_pads
			(clearance 0)
		)
		(min_thickness 0.25)
		(keepout
			(tracks not_allowed)
			(vias allowed)
			(pads allowed)
			(copperpour not_allowed)
			(footprints allowed)
		)
		(placement
			(enabled no)
			(sheetname "")
		)
		(fill yes
			(thermal_gap 0.5)
			(thermal_bridge_width 0.5)
			(island_removal_mode 0)
		)
		(polygon
			(pts
				(arc
					(start 216.347802 -132.94614)
					(mid 214.569802 -132.94614)
					(end 216.347802 -132.94614)
				)
			)
		)
	)
	(zone
		(layers "In1.Cu" "In3.Cu" "In6.Cu" "In8.Cu")
		(hatch none 0.5)
		(connect_pads
			(clearance 0)
		)
		(min_thickness 0.25)
		(keepout
			(tracks not_allowed)
			(vias allowed)
			(pads allowed)
			(copperpour not_allowed)
			(footprints allowed)
		)
		(placement
			(enabled no)
			(sheetname "")
		)
		(fill yes
			(thermal_gap 0.5)
			(thermal_bridge_width 0.5)
			(island_removal_mode 0)
		)
		(polygon
			(pts
				(arc
					(start 271.78 -140.462)
					(mid 270.002 -140.462)
					(end 271.78 -140.462)
				)
			)
		)
	)
	(zone
		(layers "In1.Cu" "In3.Cu" "In6.Cu" "In8.Cu")
		(hatch none 0.5)
		(connect_pads
			(clearance 0)
		)
		(min_thickness 0.25)
		(keepout
			(tracks not_allowed)
			(vias allowed)
			(pads allowed)
			(copperpour not_allowed)
			(footprints allowed)
		)
		(placement
			(enabled no)
			(sheetname "")
		)
		(fill yes
			(thermal_gap 0.5)
			(thermal_bridge_width 0.5)
			(island_removal_mode 0)
		)
		(polygon
			(pts
				(arc
					(start 270.891 -61.722)
					(mid 269.113 -61.722)
					(end 270.891 -61.722)
				)
			)
		)
	)
	(zone
		(layers "In1.Cu" "In3.Cu" "In6.Cu" "In8.Cu")
		(hatch none 0.5)
		(connect_pads
			(clearance 0)
		)
		(min_thickness 0.25)
		(keepout
			(tracks not_allowed)
			(vias allowed)
			(pads allowed)
			(copperpour not_allowed)
			(footprints allowed)
		)
		(placement
			(enabled no)
			(sheetname "")
		)
		(fill yes
			(thermal_gap 0.5)
			(thermal_bridge_width 0.5)
			(island_removal_mode 0)
		)
		(polygon
			(pts
				(arc
					(start 13.76172 -74.319892)
					(mid 11.01852 -74.319892)
					(end 13.76172 -74.319892)
				)
			)
		)
	)
	(zone
		(layers "In1.Cu" "In3.Cu" "In6.Cu" "In8.Cu")
		(hatch none 0.5)
		(connect_pads
			(clearance 0)
		)
		(min_thickness 0.25)
		(keepout
			(tracks not_allowed)
			(vias allowed)
			(pads allowed)
			(copperpour not_allowed)
			(footprints allowed)
		)
		(placement
			(enabled no)
			(sheetname "")
		)
		(fill yes
			(thermal_gap 0.5)
			(thermal_bridge_width 0.5)
			(island_removal_mode 0)
		)
		(polygon
			(pts
				(arc
					(start 214.867236 -130.673856)
					(mid 213.089236 -130.673856)
					(end 214.867236 -130.673856)
				)
			)
		)
	)
	(zone
		(layers "In1.Cu" "In3.Cu" "In6.Cu" "In8.Cu")
		(hatch none 0.5)
		(connect_pads
			(clearance 0)
		)
		(min_thickness 0.25)
		(keepout
			(tracks not_allowed)
			(vias allowed)
			(pads allowed)
			(copperpour not_allowed)
			(footprints allowed)
		)
		(placement
			(enabled no)
			(sheetname "")
		)
		(fill yes
			(thermal_gap 0.5)
			(thermal_bridge_width 0.5)
			(island_removal_mode 0)
		)
		(polygon
			(pts
				(arc
					(start 270.891 -125.857)
					(mid 269.113 -125.857)
					(end 270.891 -125.857)
				)
			)
		)
	)
	(zone
		(layers "In1.Cu" "In3.Cu" "In6.Cu" "In8.Cu")
		(hatch none 0.5)
		(connect_pads
			(clearance 0)
		)
		(min_thickness 0.25)
		(keepout
			(tracks not_allowed)
			(vias allowed)
			(pads allowed)
			(copperpour not_allowed)
			(footprints allowed)
		)
		(placement
			(enabled no)
			(sheetname "")
		)
		(fill yes
			(thermal_gap 0.5)
			(thermal_bridge_width 0.5)
			(island_removal_mode 0)
		)
		(polygon
			(pts
				(arc
					(start 271.653 -88.138)
					(mid 269.875 -88.138)
					(end 271.653 -88.138)
				)
			)
		)
	)
	(zone
		(layers "In1.Cu" "In3.Cu" "In6.Cu" "In8.Cu")
		(hatch none 0.5)
		(connect_pads
			(clearance 0)
		)
		(min_thickness 0.25)
		(keepout
			(tracks not_allowed)
			(vias allowed)
			(pads allowed)
			(copperpour not_allowed)
			(footprints allowed)
		)
		(placement
			(enabled no)
			(sheetname "")
		)
		(fill yes
			(thermal_gap 0.5)
			(thermal_bridge_width 0.5)
			(island_removal_mode 0)
		)
		(polygon
			(pts
				(arc
					(start 273.177 -113.792)
					(mid 271.399 -113.792)
					(end 273.177 -113.792)
				)
			)
		)
	)
	(zone
		(layers "In1.Cu" "In3.Cu" "In6.Cu" "In8.Cu")
		(hatch none 0.5)
		(connect_pads
			(clearance 0)
		)
		(min_thickness 0.25)
		(keepout
			(tracks not_allowed)
			(vias allowed)
			(pads allowed)
			(copperpour not_allowed)
			(footprints allowed)
		)
		(placement
			(enabled no)
			(sheetname "")
		)
		(fill yes
			(thermal_gap 0.5)
			(thermal_bridge_width 0.5)
			(island_removal_mode 0)
		)
		(polygon
			(pts
				(arc
					(start 50.96764 -52.1208)
					(mid 49.18964 -52.1208)
					(end 50.96764 -52.1208)
				)
			)
		)
	)
	(zone
		(layers "In1.Cu" "In3.Cu" "In6.Cu" "In8.Cu")
		(hatch none 0.5)
		(connect_pads
			(clearance 0)
		)
		(min_thickness 0.25)
		(keepout
			(tracks not_allowed)
			(vias allowed)
			(pads allowed)
			(copperpour not_allowed)
			(footprints allowed)
		)
		(placement
			(enabled no)
			(sheetname "")
		)
		(fill yes
			(thermal_gap 0.5)
			(thermal_bridge_width 0.5)
			(island_removal_mode 0)
		)
		(polygon
			(pts
				(arc
					(start 288.29 -30.687264)
					(mid 286.512 -30.687264)
					(end 288.29 -30.687264)
				)
			)
		)
	)
	(zone
		(layer "In2.Cu")
		(hatch none 0.5)
		(connect_pads
			(clearance 0)
		)
		(min_thickness 0.25)
		(keepout
			(tracks not_allowed)
			(vias allowed)
			(pads allowed)
			(copperpour not_allowed)
			(footprints allowed)
		)
		(placement
			(enabled no)
			(sheetname "")
		)
		(fill
			(thermal_gap 0.5)
			(thermal_bridge_width 0.5)
			(island_removal_mode 0)
		)
		(polygon
			(pts
				(arc
					(start 108.000038 -5.729986)
					(mid 101.730048 -11.999976)
					(end 108.000038 -18.269966)
				)
				(arc
					(start 129.999994 -18.269966)
					(mid 136.269984 -11.999976)
					(end 129.999994 -5.729986)
				)
			)
		)
	)
	(zone
		(layers "In2.Cu" "In4.Cu" "In5.Cu" "In7.Cu")
		(hatch none 0.5)
		(connect_pads
			(clearance 0)
		)
		(min_thickness 0.25)
		(keepout
			(tracks not_allowed)
			(vias allowed)
			(pads allowed)
			(copperpour not_allowed)
			(footprints allowed)
		)
		(placement
			(enabled no)
			(sheetname "")
		)
		(fill yes
			(thermal_gap 0.5)
			(thermal_bridge_width 0.5)
			(island_removal_mode 0)
		)
		(polygon
			(pts
				(arc
					(start 229.079044 -52.912264)
					(mid 224.079054 -57.912254)
					(end 229.079044 -62.912244)
				)
				(arc
					(start 251.079 -62.912244)
					(mid 256.07899 -57.912254)
					(end 251.079 -52.912264)
				)
			)
		)
	)
	(zone
		(layers "In2.Cu" "In4.Cu" "In5.Cu" "In7.Cu")
		(hatch none 0.5)
		(connect_pads
			(clearance 0)
		)
		(min_thickness 0.25)
		(keepout
			(tracks not_allowed)
			(vias allowed)
			(pads allowed)
			(copperpour not_allowed)
			(footprints allowed)
		)
		(placement
			(enabled no)
			(sheetname "")
		)
		(fill yes
			(thermal_gap 0.5)
			(thermal_bridge_width 0.5)
			(island_removal_mode 0)
		)
		(polygon
			(pts
				(arc
					(start 239.747044 -132.79501)
					(mid 234.747054 -137.795)
					(end 239.747044 -142.79499)
				)
				(arc
					(start 261.747 -142.79499)
					(mid 266.74699 -137.795)
					(end 261.747 -132.79501)
				)
			)
		)
	)
	(zone
		(layers "In2.Cu" "In7.Cu")
		(hatch none 0.5)
		(connect_pads
			(clearance 0)
		)
		(min_thickness 0.25)
		(keepout
			(tracks not_allowed)
			(vias allowed)
			(pads allowed)
			(copperpour not_allowed)
			(footprints allowed)
		)
		(placement
			(enabled no)
			(sheetname "")
		)
		(fill yes
			(thermal_gap 0.5)
			(thermal_bridge_width 0.5)
			(island_removal_mode 0)
		)
		(polygon
			(pts
				(arc
					(start 251.079 -63.547244)
					(mid 256.71399 -57.912254)
					(end 251.079 -52.277264)
				)
				(arc
					(start 229.079044 -52.277264)
					(mid 223.444054 -57.912254)
					(end 229.079044 -63.547244)
				)
			)
		)
	)
	(zone
		(layers "In2.Cu" "In7.Cu")
		(hatch none 0.5)
		(connect_pads
			(clearance 0)
		)
		(min_thickness 0.25)
		(keepout
			(tracks not_allowed)
			(vias allowed)
			(pads allowed)
			(copperpour not_allowed)
			(footprints allowed)
		)
		(placement
			(enabled no)
			(sheetname "")
		)
		(fill yes
			(thermal_gap 0.5)
			(thermal_bridge_width 0.5)
			(island_removal_mode 0)
		)
		(polygon
			(pts
				(arc
					(start 129.999994 -17.634966)
					(mid 135.634984 -11.999976)
					(end 129.999994 -6.364986)
				)
				(arc
					(start 108.000038 -6.364986)
					(mid 102.365048 -11.999976)
					(end 108.000038 -17.634966)
				)
			)
		)
	)
	(zone
		(layers "In2.Cu" "In7.Cu")
		(hatch none 0.5)
		(connect_pads
			(clearance 0)
		)
		(min_thickness 0.25)
		(keepout
			(tracks not_allowed)
			(vias allowed)
			(pads allowed)
			(copperpour not_allowed)
			(footprints allowed)
		)
		(placement
			(enabled no)
			(sheetname "")
		)
		(fill yes
			(thermal_gap 0.5)
			(thermal_bridge_width 0.5)
			(island_removal_mode 0)
		)
		(polygon
			(pts
				(arc
					(start 261.747 -143.42999)
					(mid 267.38199 -137.795)
					(end 261.747 -132.16001)
				)
				(arc
					(start 239.747044 -132.16001)
					(mid 234.112054 -137.795)
					(end 239.747044 -143.42999)
				)
			)
		)
	)
	(zone
		(layers "In2.Cu" "In7.Cu")
		(hatch none 0.5)
		(connect_pads
			(clearance 0)
		)
		(min_thickness 0.25)
		(keepout
			(tracks not_allowed)
			(vias allowed)
			(pads allowed)
			(copperpour not_allowed)
			(footprints allowed)
		)
		(placement
			(enabled no)
			(sheetname "")
		)
		(fill yes
			(thermal_gap 0.5)
			(thermal_bridge_width 0.5)
			(island_removal_mode 0)
		)
		(polygon
			(pts
				(arc
					(start 7.999984 -130.999992)
					(mid 2.999994 -135.999982)
					(end 7.999984 -140.999972)
				)
				(arc
					(start 29.99994 -140.999972)
					(mid 34.99993 -135.999982)
					(end 29.99994 -130.999992)
				)
			)
		)
	)
	(zone
		(layers "In2.Cu" "In7.Cu")
		(hatch none 0.5)
		(connect_pads
			(clearance 0)
		)
		(min_thickness 0.25)
		(keepout
			(tracks not_allowed)
			(vias allowed)
			(pads allowed)
			(copperpour not_allowed)
			(footprints allowed)
		)
		(placement
			(enabled no)
			(sheetname "")
		)
		(fill yes
			(thermal_gap 0.5)
			(thermal_bridge_width 0.5)
			(island_removal_mode 0)
		)
		(polygon
			(pts
				(arc
					(start 7.999984 -6.999986)
					(mid 2.999994 -11.999976)
					(end 7.999984 -16.999966)
				)
				(arc
					(start 29.99994 -16.999966)
					(mid 34.99993 -11.999976)
					(end 29.99994 -6.999986)
				)
			)
		)
	)
	(zone
		(layers "In2.Cu" "In7.Cu")
		(hatch none 0.5)
		(connect_pads
			(clearance 0)
		)
		(min_thickness 0.25)
		(keepout
			(tracks not_allowed)
			(vias allowed)
			(pads allowed)
			(copperpour not_allowed)
			(footprints allowed)
		)
		(placement
			(enabled no)
			(sheetname "")
		)
		(fill yes
			(thermal_gap 0.5)
			(thermal_bridge_width 0.5)
			(island_removal_mode 0)
		)
		(polygon
			(pts
				(arc
					(start 108.000038 -6.999986)
					(mid 103.000048 -11.999976)
					(end 108.000038 -16.999966)
				)
				(arc
					(start 129.999994 -16.999966)
					(mid 134.999984 -11.999976)
					(end 129.999994 -6.999986)
				)
			)
		)
	)
	(zone
		(layers "In3.Cu" "In4.Cu" "In5.Cu" "In6.Cu")
		(hatch none 0.5)
		(connect_pads
			(clearance 0)
		)
		(min_thickness 0.25)
		(keepout
			(tracks not_allowed)
			(vias allowed)
			(pads allowed)
			(copperpour not_allowed)
			(footprints allowed)
		)
		(placement
			(enabled no)
			(sheetname "")
		)
		(fill yes
			(thermal_gap 0.5)
			(thermal_bridge_width 0.5)
			(island_removal_mode 0)
		)
		(polygon
			(pts
				(arc
					(start 300.741334 -42.151808)
					(mid 298.963334 -42.151808)
					(end 300.741334 -42.151808)
				)
			)
		)
	)
	(zone
		(layers "In3.Cu" "In4.Cu" "In5.Cu" "In6.Cu")
		(hatch none 0.5)
		(connect_pads
			(clearance 0)
		)
		(min_thickness 0.25)
		(keepout
			(tracks not_allowed)
			(vias allowed)
			(pads allowed)
			(copperpour not_allowed)
			(footprints allowed)
		)
		(placement
			(enabled no)
			(sheetname "")
		)
		(fill yes
			(thermal_gap 0.5)
			(thermal_bridge_width 0.5)
			(island_removal_mode 0)
		)
		(polygon
			(pts
				(arc
					(start 300.741334 -41.389808)
					(mid 298.963334 -41.389808)
					(end 300.741334 -41.389808)
				)
			)
		)
	)
	(zone
		(layers "In3.Cu" "In4.Cu" "In5.Cu" "In6.Cu")
		(hatch none 0.5)
		(connect_pads
			(clearance 0)
		)
		(min_thickness 0.25)
		(keepout
			(tracks not_allowed)
			(vias allowed)
			(pads allowed)
			(copperpour not_allowed)
			(footprints allowed)
		)
		(placement
			(enabled no)
			(sheetname "")
		)
		(fill yes
			(thermal_gap 0.5)
			(thermal_bridge_width 0.5)
			(island_removal_mode 0)
		)
		(polygon
			(pts
				(arc
					(start 299.979334 -42.151808)
					(mid 298.201334 -42.151808)
					(end 299.979334 -42.151808)
				)
			)
		)
	)
	(zone
		(layers "In3.Cu" "In4.Cu" "In5.Cu" "In6.Cu")
		(hatch none 0.5)
		(connect_pads
			(clearance 0)
		)
		(min_thickness 0.25)
		(keepout
			(tracks not_allowed)
			(vias allowed)
			(pads allowed)
			(copperpour not_allowed)
			(footprints allowed)
		)
		(placement
			(enabled no)
			(sheetname "")
		)
		(fill yes
			(thermal_gap 0.5)
			(thermal_bridge_width 0.5)
			(island_removal_mode 0)
		)
		(polygon
			(pts
				(arc
					(start 301.376334 -42.151808)
					(mid 299.598334 -42.151808)
					(end 301.376334 -42.151808)
				)
			)
		)
	)
	(zone
		(layers "In3.Cu" "In4.Cu" "In5.Cu" "In6.Cu")
		(hatch none 0.5)
		(connect_pads
			(clearance 0)
		)
		(min_thickness 0.25)
		(keepout
			(tracks not_allowed)
			(vias allowed)
			(pads allowed)
			(copperpour not_allowed)
			(footprints allowed)
		)
		(placement
			(enabled no)
			(sheetname "")
		)
		(fill yes
			(thermal_gap 0.5)
			(thermal_bridge_width 0.5)
			(island_removal_mode 0)
		)
		(polygon
			(pts
				(arc
					(start 299.979334 -41.389808)
					(mid 298.201334 -41.389808)
					(end 299.979334 -41.389808)
				)
			)
		)
	)
	(zone
		(layers "In3.Cu" "In4.Cu" "In5.Cu" "In6.Cu")
		(hatch none 0.5)
		(connect_pads
			(clearance 0)
		)
		(min_thickness 0.25)
		(keepout
			(tracks not_allowed)
			(vias allowed)
			(pads allowed)
			(copperpour not_allowed)
			(footprints allowed)
		)
		(placement
			(enabled no)
			(sheetname "")
		)
		(fill yes
			(thermal_gap 0.5)
			(thermal_bridge_width 0.5)
			(island_removal_mode 0)
		)
		(polygon
			(pts
				(arc
					(start 302.011334 -42.151808)
					(mid 300.233334 -42.151808)
					(end 302.011334 -42.151808)
				)
			)
		)
	)
	(zone
		(layers "In3.Cu" "In4.Cu" "In5.Cu" "In6.Cu")
		(hatch none 0.5)
		(connect_pads
			(clearance 0)
		)
		(min_thickness 0.25)
		(keepout
			(tracks not_allowed)
			(vias allowed)
			(pads allowed)
			(copperpour not_allowed)
			(footprints allowed)
		)
		(placement
			(enabled no)
			(sheetname "")
		)
		(fill yes
			(thermal_gap 0.5)
			(thermal_bridge_width 0.5)
			(island_removal_mode 0)
		)
		(polygon
			(pts
				(arc
					(start 302.797972 -41.346628)
					(mid 301.019972 -41.346628)
					(end 302.797972 -41.346628)
				)
			)
		)
	)
	(zone
		(layers "In3.Cu" "In4.Cu" "In5.Cu" "In6.Cu")
		(hatch none 0.5)
		(connect_pads
			(clearance 0)
		)
		(min_thickness 0.25)
		(keepout
			(tracks not_allowed)
			(vias allowed)
			(pads allowed)
			(copperpour not_allowed)
			(footprints allowed)
		)
		(placement
			(enabled no)
			(sheetname "")
		)
		(fill yes
			(thermal_gap 0.5)
			(thermal_bridge_width 0.5)
			(island_removal_mode 0)
		)
		(polygon
			(pts
				(arc
					(start 301.376334 -41.389808)
					(mid 299.598334 -41.389808)
					(end 301.376334 -41.389808)
				)
			)
		)
	)
	(zone
		(layers "In3.Cu" "In4.Cu" "In5.Cu" "In6.Cu")
		(hatch none 0.5)
		(connect_pads
			(clearance 0)
		)
		(min_thickness 0.25)
		(keepout
			(tracks not_allowed)
			(vias allowed)
			(pads allowed)
			(copperpour not_allowed)
			(footprints allowed)
		)
		(placement
			(enabled no)
			(sheetname "")
		)
		(fill yes
			(thermal_gap 0.5)
			(thermal_bridge_width 0.5)
			(island_removal_mode 0)
		)
		(polygon
			(pts
				(arc
					(start 302.7934 -42.164)
					(mid 301.0154 -42.164)
					(end 302.7934 -42.164)
				)
			)
		)
	)
	(zone
		(layers "In3.Cu" "In4.Cu" "In5.Cu" "In6.Cu")
		(hatch none 0.5)
		(connect_pads
			(clearance 0)
		)
		(min_thickness 0.25)
		(keepout
			(tracks not_allowed)
			(vias allowed)
			(pads allowed)
			(copperpour not_allowed)
			(footprints allowed)
		)
		(placement
			(enabled no)
			(sheetname "")
		)
		(fill yes
			(thermal_gap 0.5)
			(thermal_bridge_width 0.5)
			(island_removal_mode 0)
		)
		(polygon
			(pts
				(arc
					(start 302.011334 -41.389808)
					(mid 300.233334 -41.389808)
					(end 302.011334 -41.389808)
				)
			)
		)
	)
	(zone
		(layers "In3.Cu" "In4.Cu" "In6.Cu")
		(hatch none 0.5)
		(connect_pads
			(clearance 0)
		)
		(min_thickness 0.25)
		(keepout
			(tracks not_allowed)
			(vias allowed)
			(pads allowed)
			(copperpour not_allowed)
			(footprints allowed)
		)
		(placement
			(enabled no)
			(sheetname "")
		)
		(fill yes
			(thermal_gap 0.5)
			(thermal_bridge_width 0.5)
			(island_removal_mode 0)
		)
		(polygon
			(pts
				(arc
					(start 298.45 -52.832)
					(mid 296.672 -52.832)
					(end 298.45 -52.832)
				)
			)
		)
	)
	(zone
		(layers "In3.Cu" "In4.Cu" "In6.Cu")
		(hatch none 0.5)
		(connect_pads
			(clearance 0)
		)
		(min_thickness 0.25)
		(keepout
			(tracks not_allowed)
			(vias allowed)
			(pads allowed)
			(copperpour not_allowed)
			(footprints allowed)
		)
		(placement
			(enabled no)
			(sheetname "")
		)
		(fill yes
			(thermal_gap 0.5)
			(thermal_bridge_width 0.5)
			(island_removal_mode 0)
		)
		(polygon
			(pts
				(arc
					(start 299.212 -53.594)
					(mid 297.434 -53.594)
					(end 299.212 -53.594)
				)
			)
		)
	)
	(zone
		(layers "In3.Cu" "In4.Cu" "In6.Cu")
		(hatch none 0.5)
		(connect_pads
			(clearance 0)
		)
		(min_thickness 0.25)
		(keepout
			(tracks not_allowed)
			(vias allowed)
			(pads allowed)
			(copperpour not_allowed)
			(footprints allowed)
		)
		(placement
			(enabled no)
			(sheetname "")
		)
		(fill yes
			(thermal_gap 0.5)
			(thermal_bridge_width 0.5)
			(island_removal_mode 0)
		)
		(polygon
			(pts
				(arc
					(start 299.212 -52.07)
					(mid 297.434 -52.07)
					(end 299.212 -52.07)
				)
			)
		)
	)
	(zone
		(layers "In3.Cu" "In4.Cu" "In6.Cu")
		(hatch none 0.5)
		(connect_pads
			(clearance 0)
		)
		(min_thickness 0.25)
		(keepout
			(tracks not_allowed)
			(vias allowed)
			(pads allowed)
			(copperpour not_allowed)
			(footprints allowed)
		)
		(placement
			(enabled no)
			(sheetname "")
		)
		(fill yes
			(thermal_gap 0.5)
			(thermal_bridge_width 0.5)
			(island_removal_mode 0)
		)
		(polygon
			(pts
				(arc
					(start 299.212 -54.356)
					(mid 297.434 -54.356)
					(end 299.212 -54.356)
				)
			)
		)
	)
	(zone
		(layers "In3.Cu" "In4.Cu" "In6.Cu")
		(hatch none 0.5)
		(connect_pads
			(clearance 0)
		)
		(min_thickness 0.25)
		(keepout
			(tracks not_allowed)
			(vias allowed)
			(pads allowed)
			(copperpour not_allowed)
			(footprints allowed)
		)
		(placement
			(enabled no)
			(sheetname "")
		)
		(fill yes
			(thermal_gap 0.5)
			(thermal_bridge_width 0.5)
			(island_removal_mode 0)
		)
		(polygon
			(pts
				(arc
					(start 299.212 -52.832)
					(mid 297.434 -52.832)
					(end 299.212 -52.832)
				)
			)
		)
	)
	(zone
		(layers "In3.Cu" "In4.Cu" "In6.Cu")
		(hatch none 0.5)
		(connect_pads
			(clearance 0)
		)
		(min_thickness 0.25)
		(keepout
			(tracks not_allowed)
			(vias allowed)
			(pads allowed)
			(copperpour not_allowed)
			(footprints allowed)
		)
		(placement
			(enabled no)
			(sheetname "")
		)
		(fill yes
			(thermal_gap 0.5)
			(thermal_bridge_width 0.5)
			(island_removal_mode 0)
		)
		(polygon
			(pts
				(arc
					(start 298.45 -53.594)
					(mid 296.672 -53.594)
					(end 298.45 -53.594)
				)
			)
		)
	)
	(zone
		(layers "In3.Cu" "In4.Cu" "In6.Cu")
		(hatch none 0.5)
		(connect_pads
			(clearance 0)
		)
		(min_thickness 0.25)
		(keepout
			(tracks not_allowed)
			(vias allowed)
			(pads allowed)
			(copperpour not_allowed)
			(footprints allowed)
		)
		(placement
			(enabled no)
			(sheetname "")
		)
		(fill yes
			(thermal_gap 0.5)
			(thermal_bridge_width 0.5)
			(island_removal_mode 0)
		)
		(polygon
			(pts
				(arc
					(start 298.45 -52.07)
					(mid 296.672 -52.07)
					(end 298.45 -52.07)
				)
			)
		)
	)
	(zone
		(layers "In3.Cu" "In4.Cu" "In6.Cu")
		(hatch none 0.5)
		(connect_pads
			(clearance 0)
		)
		(min_thickness 0.25)
		(keepout
			(tracks not_allowed)
			(vias allowed)
			(pads allowed)
			(copperpour not_allowed)
			(footprints allowed)
		)
		(placement
			(enabled no)
			(sheetname "")
		)
		(fill yes
			(thermal_gap 0.5)
			(thermal_bridge_width 0.5)
			(island_removal_mode 0)
		)
		(polygon
			(pts
				(arc
					(start 298.45 -54.356)
					(mid 296.672 -54.356)
					(end 298.45 -54.356)
				)
			)
		)
	)
	(zone
		(layers "In3.Cu" "In6.Cu" "In8.Cu")
		(hatch none 0.5)
		(connect_pads
			(clearance 0)
		)
		(min_thickness 0.25)
		(keepout
			(tracks not_allowed)
			(vias allowed)
			(pads allowed)
			(copperpour not_allowed)
			(footprints allowed)
		)
		(placement
			(enabled no)
			(sheetname "")
		)
		(fill yes
			(thermal_gap 0.5)
			(thermal_bridge_width 0.5)
			(island_removal_mode 0)
		)
		(polygon
			(pts
				(arc
					(start 112.33404 -40.55999)
					(mid 109.535976 -40.55999)
					(end 112.33404 -40.55999)
				)
			)
		)
	)
	(zone
		(layers "In3.Cu" "In6.Cu" "In8.Cu")
		(hatch none 0.5)
		(connect_pads
			(clearance 0)
		)
		(min_thickness 0.25)
		(keepout
			(tracks not_allowed)
			(vias allowed)
			(pads allowed)
			(copperpour not_allowed)
			(footprints allowed)
		)
		(placement
			(enabled no)
			(sheetname "")
		)
		(fill yes
			(thermal_gap 0.5)
			(thermal_bridge_width 0.5)
			(island_removal_mode 0)
		)
		(polygon
			(pts
				(arc
					(start 114.87404 -35.47999)
					(mid 112.075976 -35.47999)
					(end 114.87404 -35.47999)
				)
			)
		)
	)
	(zone
		(layers "In3.Cu" "In6.Cu" "In8.Cu")
		(hatch none 0.5)
		(connect_pads
			(clearance 0)
		)
		(min_thickness 0.25)
		(keepout
			(tracks not_allowed)
			(vias allowed)
			(pads allowed)
			(copperpour not_allowed)
			(footprints allowed)
		)
		(placement
			(enabled no)
			(sheetname "")
		)
		(fill yes
			(thermal_gap 0.5)
			(thermal_bridge_width 0.5)
			(island_removal_mode 0)
		)
		(polygon
			(pts
				(arc
					(start 193.819018 -32.869632)
					(mid 191.020954 -32.869632)
					(end 193.819018 -32.869632)
				)
			)
		)
	)
	(zone
		(layers "In3.Cu" "In6.Cu" "In8.Cu")
		(hatch none 0.5)
		(connect_pads
			(clearance 0)
		)
		(min_thickness 0.25)
		(keepout
			(tracks not_allowed)
			(vias allowed)
			(pads allowed)
			(copperpour not_allowed)
			(footprints allowed)
		)
		(placement
			(enabled no)
			(sheetname "")
		)
		(fill yes
			(thermal_gap 0.5)
			(thermal_bridge_width 0.5)
			(island_removal_mode 0)
		)
		(polygon
			(pts
				(arc
					(start 114.87404 -32.93999)
					(mid 112.075976 -32.93999)
					(end 114.87404 -32.93999)
				)
			)
		)
	)
	(zone
		(layers "In3.Cu" "In6.Cu" "In8.Cu")
		(hatch none 0.5)
		(connect_pads
			(clearance 0)
		)
		(min_thickness 0.25)
		(keepout
			(tracks not_allowed)
			(vias allowed)
			(pads allowed)
			(copperpour not_allowed)
			(footprints allowed)
		)
		(placement
			(enabled no)
			(sheetname "")
		)
		(fill yes
			(thermal_gap 0.5)
			(thermal_bridge_width 0.5)
			(island_removal_mode 0)
		)
		(polygon
			(pts
				(arc
					(start 191.279018 -35.409632)
					(mid 188.480954 -35.409632)
					(end 191.279018 -35.409632)
				)
			)
		)
	)
	(zone
		(layers "In3.Cu" "In6.Cu" "In8.Cu")
		(hatch none 0.5)
		(connect_pads
			(clearance 0)
		)
		(min_thickness 0.25)
		(keepout
			(tracks not_allowed)
			(vias allowed)
			(pads allowed)
			(copperpour not_allowed)
			(footprints allowed)
		)
		(placement
			(enabled no)
			(sheetname "")
		)
		(fill yes
			(thermal_gap 0.5)
			(thermal_bridge_width 0.5)
			(island_removal_mode 0)
		)
		(polygon
			(pts
				(arc
					(start 103.44404 -38.01999)
					(mid 100.645976 -38.01999)
					(end 103.44404 -38.01999)
				)
			)
		)
	)
	(zone
		(layers "In3.Cu" "In6.Cu" "In8.Cu")
		(hatch none 0.5)
		(connect_pads
			(clearance 0)
		)
		(min_thickness 0.25)
		(keepout
			(tracks not_allowed)
			(vias allowed)
			(pads allowed)
			(copperpour not_allowed)
			(footprints allowed)
		)
		(placement
			(enabled no)
			(sheetname "")
		)
		(fill yes
			(thermal_gap 0.5)
			(thermal_bridge_width 0.5)
			(island_removal_mode 0)
		)
		(polygon
			(pts
				(arc
					(start 182.389018 -37.949632)
					(mid 179.590954 -37.949632)
					(end 182.389018 -37.949632)
				)
			)
		)
	)
	(zone
		(layers "In3.Cu" "In6.Cu" "In8.Cu")
		(hatch none 0.5)
		(connect_pads
			(clearance 0)
		)
		(min_thickness 0.25)
		(keepout
			(tracks not_allowed)
			(vias allowed)
			(pads allowed)
			(copperpour not_allowed)
			(footprints allowed)
		)
		(placement
			(enabled no)
			(sheetname "")
		)
		(fill yes
			(thermal_gap 0.5)
			(thermal_bridge_width 0.5)
			(island_removal_mode 0)
		)
		(polygon
			(pts
				(arc
					(start 105.98404 -32.93999)
					(mid 103.185976 -32.93999)
					(end 105.98404 -32.93999)
				)
			)
		)
	)
	(zone
		(layers "In3.Cu" "In6.Cu" "In8.Cu")
		(hatch none 0.5)
		(connect_pads
			(clearance 0)
		)
		(min_thickness 0.25)
		(keepout
			(tracks not_allowed)
			(vias allowed)
			(pads allowed)
			(copperpour not_allowed)
			(footprints allowed)
		)
		(placement
			(enabled no)
			(sheetname "")
		)
		(fill yes
			(thermal_gap 0.5)
			(thermal_bridge_width 0.5)
			(island_removal_mode 0)
		)
		(polygon
			(pts
				(arc
					(start 182.389018 -35.409632)
					(mid 179.590954 -35.409632)
					(end 182.389018 -35.409632)
				)
			)
		)
	)
	(zone
		(layers "In3.Cu" "In6.Cu" "In8.Cu")
		(hatch none 0.5)
		(connect_pads
			(clearance 0)
		)
		(min_thickness 0.25)
		(keepout
			(tracks not_allowed)
			(vias allowed)
			(pads allowed)
			(copperpour not_allowed)
			(footprints allowed)
		)
		(placement
			(enabled no)
			(sheetname "")
		)
		(fill yes
			(thermal_gap 0.5)
			(thermal_bridge_width 0.5)
			(island_removal_mode 0)
		)
		(polygon
			(pts
				(arc
					(start 191.279018 -37.949632)
					(mid 188.480954 -37.949632)
					(end 191.279018 -37.949632)
				)
			)
		)
	)
	(zone
		(layers "In3.Cu" "In6.Cu" "In8.Cu")
		(hatch none 0.5)
		(connect_pads
			(clearance 0)
		)
		(min_thickness 0.25)
		(keepout
			(tracks not_allowed)
			(vias allowed)
			(pads allowed)
			(copperpour not_allowed)
			(footprints allowed)
		)
		(placement
			(enabled no)
			(sheetname "")
		)
		(fill yes
			(thermal_gap 0.5)
			(thermal_bridge_width 0.5)
			(island_removal_mode 0)
		)
		(polygon
			(pts
				(arc
					(start 123.76404 -38.01999)
					(mid 120.965976 -38.01999)
					(end 123.76404 -38.01999)
				)
			)
		)
	)
	(zone
		(layers "In3.Cu" "In6.Cu" "In8.Cu")
		(hatch none 0.5)
		(connect_pads
			(clearance 0)
		)
		(min_thickness 0.25)
		(keepout
			(tracks not_allowed)
			(vias allowed)
			(pads allowed)
			(copperpour not_allowed)
			(footprints allowed)
		)
		(placement
			(enabled no)
			(sheetname "")
		)
		(fill yes
			(thermal_gap 0.5)
			(thermal_bridge_width 0.5)
			(island_removal_mode 0)
		)
		(polygon
			(pts
				(arc
					(start 191.279018 -32.869632)
					(mid 188.480954 -32.869632)
					(end 191.279018 -32.869632)
				)
			)
		)
	)
	(zone
		(layers "In3.Cu" "In6.Cu" "In8.Cu")
		(hatch none 0.5)
		(connect_pads
			(clearance 0)
		)
		(min_thickness 0.25)
		(keepout
			(tracks not_allowed)
			(vias allowed)
			(pads allowed)
			(copperpour not_allowed)
			(footprints allowed)
		)
		(placement
			(enabled no)
			(sheetname "")
		)
		(fill yes
			(thermal_gap 0.5)
			(thermal_bridge_width 0.5)
			(island_removal_mode 0)
		)
		(polygon
			(pts
				(arc
					(start 193.819018 -30.329632)
					(mid 191.020954 -30.329632)
					(end 193.819018 -30.329632)
				)
			)
		)
	)
	(zone
		(layers "In3.Cu" "In6.Cu" "In8.Cu")
		(hatch none 0.5)
		(connect_pads
			(clearance 0)
		)
		(min_thickness 0.25)
		(keepout
			(tracks not_allowed)
			(vias allowed)
			(pads allowed)
			(copperpour not_allowed)
			(footprints allowed)
		)
		(placement
			(enabled no)
			(sheetname "")
		)
		(fill yes
			(thermal_gap 0.5)
			(thermal_bridge_width 0.5)
			(island_removal_mode 0)
		)
		(polygon
			(pts
				(arc
					(start 123.76404 -35.47999)
					(mid 120.965976 -35.47999)
					(end 123.76404 -35.47999)
				)
			)
		)
	)
	(zone
		(layers "In3.Cu" "In6.Cu" "In8.Cu")
		(hatch none 0.5)
		(connect_pads
			(clearance 0)
		)
		(min_thickness 0.25)
		(keepout
			(tracks not_allowed)
			(vias allowed)
			(pads allowed)
			(copperpour not_allowed)
			(footprints allowed)
		)
		(placement
			(enabled no)
			(sheetname "")
		)
		(fill yes
			(thermal_gap 0.5)
			(thermal_bridge_width 0.5)
			(island_removal_mode 0)
		)
		(polygon
			(pts
				(arc
					(start 103.44404 -40.55999)
					(mid 100.645976 -40.55999)
					(end 103.44404 -40.55999)
				)
			)
		)
	)
	(zone
		(layers "In3.Cu" "In6.Cu" "In8.Cu")
		(hatch none 0.5)
		(connect_pads
			(clearance 0)
		)
		(min_thickness 0.25)
		(keepout
			(tracks not_allowed)
			(vias allowed)
			(pads allowed)
			(copperpour not_allowed)
			(footprints allowed)
		)
		(placement
			(enabled no)
			(sheetname "")
		)
		(fill yes
			(thermal_gap 0.5)
			(thermal_bridge_width 0.5)
			(island_removal_mode 0)
		)
		(polygon
			(pts
				(arc
					(start 121.22404 -38.01999)
					(mid 118.425976 -38.01999)
					(end 121.22404 -38.01999)
				)
			)
		)
	)
	(zone
		(layers "In3.Cu" "In6.Cu" "In8.Cu")
		(hatch none 0.5)
		(connect_pads
			(clearance 0)
		)
		(min_thickness 0.25)
		(keepout
			(tracks not_allowed)
			(vias allowed)
			(pads allowed)
			(copperpour not_allowed)
			(footprints allowed)
		)
		(placement
			(enabled no)
			(sheetname "")
		)
		(fill yes
			(thermal_gap 0.5)
			(thermal_bridge_width 0.5)
			(island_removal_mode 0)
		)
		(polygon
			(pts
				(arc
					(start 184.929018 -30.329632)
					(mid 182.130954 -30.329632)
					(end 184.929018 -30.329632)
				)
			)
		)
	)
	(zone
		(layers "In3.Cu" "In6.Cu" "In8.Cu")
		(hatch none 0.5)
		(connect_pads
			(clearance 0)
		)
		(min_thickness 0.25)
		(keepout
			(tracks not_allowed)
			(vias allowed)
			(pads allowed)
			(copperpour not_allowed)
			(footprints allowed)
		)
		(placement
			(enabled no)
			(sheetname "")
		)
		(fill yes
			(thermal_gap 0.5)
			(thermal_bridge_width 0.5)
			(island_removal_mode 0)
		)
		(polygon
			(pts
				(arc
					(start 105.98404 -35.47999)
					(mid 103.185976 -35.47999)
					(end 105.98404 -35.47999)
				)
			)
		)
	)
	(zone
		(layers "In3.Cu" "In6.Cu" "In8.Cu")
		(hatch none 0.5)
		(connect_pads
			(clearance 0)
		)
		(min_thickness 0.25)
		(keepout
			(tracks not_allowed)
			(vias allowed)
			(pads allowed)
			(copperpour not_allowed)
			(footprints allowed)
		)
		(placement
			(enabled no)
			(sheetname "")
		)
		(fill yes
			(thermal_gap 0.5)
			(thermal_bridge_width 0.5)
			(island_removal_mode 0)
		)
		(polygon
			(pts
				(arc
					(start 105.98404 -38.01999)
					(mid 103.185976 -38.01999)
					(end 105.98404 -38.01999)
				)
			)
		)
	)
	(zone
		(layers "In3.Cu" "In6.Cu" "In8.Cu")
		(hatch none 0.5)
		(connect_pads
			(clearance 0)
		)
		(min_thickness 0.25)
		(keepout
			(tracks not_allowed)
			(vias allowed)
			(pads allowed)
			(copperpour not_allowed)
			(footprints allowed)
		)
		(placement
			(enabled no)
			(sheetname "")
		)
		(fill yes
			(thermal_gap 0.5)
			(thermal_bridge_width 0.5)
			(island_removal_mode 0)
		)
		(polygon
			(pts
				(arc
					(start 200.169018 -32.869632)
					(mid 197.370954 -32.869632)
					(end 200.169018 -32.869632)
				)
			)
		)
	)
	(zone
		(layers "In3.Cu" "In6.Cu" "In8.Cu")
		(hatch none 0.5)
		(connect_pads
			(clearance 0)
		)
		(min_thickness 0.25)
		(keepout
			(tracks not_allowed)
			(vias allowed)
			(pads allowed)
			(copperpour not_allowed)
			(footprints allowed)
		)
		(placement
			(enabled no)
			(sheetname "")
		)
		(fill yes
			(thermal_gap 0.5)
			(thermal_bridge_width 0.5)
			(island_removal_mode 0)
		)
		(polygon
			(pts
				(arc
					(start 121.22404 -40.55999)
					(mid 118.425976 -40.55999)
					(end 121.22404 -40.55999)
				)
			)
		)
	)
	(zone
		(layers "In3.Cu" "In6.Cu" "In8.Cu")
		(hatch none 0.5)
		(connect_pads
			(clearance 0)
		)
		(min_thickness 0.25)
		(keepout
			(tracks not_allowed)
			(vias allowed)
			(pads allowed)
			(copperpour not_allowed)
			(footprints allowed)
		)
		(placement
			(enabled no)
			(sheetname "")
		)
		(fill yes
			(thermal_gap 0.5)
			(thermal_bridge_width 0.5)
			(island_removal_mode 0)
		)
		(polygon
			(pts
				(arc
					(start 114.87404 -40.55999)
					(mid 112.075976 -40.55999)
					(end 114.87404 -40.55999)
				)
			)
		)
	)
	(zone
		(layers "In3.Cu" "In6.Cu" "In8.Cu")
		(hatch none 0.5)
		(connect_pads
			(clearance 0)
		)
		(min_thickness 0.25)
		(keepout
			(tracks not_allowed)
			(vias allowed)
			(pads allowed)
			(copperpour not_allowed)
			(footprints allowed)
		)
		(placement
			(enabled no)
			(sheetname "")
		)
		(fill yes
			(thermal_gap 0.5)
			(thermal_bridge_width 0.5)
			(island_removal_mode 0)
		)
		(polygon
			(pts
				(arc
					(start 193.819018 -37.949632)
					(mid 191.020954 -37.949632)
					(end 193.819018 -37.949632)
				)
			)
		)
	)
	(zone
		(layers "In3.Cu" "In6.Cu" "In8.Cu")
		(hatch none 0.5)
		(connect_pads
			(clearance 0)
		)
		(min_thickness 0.25)
		(keepout
			(tracks not_allowed)
			(vias allowed)
			(pads allowed)
			(copperpour not_allowed)
			(footprints allowed)
		)
		(placement
			(enabled no)
			(sheetname "")
		)
		(fill yes
			(thermal_gap 0.5)
			(thermal_bridge_width 0.5)
			(island_removal_mode 0)
		)
		(polygon
			(pts
				(arc
					(start 193.819018 -35.409632)
					(mid 191.020954 -35.409632)
					(end 193.819018 -35.409632)
				)
			)
		)
	)
	(zone
		(layers "In3.Cu" "In6.Cu" "In8.Cu")
		(hatch none 0.5)
		(connect_pads
			(clearance 0)
		)
		(min_thickness 0.25)
		(keepout
			(tracks not_allowed)
			(vias allowed)
			(pads allowed)
			(copperpour not_allowed)
			(footprints allowed)
		)
		(placement
			(enabled no)
			(sheetname "")
		)
		(fill yes
			(thermal_gap 0.5)
			(thermal_bridge_width 0.5)
			(island_removal_mode 0)
		)
		(polygon
			(pts
				(arc
					(start 105.98404 -40.55999)
					(mid 103.185976 -40.55999)
					(end 105.98404 -40.55999)
				)
			)
		)
	)
	(zone
		(layers "In3.Cu" "In6.Cu" "In8.Cu")
		(hatch none 0.5)
		(connect_pads
			(clearance 0)
		)
		(min_thickness 0.25)
		(keepout
			(tracks not_allowed)
			(vias allowed)
			(pads allowed)
			(copperpour not_allowed)
			(footprints allowed)
		)
		(placement
			(enabled no)
			(sheetname "")
		)
		(fill yes
			(thermal_gap 0.5)
			(thermal_bridge_width 0.5)
			(island_removal_mode 0)
		)
		(polygon
			(pts
				(arc
					(start 200.169018 -30.329632)
					(mid 197.370954 -30.329632)
					(end 200.169018 -30.329632)
				)
			)
		)
	)
	(zone
		(layers "In3.Cu" "In6.Cu" "In8.Cu")
		(hatch none 0.5)
		(connect_pads
			(clearance 0)
		)
		(min_thickness 0.25)
		(keepout
			(tracks not_allowed)
			(vias allowed)
			(pads allowed)
			(copperpour not_allowed)
			(footprints allowed)
		)
		(placement
			(enabled no)
			(sheetname "")
		)
		(fill yes
			(thermal_gap 0.5)
			(thermal_bridge_width 0.5)
			(island_removal_mode 0)
		)
		(polygon
			(pts
				(arc
					(start 202.709018 -32.869632)
					(mid 199.910954 -32.869632)
					(end 202.709018 -32.869632)
				)
			)
		)
	)
	(zone
		(layers "In3.Cu" "In6.Cu" "In8.Cu")
		(hatch none 0.5)
		(connect_pads
			(clearance 0)
		)
		(min_thickness 0.25)
		(keepout
			(tracks not_allowed)
			(vias allowed)
			(pads allowed)
			(copperpour not_allowed)
			(footprints allowed)
		)
		(placement
			(enabled no)
			(sheetname "")
		)
		(fill yes
			(thermal_gap 0.5)
			(thermal_bridge_width 0.5)
			(island_removal_mode 0)
		)
		(polygon
			(pts
				(arc
					(start 123.76404 -40.55999)
					(mid 120.965976 -40.55999)
					(end 123.76404 -40.55999)
				)
			)
		)
	)
	(zone
		(layers "In3.Cu" "In6.Cu" "In8.Cu")
		(hatch none 0.5)
		(connect_pads
			(clearance 0)
		)
		(min_thickness 0.25)
		(keepout
			(tracks not_allowed)
			(vias allowed)
			(pads allowed)
			(copperpour not_allowed)
			(footprints allowed)
		)
		(placement
			(enabled no)
			(sheetname "")
		)
		(fill yes
			(thermal_gap 0.5)
			(thermal_bridge_width 0.5)
			(island_removal_mode 0)
		)
		(polygon
			(pts
				(arc
					(start 182.389018 -30.329632)
					(mid 179.590954 -30.329632)
					(end 182.389018 -30.329632)
				)
			)
		)
	)
	(zone
		(layers "In3.Cu" "In6.Cu" "In8.Cu")
		(hatch none 0.5)
		(connect_pads
			(clearance 0)
		)
		(min_thickness 0.25)
		(keepout
			(tracks not_allowed)
			(vias allowed)
			(pads allowed)
			(copperpour not_allowed)
			(footprints allowed)
		)
		(placement
			(enabled no)
			(sheetname "")
		)
		(fill yes
			(thermal_gap 0.5)
			(thermal_bridge_width 0.5)
			(island_removal_mode 0)
		)
		(polygon
			(pts
				(arc
					(start 202.709018 -37.949632)
					(mid 199.910954 -37.949632)
					(end 202.709018 -37.949632)
				)
			)
		)
	)
	(zone
		(layers "In3.Cu" "In6.Cu" "In8.Cu")
		(hatch none 0.5)
		(connect_pads
			(clearance 0)
		)
		(min_thickness 0.25)
		(keepout
			(tracks not_allowed)
			(vias allowed)
			(pads allowed)
			(copperpour not_allowed)
			(footprints allowed)
		)
		(placement
			(enabled no)
			(sheetname "")
		)
		(fill yes
			(thermal_gap 0.5)
			(thermal_bridge_width 0.5)
			(island_removal_mode 0)
		)
		(polygon
			(pts
				(arc
					(start 103.44404 -32.93999)
					(mid 100.645976 -32.93999)
					(end 103.44404 -32.93999)
				)
			)
		)
	)
	(zone
		(layers "In3.Cu" "In6.Cu" "In8.Cu")
		(hatch none 0.5)
		(connect_pads
			(clearance 0)
		)
		(min_thickness 0.25)
		(keepout
			(tracks not_allowed)
			(vias allowed)
			(pads allowed)
			(copperpour not_allowed)
			(footprints allowed)
		)
		(placement
			(enabled no)
			(sheetname "")
		)
		(fill yes
			(thermal_gap 0.5)
			(thermal_bridge_width 0.5)
			(island_removal_mode 0)
		)
		(polygon
			(pts
				(arc
					(start 200.169018 -35.409632)
					(mid 197.370954 -35.409632)
					(end 200.169018 -35.409632)
				)
			)
		)
	)
	(zone
		(layers "In3.Cu" "In6.Cu" "In8.Cu")
		(hatch none 0.5)
		(connect_pads
			(clearance 0)
		)
		(min_thickness 0.25)
		(keepout
			(tracks not_allowed)
			(vias allowed)
			(pads allowed)
			(copperpour not_allowed)
			(footprints allowed)
		)
		(placement
			(enabled no)
			(sheetname "")
		)
		(fill yes
			(thermal_gap 0.5)
			(thermal_bridge_width 0.5)
			(island_removal_mode 0)
		)
		(polygon
			(pts
				(arc
					(start 121.22404 -32.93999)
					(mid 118.425976 -32.93999)
					(end 121.22404 -32.93999)
				)
			)
		)
	)
	(zone
		(layers "In3.Cu" "In6.Cu" "In8.Cu")
		(hatch none 0.5)
		(connect_pads
			(clearance 0)
		)
		(min_thickness 0.25)
		(keepout
			(tracks not_allowed)
			(vias allowed)
			(pads allowed)
			(copperpour not_allowed)
			(footprints allowed)
		)
		(placement
			(enabled no)
			(sheetname "")
		)
		(fill yes
			(thermal_gap 0.5)
			(thermal_bridge_width 0.5)
			(island_removal_mode 0)
		)
		(polygon
			(pts
				(arc
					(start 191.279018 -30.329632)
					(mid 188.480954 -30.329632)
					(end 191.279018 -30.329632)
				)
			)
		)
	)
	(zone
		(layers "In3.Cu" "In6.Cu" "In8.Cu")
		(hatch none 0.5)
		(connect_pads
			(clearance 0)
		)
		(min_thickness 0.25)
		(keepout
			(tracks not_allowed)
			(vias allowed)
			(pads allowed)
			(copperpour not_allowed)
			(footprints allowed)
		)
		(placement
			(enabled no)
			(sheetname "")
		)
		(fill yes
			(thermal_gap 0.5)
			(thermal_bridge_width 0.5)
			(island_removal_mode 0)
		)
		(polygon
			(pts
				(arc
					(start 114.87404 -38.01999)
					(mid 112.075976 -38.01999)
					(end 114.87404 -38.01999)
				)
			)
		)
	)
	(zone
		(layers "In3.Cu" "In6.Cu" "In8.Cu")
		(hatch none 0.5)
		(connect_pads
			(clearance 0)
		)
		(min_thickness 0.25)
		(keepout
			(tracks not_allowed)
			(vias allowed)
			(pads allowed)
			(copperpour not_allowed)
			(footprints allowed)
		)
		(placement
			(enabled no)
			(sheetname "")
		)
		(fill yes
			(thermal_gap 0.5)
			(thermal_bridge_width 0.5)
			(island_removal_mode 0)
		)
		(polygon
			(pts
				(arc
					(start 200.169018 -37.949632)
					(mid 197.370954 -37.949632)
					(end 200.169018 -37.949632)
				)
			)
		)
	)
	(zone
		(layers "In3.Cu" "In6.Cu" "In8.Cu")
		(hatch none 0.5)
		(connect_pads
			(clearance 0)
		)
		(min_thickness 0.25)
		(keepout
			(tracks not_allowed)
			(vias allowed)
			(pads allowed)
			(copperpour not_allowed)
			(footprints allowed)
		)
		(placement
			(enabled no)
			(sheetname "")
		)
		(fill yes
			(thermal_gap 0.5)
			(thermal_bridge_width 0.5)
			(island_removal_mode 0)
		)
		(polygon
			(pts
				(arc
					(start 184.929018 -37.949632)
					(mid 182.130954 -37.949632)
					(end 184.929018 -37.949632)
				)
			)
		)
	)
	(zone
		(layers "In3.Cu" "In6.Cu" "In8.Cu")
		(hatch none 0.5)
		(connect_pads
			(clearance 0)
		)
		(min_thickness 0.25)
		(keepout
			(tracks not_allowed)
			(vias allowed)
			(pads allowed)
			(copperpour not_allowed)
			(footprints allowed)
		)
		(placement
			(enabled no)
			(sheetname "")
		)
		(fill yes
			(thermal_gap 0.5)
			(thermal_bridge_width 0.5)
			(island_removal_mode 0)
		)
		(polygon
			(pts
				(arc
					(start 112.33404 -35.47999)
					(mid 109.535976 -35.47999)
					(end 112.33404 -35.47999)
				)
			)
		)
	)
	(zone
		(layers "In3.Cu" "In6.Cu" "In8.Cu")
		(hatch none 0.5)
		(connect_pads
			(clearance 0)
		)
		(min_thickness 0.25)
		(keepout
			(tracks not_allowed)
			(vias allowed)
			(pads allowed)
			(copperpour not_allowed)
			(footprints allowed)
		)
		(placement
			(enabled no)
			(sheetname "")
		)
		(fill yes
			(thermal_gap 0.5)
			(thermal_bridge_width 0.5)
			(island_removal_mode 0)
		)
		(polygon
			(pts
				(arc
					(start 202.709018 -30.329632)
					(mid 199.910954 -30.329632)
					(end 202.709018 -30.329632)
				)
			)
		)
	)
	(zone
		(layers "In3.Cu" "In6.Cu" "In8.Cu")
		(hatch none 0.5)
		(connect_pads
			(clearance 0)
		)
		(min_thickness 0.25)
		(keepout
			(tracks not_allowed)
			(vias allowed)
			(pads allowed)
			(copperpour not_allowed)
			(footprints allowed)
		)
		(placement
			(enabled no)
			(sheetname "")
		)
		(fill yes
			(thermal_gap 0.5)
			(thermal_bridge_width 0.5)
			(island_removal_mode 0)
		)
		(polygon
			(pts
				(arc
					(start 112.33404 -38.01999)
					(mid 109.535976 -38.01999)
					(end 112.33404 -38.01999)
				)
			)
		)
	)
	(zone
		(layers "In3.Cu" "In6.Cu" "In8.Cu")
		(hatch none 0.5)
		(connect_pads
			(clearance 0)
		)
		(min_thickness 0.25)
		(keepout
			(tracks not_allowed)
			(vias allowed)
			(pads allowed)
			(copperpour not_allowed)
			(footprints allowed)
		)
		(placement
			(enabled no)
			(sheetname "")
		)
		(fill yes
			(thermal_gap 0.5)
			(thermal_bridge_width 0.5)
			(island_removal_mode 0)
		)
		(polygon
			(pts
				(arc
					(start 103.44404 -35.47999)
					(mid 100.645976 -35.47999)
					(end 103.44404 -35.47999)
				)
			)
		)
	)
	(zone
		(layers "In3.Cu" "In6.Cu" "In8.Cu")
		(hatch none 0.5)
		(connect_pads
			(clearance 0)
		)
		(min_thickness 0.25)
		(keepout
			(tracks not_allowed)
			(vias allowed)
			(pads allowed)
			(copperpour not_allowed)
			(footprints allowed)
		)
		(placement
			(enabled no)
			(sheetname "")
		)
		(fill yes
			(thermal_gap 0.5)
			(thermal_bridge_width 0.5)
			(island_removal_mode 0)
		)
		(polygon
			(pts
				(arc
					(start 184.929018 -35.409632)
					(mid 182.130954 -35.409632)
					(end 184.929018 -35.409632)
				)
			)
		)
	)
	(zone
		(layers "In3.Cu" "In6.Cu" "In8.Cu")
		(hatch none 0.5)
		(connect_pads
			(clearance 0)
		)
		(min_thickness 0.25)
		(keepout
			(tracks not_allowed)
			(vias allowed)
			(pads allowed)
			(copperpour not_allowed)
			(footprints allowed)
		)
		(placement
			(enabled no)
			(sheetname "")
		)
		(fill yes
			(thermal_gap 0.5)
			(thermal_bridge_width 0.5)
			(island_removal_mode 0)
		)
		(polygon
			(pts
				(arc
					(start 202.709018 -35.409632)
					(mid 199.910954 -35.409632)
					(end 202.709018 -35.409632)
				)
			)
		)
	)
	(zone
		(layers "In3.Cu" "In6.Cu" "In8.Cu")
		(hatch none 0.5)
		(connect_pads
			(clearance 0)
		)
		(min_thickness 0.25)
		(keepout
			(tracks not_allowed)
			(vias allowed)
			(pads allowed)
			(copperpour not_allowed)
			(footprints allowed)
		)
		(placement
			(enabled no)
			(sheetname "")
		)
		(fill yes
			(thermal_gap 0.5)
			(thermal_bridge_width 0.5)
			(island_removal_mode 0)
		)
		(polygon
			(pts
				(arc
					(start 184.929018 -32.869632)
					(mid 182.130954 -32.869632)
					(end 184.929018 -32.869632)
				)
			)
		)
	)
	(zone
		(layers "In3.Cu" "In6.Cu" "In8.Cu")
		(hatch none 0.5)
		(connect_pads
			(clearance 0)
		)
		(min_thickness 0.25)
		(keepout
			(tracks not_allowed)
			(vias allowed)
			(pads allowed)
			(copperpour not_allowed)
			(footprints allowed)
		)
		(placement
			(enabled no)
			(sheetname "")
		)
		(fill yes
			(thermal_gap 0.5)
			(thermal_bridge_width 0.5)
			(island_removal_mode 0)
		)
		(polygon
			(pts
				(arc
					(start 121.22404 -35.47999)
					(mid 118.425976 -35.47999)
					(end 121.22404 -35.47999)
				)
			)
		)
	)
	(zone
		(layers "In3.Cu" "In6.Cu" "In8.Cu")
		(hatch none 0.5)
		(connect_pads
			(clearance 0)
		)
		(min_thickness 0.25)
		(keepout
			(tracks not_allowed)
			(vias allowed)
			(pads allowed)
			(copperpour not_allowed)
			(footprints allowed)
		)
		(placement
			(enabled no)
			(sheetname "")
		)
		(fill yes
			(thermal_gap 0.5)
			(thermal_bridge_width 0.5)
			(island_removal_mode 0)
		)
		(polygon
			(pts
				(arc
					(start 182.389018 -32.869632)
					(mid 179.590954 -32.869632)
					(end 182.389018 -32.869632)
				)
			)
		)
	)
	(zone
		(layers "In3.Cu" "In6.Cu" "In8.Cu")
		(hatch none 0.5)
		(connect_pads
			(clearance 0)
		)
		(min_thickness 0.25)
		(keepout
			(tracks not_allowed)
			(vias allowed)
			(pads allowed)
			(copperpour not_allowed)
			(footprints allowed)
		)
		(placement
			(enabled no)
			(sheetname "")
		)
		(fill yes
			(thermal_gap 0.5)
			(thermal_bridge_width 0.5)
			(island_removal_mode 0)
		)
		(polygon
			(pts
				(arc
					(start 112.33404 -32.93999)
					(mid 109.535976 -32.93999)
					(end 112.33404 -32.93999)
				)
			)
		)
	)
	(zone
		(layers "In3.Cu" "In6.Cu" "In8.Cu")
		(hatch none 0.5)
		(connect_pads
			(clearance 0)
		)
		(min_thickness 0.25)
		(keepout
			(tracks not_allowed)
			(vias allowed)
			(pads allowed)
			(copperpour not_allowed)
			(footprints allowed)
		)
		(placement
			(enabled no)
			(sheetname "")
		)
		(fill yes
			(thermal_gap 0.5)
			(thermal_bridge_width 0.5)
			(island_removal_mode 0)
		)
		(polygon
			(pts
				(arc
					(start 123.76404 -32.93999)
					(mid 120.965976 -32.93999)
					(end 123.76404 -32.93999)
				)
			)
		)
	)
	(zone
		(layer "In4.Cu")
		(hatch none 0.5)
		(connect_pads
			(clearance 0)
		)
		(min_thickness 0.25)
		(keepout
			(tracks not_allowed)
			(vias allowed)
			(pads allowed)
			(copperpour not_allowed)
			(footprints allowed)
		)
		(placement
			(enabled no)
			(sheetname "")
		)
		(fill
			(thermal_gap 0.5)
			(thermal_bridge_width 0.5)
			(island_removal_mode 0)
		)
		(polygon
			(pts
				(arc
					(start 208.000092 -6.999986)
					(mid 203.000102 -11.999976)
					(end 208.000092 -16.999966)
				)
				(arc
					(start 230.000048 -16.999966)
					(mid 235.000038 -11.999976)
					(end 230.000048 -6.999986)
				)
			)
		)
	)
	(zone
		(layer "In4.Cu")
		(hatch none 0.5)
		(connect_pads
			(clearance 0)
		)
		(min_thickness 0.25)
		(keepout
			(tracks not_allowed)
			(vias allowed)
			(pads allowed)
			(copperpour not_allowed)
			(footprints allowed)
		)
		(placement
			(enabled no)
			(sheetname "")
		)
		(fill
			(thermal_gap 0.5)
			(thermal_bridge_width 0.5)
			(island_removal_mode 0)
		)
		(polygon
			(pts
				(arc
					(start 218.186 -92.329)
					(mid 216.408 -92.329)
					(end 218.186 -92.329)
				)
			)
		)
	)
	(zone
		(layer "In4.Cu")
		(hatch none 0.5)
		(connect_pads
			(clearance 0)
		)
		(min_thickness 0.25)
		(keepout
			(tracks not_allowed)
			(vias allowed)
			(pads allowed)
			(copperpour not_allowed)
			(footprints allowed)
		)
		(placement
			(enabled no)
			(sheetname "")
		)
		(fill
			(thermal_gap 0.5)
			(thermal_bridge_width 0.5)
			(island_removal_mode 0)
		)
		(polygon
			(pts
				(arc
					(start 220.726 -92.329)
					(mid 218.948 -92.329)
					(end 220.726 -92.329)
				)
			)
		)
	)
	(zone
		(layer "In4.Cu")
		(hatch none 0.5)
		(connect_pads
			(clearance 0)
		)
		(min_thickness 0.25)
		(keepout
			(tracks not_allowed)
			(vias allowed)
			(pads allowed)
			(copperpour not_allowed)
			(footprints allowed)
		)
		(placement
			(enabled no)
			(sheetname "")
		)
		(fill
			(thermal_gap 0.5)
			(thermal_bridge_width 0.5)
			(island_removal_mode 0)
		)
		(polygon
			(pts
				(arc
					(start 219.329 -92.329)
					(mid 217.551 -92.329)
					(end 219.329 -92.329)
				)
			)
		)
	)
	(zone
		(layers "In4.Cu" "In5.Cu")
		(hatch none 0.5)
		(connect_pads
			(clearance 0)
		)
		(min_thickness 0.25)
		(keepout
			(tracks not_allowed)
			(vias allowed)
			(pads allowed)
			(copperpour not_allowed)
			(footprints allowed)
		)
		(placement
			(enabled no)
			(sheetname "")
		)
		(fill yes
			(thermal_gap 0.5)
			(thermal_bridge_width 0.5)
			(island_removal_mode 0)
		)
		(polygon
			(pts
				(arc
					(start 97.738946 -113.03635)
					(mid 95.960946 -113.03635)
					(end 97.738946 -113.03635)
				)
			)
		)
	)
	(zone
		(layers "In4.Cu" "In5.Cu")
		(hatch none 0.5)
		(connect_pads
			(clearance 0)
		)
		(min_thickness 0.25)
		(keepout
			(tracks not_allowed)
			(vias allowed)
			(pads allowed)
			(copperpour not_allowed)
			(footprints allowed)
		)
		(placement
			(enabled no)
			(sheetname "")
		)
		(fill yes
			(thermal_gap 0.5)
			(thermal_bridge_width 0.5)
			(island_removal_mode 0)
		)
		(polygon
			(pts
				(arc
					(start 176.276 -51.562)
					(mid 174.498 -51.562)
					(end 176.276 -51.562)
				)
			)
		)
	)
	(zone
		(layers "In4.Cu" "In5.Cu")
		(hatch none 0.5)
		(connect_pads
			(clearance 0)
		)
		(min_thickness 0.25)
		(keepout
			(tracks not_allowed)
			(vias allowed)
			(pads allowed)
			(copperpour not_allowed)
			(footprints allowed)
		)
		(placement
			(enabled no)
			(sheetname "")
		)
		(fill yes
			(thermal_gap 0.5)
			(thermal_bridge_width 0.5)
			(island_removal_mode 0)
		)
		(polygon
			(pts
				(arc
					(start 88.202008 -38.01999)
					(mid 85.408008 -38.01999)
					(end 88.202008 -38.01999)
				)
			)
		)
	)
	(zone
		(layers "In4.Cu" "In5.Cu")
		(hatch none 0.5)
		(connect_pads
			(clearance 0)
		)
		(min_thickness 0.25)
		(keepout
			(tracks not_allowed)
			(vias allowed)
			(pads allowed)
			(copperpour not_allowed)
			(footprints allowed)
		)
		(placement
			(enabled no)
			(sheetname "")
		)
		(fill yes
			(thermal_gap 0.5)
			(thermal_bridge_width 0.5)
			(island_removal_mode 0)
		)
		(polygon
			(pts
				(arc
					(start 86.823296 -39.27221)
					(mid 84.029296 -39.27221)
					(end 86.823296 -39.27221)
				)
			)
		)
	)
	(zone
		(layers "In4.Cu" "In5.Cu")
		(hatch none 0.5)
		(connect_pads
			(clearance 0)
		)
		(min_thickness 0.25)
		(keepout
			(tracks not_allowed)
			(vias allowed)
			(pads allowed)
			(copperpour not_allowed)
			(footprints allowed)
		)
		(placement
			(enabled no)
			(sheetname "")
		)
		(fill yes
			(thermal_gap 0.5)
			(thermal_bridge_width 0.5)
			(island_removal_mode 0)
		)
		(polygon
			(pts
				(arc
					(start 159.512 -55.96001)
					(mid 156.718 -55.96001)
					(end 159.512 -55.96001)
				)
			)
		)
	)
	(zone
		(layers "In4.Cu" "In5.Cu")
		(hatch none 0.5)
		(connect_pads
			(clearance 0)
		)
		(min_thickness 0.25)
		(keepout
			(tracks not_allowed)
			(vias allowed)
			(pads allowed)
			(copperpour not_allowed)
			(footprints allowed)
		)
		(placement
			(enabled no)
			(sheetname "")
		)
		(fill yes
			(thermal_gap 0.5)
			(thermal_bridge_width 0.5)
			(island_removal_mode 0)
		)
		(polygon
			(pts
				(arc
					(start 138.66622 -121.209816)
					(mid 135.03402 -121.209816)
					(end 138.66622 -121.209816)
				)
			)
		)
	)
	(zone
		(layers "In4.Cu" "In5.Cu")
		(hatch none 0.5)
		(connect_pads
			(clearance 0)
		)
		(min_thickness 0.25)
		(keepout
			(tracks not_allowed)
			(vias allowed)
			(pads allowed)
			(copperpour not_allowed)
			(footprints allowed)
		)
		(placement
			(enabled no)
			(sheetname "")
		)
		(fill yes
			(thermal_gap 0.5)
			(thermal_bridge_width 0.5)
			(island_removal_mode 0)
		)
		(polygon
			(pts
				(arc
					(start 60.661296 -136.906)
					(mid 57.816496 -136.906)
					(end 60.661296 -136.906)
				)
			)
		)
	)
	(zone
		(layers "In4.Cu" "In5.Cu")
		(hatch none 0.5)
		(connect_pads
			(clearance 0)
		)
		(min_thickness 0.25)
		(keepout
			(tracks not_allowed)
			(vias allowed)
			(pads allowed)
			(copperpour not_allowed)
			(footprints allowed)
		)
		(placement
			(enabled no)
			(sheetname "")
		)
		(fill yes
			(thermal_gap 0.5)
			(thermal_bridge_width 0.5)
			(island_removal_mode 0)
		)
		(polygon
			(pts
				(arc
					(start 236.347 -90.91295)
					(mid 234.569 -90.91295)
					(end 236.347 -90.91295)
				)
			)
		)
	)
	(zone
		(layers "In4.Cu" "In5.Cu")
		(hatch none 0.5)
		(connect_pads
			(clearance 0)
		)
		(min_thickness 0.25)
		(keepout
			(tracks not_allowed)
			(vias allowed)
			(pads allowed)
			(copperpour not_allowed)
			(footprints allowed)
		)
		(placement
			(enabled no)
			(sheetname "")
		)
		(fill yes
			(thermal_gap 0.5)
			(thermal_bridge_width 0.5)
			(island_removal_mode 0)
		)
		(polygon
			(pts
				(arc
					(start 97.092008 -40.55999)
					(mid 94.298008 -40.55999)
					(end 97.092008 -40.55999)
				)
			)
		)
	)
	(zone
		(layers "In4.Cu" "In5.Cu")
		(hatch none 0.5)
		(connect_pads
			(clearance 0)
		)
		(min_thickness 0.25)
		(keepout
			(tracks not_allowed)
			(vias allowed)
			(pads allowed)
			(copperpour not_allowed)
			(footprints allowed)
		)
		(placement
			(enabled no)
			(sheetname "")
		)
		(fill yes
			(thermal_gap 0.5)
			(thermal_bridge_width 0.5)
			(island_removal_mode 0)
		)
		(polygon
			(pts
				(arc
					(start 236.093 -72.00265)
					(mid 234.315 -72.00265)
					(end 236.093 -72.00265)
				)
			)
		)
	)
	(zone
		(layers "In4.Cu" "In5.Cu")
		(hatch none 0.5)
		(connect_pads
			(clearance 0)
		)
		(min_thickness 0.25)
		(keepout
			(tracks not_allowed)
			(vias allowed)
			(pads allowed)
			(copperpour not_allowed)
			(footprints allowed)
		)
		(placement
			(enabled no)
			(sheetname "")
		)
		(fill yes
			(thermal_gap 0.5)
			(thermal_bridge_width 0.5)
			(island_removal_mode 0)
		)
		(polygon
			(pts
				(arc
					(start 57.739026 -113.03635)
					(mid 55.961026 -113.03635)
					(end 57.739026 -113.03635)
				)
			)
		)
	)
	(zone
		(layers "In4.Cu" "In5.Cu")
		(hatch none 0.5)
		(connect_pads
			(clearance 0)
		)
		(min_thickness 0.25)
		(keepout
			(tracks not_allowed)
			(vias allowed)
			(pads allowed)
			(copperpour not_allowed)
			(footprints allowed)
		)
		(placement
			(enabled no)
			(sheetname "")
		)
		(fill yes
			(thermal_gap 0.5)
			(thermal_bridge_width 0.5)
			(island_removal_mode 0)
		)
		(polygon
			(pts
				(arc
					(start 51.37404 -62.2554)
					(mid 49.59604 -62.2554)
					(end 51.37404 -62.2554)
				)
			)
		)
	)
	(zone
		(layers "In4.Cu" "In5.Cu")
		(hatch none 0.5)
		(connect_pads
			(clearance 0)
		)
		(min_thickness 0.25)
		(keepout
			(tracks not_allowed)
			(vias allowed)
			(pads allowed)
			(copperpour not_allowed)
			(footprints allowed)
		)
		(placement
			(enabled no)
			(sheetname "")
		)
		(fill yes
			(thermal_gap 0.5)
			(thermal_bridge_width 0.5)
			(island_removal_mode 0)
		)
		(polygon
			(pts
				(arc
					(start 49.08804 -62.2554)
					(mid 47.31004 -62.2554)
					(end 49.08804 -62.2554)
				)
			)
		)
	)
	(zone
		(layers "In4.Cu" "In5.Cu")
		(hatch none 0.5)
		(connect_pads
			(clearance 0)
		)
		(min_thickness 0.25)
		(keepout
			(tracks not_allowed)
			(vias allowed)
			(pads allowed)
			(copperpour not_allowed)
			(footprints allowed)
		)
		(placement
			(enabled no)
			(sheetname "")
		)
		(fill yes
			(thermal_gap 0.5)
			(thermal_bridge_width 0.5)
			(island_removal_mode 0)
		)
		(polygon
			(pts
				(arc
					(start 76.327 -51.689)
					(mid 74.549 -51.689)
					(end 76.327 -51.689)
				)
			)
		)
	)
	(zone
		(layers "In4.Cu" "In5.Cu")
		(hatch none 0.5)
		(connect_pads
			(clearance 0)
		)
		(min_thickness 0.25)
		(keepout
			(tracks not_allowed)
			(vias allowed)
			(pads allowed)
			(copperpour not_allowed)
			(footprints allowed)
		)
		(placement
			(enabled no)
			(sheetname "")
		)
		(fill yes
			(thermal_gap 0.5)
			(thermal_bridge_width 0.5)
			(island_removal_mode 0)
		)
		(polygon
			(pts
				(arc
					(start 78.089506 -36.787328)
					(mid 75.295506 -36.787328)
					(end 78.089506 -36.787328)
				)
			)
		)
	)
	(zone
		(layers "In4.Cu" "In5.Cu")
		(hatch none 0.5)
		(connect_pads
			(clearance 0)
		)
		(min_thickness 0.25)
		(keepout
			(tracks not_allowed)
			(vias allowed)
			(pads allowed)
			(copperpour not_allowed)
			(footprints allowed)
		)
		(placement
			(enabled no)
			(sheetname "")
		)
		(fill yes
			(thermal_gap 0.5)
			(thermal_bridge_width 0.5)
			(island_removal_mode 0)
		)
		(polygon
			(pts
				(arc
					(start 181.73446 -50.292)
					(mid 179.95646 -50.292)
					(end 181.73446 -50.292)
				)
			)
		)
	)
	(zone
		(layers "In4.Cu" "In5.Cu")
		(hatch none 0.5)
		(connect_pads
			(clearance 0)
		)
		(min_thickness 0.25)
		(keepout
			(tracks not_allowed)
			(vias allowed)
			(pads allowed)
			(copperpour not_allowed)
			(footprints allowed)
		)
		(placement
			(enabled no)
			(sheetname "")
		)
		(fill yes
			(thermal_gap 0.5)
			(thermal_bridge_width 0.5)
			(island_removal_mode 0)
		)
		(polygon
			(pts
				(arc
					(start 227.803202 -75.87996)
					(mid 226.025202 -75.87996)
					(end 227.803202 -75.87996)
				)
			)
		)
	)
	(zone
		(layers "In4.Cu" "In5.Cu")
		(hatch none 0.5)
		(connect_pads
			(clearance 0)
		)
		(min_thickness 0.25)
		(keepout
			(tracks not_allowed)
			(vias allowed)
			(pads allowed)
			(copperpour not_allowed)
			(footprints allowed)
		)
		(placement
			(enabled no)
			(sheetname "")
		)
		(fill yes
			(thermal_gap 0.5)
			(thermal_bridge_width 0.5)
			(island_removal_mode 0)
		)
		(polygon
			(pts
				(arc
					(start 287.655 -44.831)
					(mid 285.877 -44.831)
					(end 287.655 -44.831)
				)
			)
		)
	)
	(zone
		(layers "In4.Cu" "In5.Cu")
		(hatch none 0.5)
		(connect_pads
			(clearance 0)
		)
		(min_thickness 0.25)
		(keepout
			(tracks not_allowed)
			(vias allowed)
			(pads allowed)
			(copperpour not_allowed)
			(footprints allowed)
		)
		(placement
			(enabled no)
			(sheetname "")
		)
		(fill yes
			(thermal_gap 0.5)
			(thermal_bridge_width 0.5)
			(island_removal_mode 0)
		)
		(polygon
			(pts
				(arc
					(start 92.71 -50.419)
					(mid 90.932 -50.419)
					(end 92.71 -50.419)
				)
			)
		)
	)
	(zone
		(layers "In4.Cu" "In5.Cu")
		(hatch none 0.5)
		(connect_pads
			(clearance 0)
		)
		(min_thickness 0.25)
		(keepout
			(tracks not_allowed)
			(vias allowed)
			(pads allowed)
			(copperpour not_allowed)
			(footprints allowed)
		)
		(placement
			(enabled no)
			(sheetname "")
		)
		(fill yes
			(thermal_gap 0.5)
			(thermal_bridge_width 0.5)
			(island_removal_mode 0)
		)
		(polygon
			(pts
				(arc
					(start 221.869 -77.34935)
					(mid 220.091 -77.34935)
					(end 221.869 -77.34935)
				)
			)
		)
	)
	(zone
		(layers "In4.Cu" "In5.Cu")
		(hatch none 0.5)
		(connect_pads
			(clearance 0)
		)
		(min_thickness 0.25)
		(keepout
			(tracks not_allowed)
			(vias allowed)
			(pads allowed)
			(copperpour not_allowed)
			(footprints allowed)
		)
		(placement
			(enabled no)
			(sheetname "")
		)
		(fill yes
			(thermal_gap 0.5)
			(thermal_bridge_width 0.5)
			(island_removal_mode 0)
		)
		(polygon
			(pts
				(arc
					(start 223.012 -92.964)
					(mid 221.234 -92.964)
					(end 223.012 -92.964)
				)
			)
		)
	)
	(zone
		(layers "In4.Cu" "In5.Cu")
		(hatch none 0.5)
		(connect_pads
			(clearance 0)
		)
		(min_thickness 0.25)
		(keepout
			(tracks not_allowed)
			(vias allowed)
			(pads allowed)
			(copperpour not_allowed)
			(footprints allowed)
		)
		(placement
			(enabled no)
			(sheetname "")
		)
		(fill yes
			(thermal_gap 0.5)
			(thermal_bridge_width 0.5)
			(island_removal_mode 0)
		)
		(polygon
			(pts
				(arc
					(start 218.44 -92.964)
					(mid 216.662 -92.964)
					(end 218.44 -92.964)
				)
			)
		)
	)
	(zone
		(layers "In4.Cu" "In5.Cu")
		(hatch none 0.5)
		(connect_pads
			(clearance 0)
		)
		(min_thickness 0.25)
		(keepout
			(tracks not_allowed)
			(vias allowed)
			(pads allowed)
			(copperpour not_allowed)
			(footprints allowed)
		)
		(placement
			(enabled no)
			(sheetname "")
		)
		(fill yes
			(thermal_gap 0.5)
			(thermal_bridge_width 0.5)
			(island_removal_mode 0)
		)
		(polygon
			(pts
				(arc
					(start 51.046126 -121.209816)
					(mid 47.413926 -121.209816)
					(end 51.046126 -121.209816)
				)
			)
		)
	)
	(zone
		(layers "In4.Cu" "In5.Cu")
		(hatch none 0.5)
		(connect_pads
			(clearance 0)
		)
		(min_thickness 0.25)
		(keepout
			(tracks not_allowed)
			(vias allowed)
			(pads allowed)
			(copperpour not_allowed)
			(footprints allowed)
		)
		(placement
			(enabled no)
			(sheetname "")
		)
		(fill yes
			(thermal_gap 0.5)
			(thermal_bridge_width 0.5)
			(island_removal_mode 0)
		)
		(polygon
			(pts
				(arc
					(start 166.746174 -131.572)
					(mid 164.968174 -131.572)
					(end 166.746174 -131.572)
				)
			)
		)
	)
	(zone
		(layers "In4.Cu" "In5.Cu")
		(hatch none 0.5)
		(connect_pads
			(clearance 0)
		)
		(min_thickness 0.25)
		(keepout
			(tracks not_allowed)
			(vias allowed)
			(pads allowed)
			(copperpour not_allowed)
			(footprints allowed)
		)
		(placement
			(enabled no)
			(sheetname "")
		)
		(fill yes
			(thermal_gap 0.5)
			(thermal_bridge_width 0.5)
			(island_removal_mode 0)
		)
		(polygon
			(pts
				(arc
					(start 159.893 -52.197)
					(mid 158.115 -52.197)
					(end 159.893 -52.197)
				)
			)
		)
	)
	(zone
		(layers "In4.Cu" "In5.Cu")
		(hatch none 0.5)
		(connect_pads
			(clearance 0)
		)
		(min_thickness 0.25)
		(keepout
			(tracks not_allowed)
			(vias allowed)
			(pads allowed)
			(copperpour not_allowed)
			(footprints allowed)
		)
		(placement
			(enabled no)
			(sheetname "")
		)
		(fill yes
			(thermal_gap 0.5)
			(thermal_bridge_width 0.5)
			(island_removal_mode 0)
		)
		(polygon
			(pts
				(arc
					(start 151.892 -131.572)
					(mid 150.114 -131.572)
					(end 151.892 -131.572)
				)
			)
		)
	)
	(zone
		(layers "In4.Cu" "In5.Cu")
		(hatch none 0.5)
		(connect_pads
			(clearance 0)
		)
		(min_thickness 0.25)
		(keepout
			(tracks not_allowed)
			(vias allowed)
			(pads allowed)
			(copperpour not_allowed)
			(footprints allowed)
		)
		(placement
			(enabled no)
			(sheetname "")
		)
		(fill yes
			(thermal_gap 0.5)
			(thermal_bridge_width 0.5)
			(island_removal_mode 0)
		)
		(polygon
			(pts
				(arc
					(start 47.713646 -54.013354)
					(mid 45.935646 -54.013354)
					(end 47.713646 -54.013354)
				)
			)
		)
	)
	(zone
		(layers "In4.Cu" "In5.Cu")
		(hatch none 0.5)
		(connect_pads
			(clearance 0)
		)
		(min_thickness 0.25)
		(keepout
			(tracks not_allowed)
			(vias allowed)
			(pads allowed)
			(copperpour not_allowed)
			(footprints allowed)
		)
		(placement
			(enabled no)
			(sheetname "")
		)
		(fill yes
			(thermal_gap 0.5)
			(thermal_bridge_width 0.5)
			(island_removal_mode 0)
		)
		(polygon
			(pts
				(arc
					(start 95.713296 -39.27221)
					(mid 92.919296 -39.27221)
					(end 95.713296 -39.27221)
				)
			)
		)
	)
	(zone
		(layers "In4.Cu" "In5.Cu")
		(hatch none 0.5)
		(connect_pads
			(clearance 0)
		)
		(min_thickness 0.25)
		(keepout
			(tracks not_allowed)
			(vias allowed)
			(pads allowed)
			(copperpour not_allowed)
			(footprints allowed)
		)
		(placement
			(enabled no)
			(sheetname "")
		)
		(fill yes
			(thermal_gap 0.5)
			(thermal_bridge_width 0.5)
			(island_removal_mode 0)
		)
		(polygon
			(pts
				(arc
					(start 170.688 -55.96001)
					(mid 167.894 -55.96001)
					(end 170.688 -55.96001)
				)
			)
		)
	)
	(zone
		(layers "In4.Cu" "In5.Cu")
		(hatch none 0.5)
		(connect_pads
			(clearance 0)
		)
		(min_thickness 0.25)
		(keepout
			(tracks not_allowed)
			(vias allowed)
			(pads allowed)
			(copperpour not_allowed)
			(footprints allowed)
		)
		(placement
			(enabled no)
			(sheetname "")
		)
		(fill yes
			(thermal_gap 0.5)
			(thermal_bridge_width 0.5)
			(island_removal_mode 0)
		)
		(polygon
			(pts
				(arc
					(start 81.788 -49.784)
					(mid 80.01 -49.784)
					(end 81.788 -49.784)
				)
			)
		)
	)
	(zone
		(layers "In4.Cu" "In5.Cu")
		(hatch none 0.5)
		(connect_pads
			(clearance 0)
		)
		(min_thickness 0.25)
		(keepout
			(tracks not_allowed)
			(vias allowed)
			(pads allowed)
			(copperpour not_allowed)
			(footprints allowed)
		)
		(placement
			(enabled no)
			(sheetname "")
		)
		(fill yes
			(thermal_gap 0.5)
			(thermal_bridge_width 0.5)
			(island_removal_mode 0)
		)
		(polygon
			(pts
				(arc
					(start 167.508174 -131.572)
					(mid 165.730174 -131.572)
					(end 167.508174 -131.572)
				)
			)
		)
	)
	(zone
		(layers "In4.Cu" "In5.Cu")
		(hatch none 0.5)
		(connect_pads
			(clearance 0)
		)
		(min_thickness 0.25)
		(keepout
			(tracks not_allowed)
			(vias allowed)
			(pads allowed)
			(copperpour not_allowed)
			(footprints allowed)
		)
		(placement
			(enabled no)
			(sheetname "")
		)
		(fill yes
			(thermal_gap 0.5)
			(thermal_bridge_width 0.5)
			(island_removal_mode 0)
		)
		(polygon
			(pts
				(arc
					(start 191.130174 -126.492)
					(mid 189.352174 -126.492)
					(end 191.130174 -126.492)
				)
			)
		)
	)
	(zone
		(layers "In4.Cu" "In5.Cu")
		(hatch none 0.5)
		(connect_pads
			(clearance 0)
		)
		(min_thickness 0.25)
		(keepout
			(tracks not_allowed)
			(vias allowed)
			(pads allowed)
			(copperpour not_allowed)
			(footprints allowed)
		)
		(placement
			(enabled no)
			(sheetname "")
		)
		(fill yes
			(thermal_gap 0.5)
			(thermal_bridge_width 0.5)
			(island_removal_mode 0)
		)
		(polygon
			(pts
				(arc
					(start 285.4198 -39.878)
					(mid 283.6418 -39.878)
					(end 285.4198 -39.878)
				)
			)
		)
	)
	(zone
		(layers "In4.Cu" "In5.Cu")
		(hatch none 0.5)
		(connect_pads
			(clearance 0)
		)
		(min_thickness 0.25)
		(keepout
			(tracks not_allowed)
			(vias allowed)
			(pads allowed)
			(copperpour not_allowed)
			(footprints allowed)
		)
		(placement
			(enabled no)
			(sheetname "")
		)
		(fill yes
			(thermal_gap 0.5)
			(thermal_bridge_width 0.5)
			(island_removal_mode 0)
		)
		(polygon
			(pts
				(arc
					(start 85.662008 -35.47999)
					(mid 82.868008 -35.47999)
					(end 85.662008 -35.47999)
				)
			)
		)
	)
	(zone
		(layers "In4.Cu" "In5.Cu")
		(hatch none 0.5)
		(connect_pads
			(clearance 0)
		)
		(min_thickness 0.25)
		(keepout
			(tracks not_allowed)
			(vias allowed)
			(pads allowed)
			(copperpour not_allowed)
			(footprints allowed)
		)
		(placement
			(enabled no)
			(sheetname "")
		)
		(fill yes
			(thermal_gap 0.5)
			(thermal_bridge_width 0.5)
			(island_removal_mode 0)
		)
		(polygon
			(pts
				(arc
					(start 76.327 -49.784)
					(mid 74.549 -49.784)
					(end 76.327 -49.784)
				)
			)
		)
	)
	(zone
		(layers "In4.Cu" "In5.Cu")
		(hatch none 0.5)
		(connect_pads
			(clearance 0)
		)
		(min_thickness 0.25)
		(keepout
			(tracks not_allowed)
			(vias allowed)
			(pads allowed)
			(copperpour not_allowed)
			(footprints allowed)
		)
		(placement
			(enabled no)
			(sheetname "")
		)
		(fill yes
			(thermal_gap 0.5)
			(thermal_bridge_width 0.5)
			(island_removal_mode 0)
		)
		(polygon
			(pts
				(arc
					(start 98.937826 -126.492)
					(mid 97.159826 -126.492)
					(end 98.937826 -126.492)
				)
			)
		)
	)
	(zone
		(layers "In4.Cu" "In5.Cu")
		(hatch none 0.5)
		(connect_pads
			(clearance 0)
		)
		(min_thickness 0.25)
		(keepout
			(tracks not_allowed)
			(vias allowed)
			(pads allowed)
			(copperpour not_allowed)
			(footprints allowed)
		)
		(placement
			(enabled no)
			(sheetname "")
		)
		(fill yes
			(thermal_gap 0.5)
			(thermal_bridge_width 0.5)
			(island_removal_mode 0)
		)
		(polygon
			(pts
				(arc
					(start 87.249 -49.784)
					(mid 85.471 -49.784)
					(end 87.249 -49.784)
				)
			)
		)
	)
	(zone
		(layers "In4.Cu" "In5.Cu")
		(hatch none 0.5)
		(connect_pads
			(clearance 0)
		)
		(min_thickness 0.25)
		(keepout
			(tracks not_allowed)
			(vias allowed)
			(pads allowed)
			(copperpour not_allowed)
			(footprints allowed)
		)
		(placement
			(enabled no)
			(sheetname "")
		)
		(fill yes
			(thermal_gap 0.5)
			(thermal_bridge_width 0.5)
			(island_removal_mode 0)
		)
		(polygon
			(pts
				(arc
					(start 225.806 -89.64295)
					(mid 224.028 -89.64295)
					(end 225.806 -89.64295)
				)
			)
		)
	)
	(zone
		(layers "In4.Cu" "In5.Cu")
		(hatch none 0.5)
		(connect_pads
			(clearance 0)
		)
		(min_thickness 0.25)
		(keepout
			(tracks not_allowed)
			(vias allowed)
			(pads allowed)
			(copperpour not_allowed)
			(footprints allowed)
		)
		(placement
			(enabled no)
			(sheetname "")
		)
		(fill yes
			(thermal_gap 0.5)
			(thermal_bridge_width 0.5)
			(island_removal_mode 0)
		)
		(polygon
			(pts
				(arc
					(start 109.093 -51.689)
					(mid 107.315 -51.689)
					(end 109.093 -51.689)
				)
			)
		)
	)
	(zone
		(layers "In4.Cu" "In5.Cu")
		(hatch none 0.5)
		(connect_pads
			(clearance 0)
		)
		(min_thickness 0.25)
		(keepout
			(tracks not_allowed)
			(vias allowed)
			(pads allowed)
			(copperpour not_allowed)
			(footprints allowed)
		)
		(placement
			(enabled no)
			(sheetname "")
		)
		(fill yes
			(thermal_gap 0.5)
			(thermal_bridge_width 0.5)
			(island_removal_mode 0)
		)
		(polygon
			(pts
				(arc
					(start 98.171 -49.784)
					(mid 96.393 -49.784)
					(end 98.171 -49.784)
				)
			)
		)
	)
	(zone
		(layers "In4.Cu" "In5.Cu")
		(hatch none 0.5)
		(connect_pads
			(clearance 0)
		)
		(min_thickness 0.25)
		(keepout
			(tracks not_allowed)
			(vias allowed)
			(pads allowed)
			(copperpour not_allowed)
			(footprints allowed)
		)
		(placement
			(enabled no)
			(sheetname "")
		)
		(fill yes
			(thermal_gap 0.5)
			(thermal_bridge_width 0.5)
			(island_removal_mode 0)
		)
		(polygon
			(pts
				(arc
					(start 223.139 -77.34935)
					(mid 221.361 -77.34935)
					(end 223.139 -77.34935)
				)
			)
		)
	)
	(zone
		(layers "In4.Cu" "In5.Cu")
		(hatch none 0.5)
		(connect_pads
			(clearance 0)
		)
		(min_thickness 0.25)
		(keepout
			(tracks not_allowed)
			(vias allowed)
			(pads allowed)
			(copperpour not_allowed)
			(footprints allowed)
		)
		(placement
			(enabled no)
			(sheetname "")
		)
		(fill yes
			(thermal_gap 0.5)
			(thermal_bridge_width 0.5)
			(island_removal_mode 0)
		)
		(polygon
			(pts
				(arc
					(start 85.662008 -40.55999)
					(mid 82.868008 -40.55999)
					(end 85.662008 -40.55999)
				)
			)
		)
	)
	(zone
		(layers "In4.Cu" "In5.Cu")
		(hatch none 0.5)
		(connect_pads
			(clearance 0)
		)
		(min_thickness 0.25)
		(keepout
			(tracks not_allowed)
			(vias allowed)
			(pads allowed)
			(copperpour not_allowed)
			(footprints allowed)
		)
		(placement
			(enabled no)
			(sheetname "")
		)
		(fill yes
			(thermal_gap 0.5)
			(thermal_bridge_width 0.5)
			(island_removal_mode 0)
		)
		(polygon
			(pts
				(arc
					(start 76.772008 -35.47999)
					(mid 73.978008 -35.47999)
					(end 76.772008 -35.47999)
				)
			)
		)
	)
	(zone
		(layers "In4.Cu" "In5.Cu")
		(hatch none 0.5)
		(connect_pads
			(clearance 0)
		)
		(min_thickness 0.25)
		(keepout
			(tracks not_allowed)
			(vias allowed)
			(pads allowed)
			(copperpour not_allowed)
			(footprints allowed)
		)
		(placement
			(enabled no)
			(sheetname "")
		)
		(fill yes
			(thermal_gap 0.5)
			(thermal_bridge_width 0.5)
			(island_removal_mode 0)
		)
		(polygon
			(pts
				(arc
					(start 159.893 -51.562)
					(mid 158.115 -51.562)
					(end 159.893 -51.562)
				)
			)
		)
	)
	(zone
		(layers "In4.Cu" "In5.Cu")
		(hatch none 0.5)
		(connect_pads
			(clearance 0)
		)
		(min_thickness 0.25)
		(keepout
			(tracks not_allowed)
			(vias allowed)
			(pads allowed)
			(copperpour not_allowed)
			(footprints allowed)
		)
		(placement
			(enabled no)
			(sheetname "")
		)
		(fill yes
			(thermal_gap 0.5)
			(thermal_bridge_width 0.5)
			(island_removal_mode 0)
		)
		(polygon
			(pts
				(arc
					(start 187.19546 -50.292)
					(mid 185.41746 -50.292)
					(end 187.19546 -50.292)
				)
			)
		)
	)
	(zone
		(layers "In4.Cu" "In5.Cu")
		(hatch none 0.5)
		(connect_pads
			(clearance 0)
		)
		(min_thickness 0.25)
		(keepout
			(tracks not_allowed)
			(vias allowed)
			(pads allowed)
			(copperpour not_allowed)
			(footprints allowed)
		)
		(placement
			(enabled no)
			(sheetname "")
		)
		(fill yes
			(thermal_gap 0.5)
			(thermal_bridge_width 0.5)
			(island_removal_mode 0)
		)
		(polygon
			(pts
				(arc
					(start 176.276 -50.292)
					(mid 174.498 -50.292)
					(end 176.276 -50.292)
				)
			)
		)
	)
	(zone
		(layers "In4.Cu" "In5.Cu")
		(hatch none 0.5)
		(connect_pads
			(clearance 0)
		)
		(min_thickness 0.25)
		(keepout
			(tracks not_allowed)
			(vias allowed)
			(pads allowed)
			(copperpour not_allowed)
			(footprints allowed)
		)
		(placement
			(enabled no)
			(sheetname "")
		)
		(fill yes
			(thermal_gap 0.5)
			(thermal_bridge_width 0.5)
			(island_removal_mode 0)
		)
		(polygon
			(pts
				(arc
					(start 78.124304 -34.26206)
					(mid 75.330304 -34.26206)
					(end 78.124304 -34.26206)
				)
			)
		)
	)
	(zone
		(layers "In4.Cu" "In5.Cu")
		(hatch none 0.5)
		(connect_pads
			(clearance 0)
		)
		(min_thickness 0.25)
		(keepout
			(tracks not_allowed)
			(vias allowed)
			(pads allowed)
			(copperpour not_allowed)
			(footprints allowed)
		)
		(placement
			(enabled no)
			(sheetname "")
		)
		(fill yes
			(thermal_gap 0.5)
			(thermal_bridge_width 0.5)
			(island_removal_mode 0)
		)
		(polygon
			(pts
				(arc
					(start 52.13604 -62.2554)
					(mid 50.35804 -62.2554)
					(end 52.13604 -62.2554)
				)
			)
		)
	)
	(zone
		(layers "In4.Cu" "In5.Cu")
		(hatch none 0.5)
		(connect_pads
			(clearance 0)
		)
		(min_thickness 0.25)
		(keepout
			(tracks not_allowed)
			(vias allowed)
			(pads allowed)
			(copperpour not_allowed)
			(footprints allowed)
		)
		(placement
			(enabled no)
			(sheetname "")
		)
		(fill yes
			(thermal_gap 0.5)
			(thermal_bridge_width 0.5)
			(island_removal_mode 0)
		)
		(polygon
			(pts
				(arc
					(start 221.488 -92.964)
					(mid 219.71 -92.964)
					(end 221.488 -92.964)
				)
			)
		)
	)
	(zone
		(layers "In4.Cu" "In5.Cu")
		(hatch none 0.5)
		(connect_pads
			(clearance 0)
		)
		(min_thickness 0.25)
		(keepout
			(tracks not_allowed)
			(vias allowed)
			(pads allowed)
			(copperpour not_allowed)
			(footprints allowed)
		)
		(placement
			(enabled no)
			(sheetname "")
		)
		(fill yes
			(thermal_gap 0.5)
			(thermal_bridge_width 0.5)
			(island_removal_mode 0)
		)
		(polygon
			(pts
				(arc
					(start 54.145434 -67.869816)
					(mid 51.554634 -67.869816)
					(end 54.145434 -67.869816)
				)
			)
		)
	)
	(zone
		(layers "In4.Cu" "In5.Cu")
		(hatch none 0.5)
		(connect_pads
			(clearance 0)
		)
		(min_thickness 0.25)
		(keepout
			(tracks not_allowed)
			(vias allowed)
			(pads allowed)
			(copperpour not_allowed)
			(footprints allowed)
		)
		(placement
			(enabled no)
			(sheetname "")
		)
		(fill yes
			(thermal_gap 0.5)
			(thermal_bridge_width 0.5)
			(island_removal_mode 0)
		)
		(polygon
			(pts
				(arc
					(start 283.0322 -43.18)
					(mid 281.2542 -43.18)
					(end 283.0322 -43.18)
				)
			)
		)
	)
	(zone
		(layers "In4.Cu" "In5.Cu")
		(hatch none 0.5)
		(connect_pads
			(clearance 0)
		)
		(min_thickness 0.25)
		(keepout
			(tracks not_allowed)
			(vias allowed)
			(pads allowed)
			(copperpour not_allowed)
			(footprints allowed)
		)
		(placement
			(enabled no)
			(sheetname "")
		)
		(fill yes
			(thermal_gap 0.5)
			(thermal_bridge_width 0.5)
			(island_removal_mode 0)
		)
		(polygon
			(pts
				(arc
					(start 233.61904 -85.617558)
					(mid 231.84104 -85.617558)
					(end 233.61904 -85.617558)
				)
			)
		)
	)
	(zone
		(layers "In4.Cu" "In5.Cu")
		(hatch none 0.5)
		(connect_pads
			(clearance 0)
		)
		(min_thickness 0.25)
		(keepout
			(tracks not_allowed)
			(vias allowed)
			(pads allowed)
			(copperpour not_allowed)
			(footprints allowed)
		)
		(placement
			(enabled no)
			(sheetname "")
		)
		(fill yes
			(thermal_gap 0.5)
			(thermal_bridge_width 0.5)
			(island_removal_mode 0)
		)
		(polygon
			(pts
				(arc
					(start 233.426 -72.00265)
					(mid 231.648 -72.00265)
					(end 233.426 -72.00265)
				)
			)
		)
	)
	(zone
		(layers "In4.Cu" "In5.Cu")
		(hatch none 0.5)
		(connect_pads
			(clearance 0)
		)
		(min_thickness 0.25)
		(keepout
			(tracks not_allowed)
			(vias allowed)
			(pads allowed)
			(copperpour not_allowed)
			(footprints allowed)
		)
		(placement
			(enabled no)
			(sheetname "")
		)
		(fill yes
			(thermal_gap 0.5)
			(thermal_bridge_width 0.5)
			(island_removal_mode 0)
		)
		(polygon
			(pts
				(arc
					(start 76.327 -50.419)
					(mid 74.549 -50.419)
					(end 76.327 -50.419)
				)
			)
		)
	)
	(zone
		(layers "In4.Cu" "In5.Cu")
		(hatch none 0.5)
		(connect_pads
			(clearance 0)
		)
		(min_thickness 0.25)
		(keepout
			(tracks not_allowed)
			(vias allowed)
			(pads allowed)
			(copperpour not_allowed)
			(footprints allowed)
		)
		(placement
			(enabled no)
			(sheetname "")
		)
		(fill yes
			(thermal_gap 0.5)
			(thermal_bridge_width 0.5)
			(island_removal_mode 0)
		)
		(polygon
			(pts
				(arc
					(start 52.145438 -67.869816)
					(mid 49.554638 -67.869816)
					(end 52.145438 -67.869816)
				)
			)
		)
	)
	(zone
		(layers "In4.Cu" "In5.Cu")
		(hatch none 0.5)
		(connect_pads
			(clearance 0)
		)
		(min_thickness 0.25)
		(keepout
			(tracks not_allowed)
			(vias allowed)
			(pads allowed)
			(copperpour not_allowed)
			(footprints allowed)
		)
		(placement
			(enabled no)
			(sheetname "")
		)
		(fill yes
			(thermal_gap 0.5)
			(thermal_bridge_width 0.5)
			(island_removal_mode 0)
		)
		(polygon
			(pts
				(arc
					(start 100.661216 -136.906)
					(mid 97.816416 -136.906)
					(end 100.661216 -136.906)
				)
			)
		)
	)
	(zone
		(layers "In4.Cu" "In5.Cu")
		(hatch none 0.5)
		(connect_pads
			(clearance 0)
		)
		(min_thickness 0.25)
		(keepout
			(tracks not_allowed)
			(vias allowed)
			(pads allowed)
			(copperpour not_allowed)
			(footprints allowed)
		)
		(placement
			(enabled no)
			(sheetname "")
		)
		(fill yes
			(thermal_gap 0.5)
			(thermal_bridge_width 0.5)
			(island_removal_mode 0)
		)
		(polygon
			(pts
				(arc
					(start 179.700174 -131.572)
					(mid 177.922174 -131.572)
					(end 179.700174 -131.572)
				)
			)
		)
	)
	(zone
		(layers "In4.Cu" "In5.Cu")
		(hatch none 0.5)
		(connect_pads
			(clearance 0)
		)
		(min_thickness 0.25)
		(keepout
			(tracks not_allowed)
			(vias allowed)
			(pads allowed)
			(copperpour not_allowed)
			(footprints allowed)
		)
		(placement
			(enabled no)
			(sheetname "")
		)
		(fill yes
			(thermal_gap 0.5)
			(thermal_bridge_width 0.5)
			(island_removal_mode 0)
		)
		(polygon
			(pts
				(arc
					(start 85.662008 -38.01999)
					(mid 82.868008 -38.01999)
					(end 85.662008 -38.01999)
				)
			)
		)
	)
	(zone
		(layers "In4.Cu" "In5.Cu")
		(hatch none 0.5)
		(connect_pads
			(clearance 0)
		)
		(min_thickness 0.25)
		(keepout
			(tracks not_allowed)
			(vias allowed)
			(pads allowed)
			(copperpour not_allowed)
			(footprints allowed)
		)
		(placement
			(enabled no)
			(sheetname "")
		)
		(fill yes
			(thermal_gap 0.5)
			(thermal_bridge_width 0.5)
			(island_removal_mode 0)
		)
		(polygon
			(pts
				(arc
					(start 50.61204 -61.4934)
					(mid 48.83404 -61.4934)
					(end 50.61204 -61.4934)
				)
			)
		)
	)
	(zone
		(layers "In4.Cu" "In5.Cu")
		(hatch none 0.5)
		(connect_pads
			(clearance 0)
		)
		(min_thickness 0.25)
		(keepout
			(tracks not_allowed)
			(vias allowed)
			(pads allowed)
			(copperpour not_allowed)
			(footprints allowed)
		)
		(placement
			(enabled no)
			(sheetname "")
		)
		(fill yes
			(thermal_gap 0.5)
			(thermal_bridge_width 0.5)
			(island_removal_mode 0)
		)
		(polygon
			(pts
				(arc
					(start 110.236 -55.96001)
					(mid 107.442 -55.96001)
					(end 110.236 -55.96001)
				)
			)
		)
	)
	(zone
		(layers "In4.Cu" "In5.Cu")
		(hatch none 0.5)
		(connect_pads
			(clearance 0)
		)
		(min_thickness 0.25)
		(keepout
			(tracks not_allowed)
			(vias allowed)
			(pads allowed)
			(copperpour not_allowed)
			(footprints allowed)
		)
		(placement
			(enabled no)
			(sheetname "")
		)
		(fill yes
			(thermal_gap 0.5)
			(thermal_bridge_width 0.5)
			(island_removal_mode 0)
		)
		(polygon
			(pts
				(arc
					(start 192.853564 -136.906)
					(mid 190.008764 -136.906)
					(end 192.853564 -136.906)
				)
			)
		)
	)
	(zone
		(layers "In4.Cu" "In5.Cu")
		(hatch none 0.5)
		(connect_pads
			(clearance 0)
		)
		(min_thickness 0.25)
		(keepout
			(tracks not_allowed)
			(vias allowed)
			(pads allowed)
			(copperpour not_allowed)
			(footprints allowed)
		)
		(placement
			(enabled no)
			(sheetname "")
		)
		(fill yes
			(thermal_gap 0.5)
			(thermal_bridge_width 0.5)
			(island_removal_mode 0)
		)
		(polygon
			(pts
				(arc
					(start 92.71 -49.784)
					(mid 90.932 -49.784)
					(end 92.71 -49.784)
				)
			)
		)
	)
	(zone
		(layers "In4.Cu" "In5.Cu")
		(hatch none 0.5)
		(connect_pads
			(clearance 0)
		)
		(min_thickness 0.25)
		(keepout
			(tracks not_allowed)
			(vias allowed)
			(pads allowed)
			(copperpour not_allowed)
			(footprints allowed)
		)
		(placement
			(enabled no)
			(sheetname "")
		)
		(fill yes
			(thermal_gap 0.5)
			(thermal_bridge_width 0.5)
			(island_removal_mode 0)
		)
		(polygon
			(pts
				(arc
					(start 92.075 -55.96001)
					(mid 89.281 -55.96001)
					(end 92.075 -55.96001)
				)
			)
		)
	)
	(zone
		(layers "In4.Cu" "In5.Cu")
		(hatch none 0.5)
		(connect_pads
			(clearance 0)
		)
		(min_thickness 0.25)
		(keepout
			(tracks not_allowed)
			(vias allowed)
			(pads allowed)
			(copperpour not_allowed)
			(footprints allowed)
		)
		(placement
			(enabled no)
			(sheetname "")
		)
		(fill yes
			(thermal_gap 0.5)
			(thermal_bridge_width 0.5)
			(island_removal_mode 0)
		)
		(polygon
			(pts
				(arc
					(start 110.621826 -114.81435)
					(mid 108.843826 -114.81435)
					(end 110.621826 -114.81435)
				)
			)
		)
	)
	(zone
		(layers "In4.Cu" "In5.Cu")
		(hatch none 0.5)
		(connect_pads
			(clearance 0)
		)
		(min_thickness 0.25)
		(keepout
			(tracks not_allowed)
			(vias allowed)
			(pads allowed)
			(copperpour not_allowed)
			(footprints allowed)
		)
		(placement
			(enabled no)
			(sheetname "")
		)
		(fill yes
			(thermal_gap 0.5)
			(thermal_bridge_width 0.5)
			(island_removal_mode 0)
		)
		(polygon
			(pts
				(arc
					(start 171.046394 -121.209816)
					(mid 167.414194 -121.209816)
					(end 171.046394 -121.209816)
				)
			)
		)
	)
	(zone
		(layers "In4.Cu" "In5.Cu")
		(hatch none 0.5)
		(connect_pads
			(clearance 0)
		)
		(min_thickness 0.25)
		(keepout
			(tracks not_allowed)
			(vias allowed)
			(pads allowed)
			(copperpour not_allowed)
			(footprints allowed)
		)
		(placement
			(enabled no)
			(sheetname "")
		)
		(fill yes
			(thermal_gap 0.5)
			(thermal_bridge_width 0.5)
			(island_removal_mode 0)
		)
		(polygon
			(pts
				(arc
					(start 88.202008 -35.47999)
					(mid 85.408008 -35.47999)
					(end 88.202008 -35.47999)
				)
			)
		)
	)
	(zone
		(layers "In4.Cu" "In5.Cu")
		(hatch none 0.5)
		(connect_pads
			(clearance 0)
		)
		(min_thickness 0.25)
		(keepout
			(tracks not_allowed)
			(vias allowed)
			(pads allowed)
			(copperpour not_allowed)
			(footprints allowed)
		)
		(placement
			(enabled no)
			(sheetname "")
		)
		(fill yes
			(thermal_gap 0.5)
			(thermal_bridge_width 0.5)
			(island_removal_mode 0)
		)
		(polygon
			(pts
				(arc
					(start 276.479 -46.88205)
					(mid 274.701 -46.88205)
					(end 276.479 -46.88205)
				)
			)
		)
	)
	(zone
		(layers "In4.Cu" "In5.Cu")
		(hatch none 0.5)
		(connect_pads
			(clearance 0)
		)
		(min_thickness 0.25)
		(keepout
			(tracks not_allowed)
			(vias allowed)
			(pads allowed)
			(copperpour not_allowed)
			(footprints allowed)
		)
		(placement
			(enabled no)
			(sheetname "")
		)
		(fill yes
			(thermal_gap 0.5)
			(thermal_bridge_width 0.5)
			(island_removal_mode 0)
		)
		(polygon
			(pts
				(arc
					(start 71.129906 -126.492)
					(mid 69.351906 -126.492)
					(end 71.129906 -126.492)
				)
			)
		)
	)
	(zone
		(layers "In4.Cu" "In5.Cu")
		(hatch none 0.5)
		(connect_pads
			(clearance 0)
		)
		(min_thickness 0.25)
		(keepout
			(tracks not_allowed)
			(vias allowed)
			(pads allowed)
			(copperpour not_allowed)
			(footprints allowed)
		)
		(placement
			(enabled no)
			(sheetname "")
		)
		(fill yes
			(thermal_gap 0.5)
			(thermal_bridge_width 0.5)
			(island_removal_mode 0)
		)
		(polygon
			(pts
				(arc
					(start 239.649 -74.542904)
					(mid 237.871 -74.542904)
					(end 239.649 -74.542904)
				)
			)
		)
	)
	(zone
		(layers "In4.Cu" "In5.Cu")
		(hatch none 0.5)
		(connect_pads
			(clearance 0)
		)
		(min_thickness 0.25)
		(keepout
			(tracks not_allowed)
			(vias allowed)
			(pads allowed)
			(copperpour not_allowed)
			(footprints allowed)
		)
		(placement
			(enabled no)
			(sheetname "")
		)
		(fill yes
			(thermal_gap 0.5)
			(thermal_bridge_width 0.5)
			(island_removal_mode 0)
		)
		(polygon
			(pts
				(arc
					(start 276.61235 -41.656)
					(mid 274.83435 -41.656)
					(end 276.61235 -41.656)
				)
			)
		)
	)
	(zone
		(layers "In4.Cu" "In5.Cu")
		(hatch none 0.5)
		(connect_pads
			(clearance 0)
		)
		(min_thickness 0.25)
		(keepout
			(tracks not_allowed)
			(vias allowed)
			(pads allowed)
			(copperpour not_allowed)
			(footprints allowed)
		)
		(placement
			(enabled no)
			(sheetname "")
		)
		(fill yes
			(thermal_gap 0.5)
			(thermal_bridge_width 0.5)
			(island_removal_mode 0)
		)
		(polygon
			(pts
				(arc
					(start 228.092 -72.00265)
					(mid 226.314 -72.00265)
					(end 228.092 -72.00265)
				)
			)
		)
	)
	(zone
		(layers "In4.Cu" "In5.Cu")
		(hatch none 0.5)
		(connect_pads
			(clearance 0)
		)
		(min_thickness 0.25)
		(keepout
			(tracks not_allowed)
			(vias allowed)
			(pads allowed)
			(copperpour not_allowed)
			(footprints allowed)
		)
		(placement
			(enabled no)
			(sheetname "")
		)
		(fill yes
			(thermal_gap 0.5)
			(thermal_bridge_width 0.5)
			(island_removal_mode 0)
		)
		(polygon
			(pts
				(arc
					(start 180.661564 -136.906)
					(mid 177.816764 -136.906)
					(end 180.661564 -136.906)
				)
			)
		)
	)
	(zone
		(layers "In4.Cu" "In5.Cu")
		(hatch none 0.5)
		(connect_pads
			(clearance 0)
		)
		(min_thickness 0.25)
		(keepout
			(tracks not_allowed)
			(vias allowed)
			(pads allowed)
			(copperpour not_allowed)
			(footprints allowed)
		)
		(placement
			(enabled no)
			(sheetname "")
		)
		(fill yes
			(thermal_gap 0.5)
			(thermal_bridge_width 0.5)
			(island_removal_mode 0)
		)
		(polygon
			(pts
				(arc
					(start 237.920784 -89.75344)
					(mid 236.142784 -89.75344)
					(end 237.920784 -89.75344)
				)
			)
		)
	)
	(zone
		(layers "In4.Cu" "In5.Cu")
		(hatch none 0.5)
		(connect_pads
			(clearance 0)
		)
		(min_thickness 0.25)
		(keepout
			(tracks not_allowed)
			(vias allowed)
			(pads allowed)
			(copperpour not_allowed)
			(footprints allowed)
		)
		(placement
			(enabled no)
			(sheetname "")
		)
		(fill yes
			(thermal_gap 0.5)
			(thermal_bridge_width 0.5)
			(island_removal_mode 0)
		)
		(polygon
			(pts
				(arc
					(start 231.775 -72.00265)
					(mid 229.997 -72.00265)
					(end 231.775 -72.00265)
				)
			)
		)
	)
	(zone
		(layers "In4.Cu" "In5.Cu")
		(hatch none 0.5)
		(connect_pads
			(clearance 0)
		)
		(min_thickness 0.25)
		(keepout
			(tracks not_allowed)
			(vias allowed)
			(pads allowed)
			(copperpour not_allowed)
			(footprints allowed)
		)
		(placement
			(enabled no)
			(sheetname "")
		)
		(fill yes
			(thermal_gap 0.5)
			(thermal_bridge_width 0.5)
			(island_removal_mode 0)
		)
		(polygon
			(pts
				(arc
					(start 79.312008 -32.93999)
					(mid 76.518008 -32.93999)
					(end 79.312008 -32.93999)
				)
			)
		)
	)
	(zone
		(layers "In4.Cu" "In5.Cu")
		(hatch none 0.5)
		(connect_pads
			(clearance 0)
		)
		(min_thickness 0.25)
		(keepout
			(tracks not_allowed)
			(vias allowed)
			(pads allowed)
			(copperpour not_allowed)
			(footprints allowed)
		)
		(placement
			(enabled no)
			(sheetname "")
		)
		(fill yes
			(thermal_gap 0.5)
			(thermal_bridge_width 0.5)
			(island_removal_mode 0)
		)
		(polygon
			(pts
				(arc
					(start 210.693 -66.17335)
					(mid 208.915 -66.17335)
					(end 210.693 -66.17335)
				)
			)
		)
	)
	(zone
		(layers "In4.Cu" "In5.Cu")
		(hatch none 0.5)
		(connect_pads
			(clearance 0)
		)
		(min_thickness 0.25)
		(keepout
			(tracks not_allowed)
			(vias allowed)
			(pads allowed)
			(copperpour not_allowed)
			(footprints allowed)
		)
		(placement
			(enabled no)
			(sheetname "")
		)
		(fill yes
			(thermal_gap 0.5)
			(thermal_bridge_width 0.5)
			(island_removal_mode 0)
		)
		(polygon
			(pts
				(arc
					(start 235.077 -92.964)
					(mid 233.299 -92.964)
					(end 235.077 -92.964)
				)
			)
		)
	)
	(zone
		(layers "In4.Cu" "In5.Cu")
		(hatch none 0.5)
		(connect_pads
			(clearance 0)
		)
		(min_thickness 0.25)
		(keepout
			(tracks not_allowed)
			(vias allowed)
			(pads allowed)
			(copperpour not_allowed)
			(footprints allowed)
		)
		(placement
			(enabled no)
			(sheetname "")
		)
		(fill yes
			(thermal_gap 0.5)
			(thermal_bridge_width 0.5)
			(island_removal_mode 0)
		)
		(polygon
			(pts
				(arc
					(start 170.815 -49.657)
					(mid 169.037 -49.657)
					(end 170.815 -49.657)
				)
			)
		)
	)
	(zone
		(layers "In4.Cu" "In5.Cu")
		(hatch none 0.5)
		(connect_pads
			(clearance 0)
		)
		(min_thickness 0.25)
		(keepout
			(tracks not_allowed)
			(vias allowed)
			(pads allowed)
			(copperpour not_allowed)
			(footprints allowed)
		)
		(placement
			(enabled no)
			(sheetname "")
		)
		(fill yes
			(thermal_gap 0.5)
			(thermal_bridge_width 0.5)
			(island_removal_mode 0)
		)
		(polygon
			(pts
				(arc
					(start 46.745906 -126.492)
					(mid 44.967906 -126.492)
					(end 46.745906 -126.492)
				)
			)
		)
	)
	(zone
		(layers "In4.Cu" "In5.Cu")
		(hatch none 0.5)
		(connect_pads
			(clearance 0)
		)
		(min_thickness 0.25)
		(keepout
			(tracks not_allowed)
			(vias allowed)
			(pads allowed)
			(copperpour not_allowed)
			(footprints allowed)
		)
		(placement
			(enabled no)
			(sheetname "")
		)
		(fill yes
			(thermal_gap 0.5)
			(thermal_bridge_width 0.5)
			(island_removal_mode 0)
		)
		(polygon
			(pts
				(arc
					(start 49.85004 -62.2554)
					(mid 48.07204 -62.2554)
					(end 49.85004 -62.2554)
				)
			)
		)
	)
	(zone
		(layers "In4.Cu" "In5.Cu")
		(hatch none 0.5)
		(connect_pads
			(clearance 0)
		)
		(min_thickness 0.25)
		(keepout
			(tracks not_allowed)
			(vias allowed)
			(pads allowed)
			(copperpour not_allowed)
			(footprints allowed)
		)
		(placement
			(enabled no)
			(sheetname "")
		)
		(fill yes
			(thermal_gap 0.5)
			(thermal_bridge_width 0.5)
			(island_removal_mode 0)
		)
		(polygon
			(pts
				(arc
					(start 71.891906 -131.572)
					(mid 70.113906 -131.572)
					(end 71.891906 -131.572)
				)
			)
		)
	)
	(zone
		(layers "In4.Cu" "In5.Cu")
		(hatch none 0.5)
		(connect_pads
			(clearance 0)
		)
		(min_thickness 0.25)
		(keepout
			(tracks not_allowed)
			(vias allowed)
			(pads allowed)
			(copperpour not_allowed)
			(footprints allowed)
		)
		(placement
			(enabled no)
			(sheetname "")
		)
		(fill yes
			(thermal_gap 0.5)
			(thermal_bridge_width 0.5)
			(island_removal_mode 0)
		)
		(polygon
			(pts
				(arc
					(start 224.409 -79.46517)
					(mid 222.631 -79.46517)
					(end 224.409 -79.46517)
				)
			)
		)
	)
	(zone
		(layers "In4.Cu" "In5.Cu")
		(hatch none 0.5)
		(connect_pads
			(clearance 0)
		)
		(min_thickness 0.25)
		(keepout
			(tracks not_allowed)
			(vias allowed)
			(pads allowed)
			(copperpour not_allowed)
			(footprints allowed)
		)
		(placement
			(enabled no)
			(sheetname "")
		)
		(fill yes
			(thermal_gap 0.5)
			(thermal_bridge_width 0.5)
			(island_removal_mode 0)
		)
		(polygon
			(pts
				(arc
					(start 77.933296 -39.27221)
					(mid 75.139296 -39.27221)
					(end 77.933296 -39.27221)
				)
			)
		)
	)
	(zone
		(layers "In4.Cu" "In5.Cu")
		(hatch none 0.5)
		(connect_pads
			(clearance 0)
		)
		(min_thickness 0.25)
		(keepout
			(tracks not_allowed)
			(vias allowed)
			(pads allowed)
			(copperpour not_allowed)
			(footprints allowed)
		)
		(placement
			(enabled no)
			(sheetname "")
		)
		(fill yes
			(thermal_gap 0.5)
			(thermal_bridge_width 0.5)
			(island_removal_mode 0)
		)
		(polygon
			(pts
				(arc
					(start 141.097 -62.738)
					(mid 139.319 -62.738)
					(end 141.097 -62.738)
				)
			)
		)
	)
	(zone
		(layers "In4.Cu" "In5.Cu")
		(hatch none 0.5)
		(connect_pads
			(clearance 0)
		)
		(min_thickness 0.25)
		(keepout
			(tracks not_allowed)
			(vias allowed)
			(pads allowed)
			(copperpour not_allowed)
			(footprints allowed)
		)
		(placement
			(enabled no)
			(sheetname "")
		)
		(fill yes
			(thermal_gap 0.5)
			(thermal_bridge_width 0.5)
			(island_removal_mode 0)
		)
		(polygon
			(pts
				(arc
					(start 165.354 -51.562)
					(mid 163.576 -51.562)
					(end 165.354 -51.562)
				)
			)
		)
	)
	(zone
		(layers "In4.Cu" "In5.Cu")
		(hatch none 0.5)
		(connect_pads
			(clearance 0)
		)
		(min_thickness 0.25)
		(keepout
			(tracks not_allowed)
			(vias allowed)
			(pads allowed)
			(copperpour not_allowed)
			(footprints allowed)
		)
		(placement
			(enabled no)
			(sheetname "")
		)
		(fill yes
			(thermal_gap 0.5)
			(thermal_bridge_width 0.5)
			(island_removal_mode 0)
		)
		(polygon
			(pts
				(arc
					(start 71.891906 -126.492)
					(mid 70.113906 -126.492)
					(end 71.891906 -126.492)
				)
			)
		)
	)
	(zone
		(layers "In4.Cu" "In5.Cu")
		(hatch none 0.5)
		(connect_pads
			(clearance 0)
		)
		(min_thickness 0.25)
		(keepout
			(tracks not_allowed)
			(vias allowed)
			(pads allowed)
			(copperpour not_allowed)
			(footprints allowed)
		)
		(placement
			(enabled no)
			(sheetname "")
		)
		(fill yes
			(thermal_gap 0.5)
			(thermal_bridge_width 0.5)
			(island_removal_mode 0)
		)
		(polygon
			(pts
				(arc
					(start 286.91205 -34.537142)
					(mid 285.13405 -34.537142)
					(end 286.91205 -34.537142)
				)
			)
		)
	)
	(zone
		(layers "In4.Cu" "In5.Cu")
		(hatch none 0.5)
		(connect_pads
			(clearance 0)
		)
		(min_thickness 0.25)
		(keepout
			(tracks not_allowed)
			(vias allowed)
			(pads allowed)
			(copperpour not_allowed)
			(footprints allowed)
		)
		(placement
			(enabled no)
			(sheetname "")
		)
		(fill yes
			(thermal_gap 0.5)
			(thermal_bridge_width 0.5)
			(island_removal_mode 0)
		)
		(polygon
			(pts
				(arc
					(start 207.63865 -91.948)
					(mid 205.86065 -91.948)
					(end 207.63865 -91.948)
				)
			)
		)
	)
	(zone
		(layers "In4.Cu" "In5.Cu")
		(hatch none 0.5)
		(connect_pads
			(clearance 0)
		)
		(min_thickness 0.25)
		(keepout
			(tracks not_allowed)
			(vias allowed)
			(pads allowed)
			(copperpour not_allowed)
			(footprints allowed)
		)
		(placement
			(enabled no)
			(sheetname "")
		)
		(fill yes
			(thermal_gap 0.5)
			(thermal_bridge_width 0.5)
			(island_removal_mode 0)
		)
		(polygon
			(pts
				(arc
					(start 76.772008 -38.01999)
					(mid 73.978008 -38.01999)
					(end 76.772008 -38.01999)
				)
			)
		)
	)
	(zone
		(layers "In4.Cu" "In5.Cu")
		(hatch none 0.5)
		(connect_pads
			(clearance 0)
		)
		(min_thickness 0.25)
		(keepout
			(tracks not_allowed)
			(vias allowed)
			(pads allowed)
			(copperpour not_allowed)
			(footprints allowed)
		)
		(placement
			(enabled no)
			(sheetname "")
		)
		(fill yes
			(thermal_gap 0.5)
			(thermal_bridge_width 0.5)
			(island_removal_mode 0)
		)
		(polygon
			(pts
				(arc
					(start 126.746 -126.492)
					(mid 124.968 -126.492)
					(end 126.746 -126.492)
				)
			)
		)
	)
	(zone
		(layers "In4.Cu" "In5.Cu")
		(hatch none 0.5)
		(connect_pads
			(clearance 0)
		)
		(min_thickness 0.25)
		(keepout
			(tracks not_allowed)
			(vias allowed)
			(pads allowed)
			(copperpour not_allowed)
			(footprints allowed)
		)
		(placement
			(enabled no)
			(sheetname "")
		)
		(fill yes
			(thermal_gap 0.5)
			(thermal_bridge_width 0.5)
			(island_removal_mode 0)
		)
		(polygon
			(pts
				(arc
					(start 239.903 -92.964)
					(mid 238.125 -92.964)
					(end 239.903 -92.964)
				)
			)
		)
	)
	(zone
		(layers "In4.Cu" "In5.Cu")
		(hatch none 0.5)
		(connect_pads
			(clearance 0)
		)
		(min_thickness 0.25)
		(keepout
			(tracks not_allowed)
			(vias allowed)
			(pads allowed)
			(copperpour not_allowed)
			(footprints allowed)
		)
		(placement
			(enabled no)
			(sheetname "")
		)
		(fill yes
			(thermal_gap 0.5)
			(thermal_bridge_width 0.5)
			(island_removal_mode 0)
		)
		(polygon
			(pts
				(arc
					(start 181.73446 -51.562)
					(mid 179.95646 -51.562)
					(end 181.73446 -51.562)
				)
			)
		)
	)
	(zone
		(layers "In4.Cu" "In5.Cu")
		(hatch none 0.5)
		(connect_pads
			(clearance 0)
		)
		(min_thickness 0.25)
		(keepout
			(tracks not_allowed)
			(vias allowed)
			(pads allowed)
			(copperpour not_allowed)
			(footprints allowed)
		)
		(placement
			(enabled no)
			(sheetname "")
		)
		(fill yes
			(thermal_gap 0.5)
			(thermal_bridge_width 0.5)
			(island_removal_mode 0)
		)
		(polygon
			(pts
				(arc
					(start 239.649 -72.0852)
					(mid 237.871 -72.0852)
					(end 239.649 -72.0852)
				)
			)
		)
	)
	(zone
		(layers "In4.Cu" "In5.Cu")
		(hatch none 0.5)
		(connect_pads
			(clearance 0)
		)
		(min_thickness 0.25)
		(keepout
			(tracks not_allowed)
			(vias allowed)
			(pads allowed)
			(copperpour not_allowed)
			(footprints allowed)
		)
		(placement
			(enabled no)
			(sheetname "")
		)
		(fill yes
			(thermal_gap 0.5)
			(thermal_bridge_width 0.5)
			(island_removal_mode 0)
		)
		(polygon
			(pts
				(arc
					(start 279.654 -51.7398)
					(mid 277.876 -51.7398)
					(end 279.654 -51.7398)
				)
			)
		)
	)
	(zone
		(layers "In4.Cu" "In5.Cu")
		(hatch none 0.5)
		(connect_pads
			(clearance 0)
		)
		(min_thickness 0.25)
		(keepout
			(tracks not_allowed)
			(vias allowed)
			(pads allowed)
			(copperpour not_allowed)
			(footprints allowed)
		)
		(placement
			(enabled no)
			(sheetname "")
		)
		(fill yes
			(thermal_gap 0.5)
			(thermal_bridge_width 0.5)
			(island_removal_mode 0)
		)
		(polygon
			(pts
				(arc
					(start 170.815 -50.292)
					(mid 169.037 -50.292)
					(end 170.815 -50.292)
				)
			)
		)
	)
	(zone
		(layers "In4.Cu" "In5.Cu")
		(hatch none 0.5)
		(connect_pads
			(clearance 0)
		)
		(min_thickness 0.25)
		(keepout
			(tracks not_allowed)
			(vias allowed)
			(pads allowed)
			(copperpour not_allowed)
			(footprints allowed)
		)
		(placement
			(enabled no)
			(sheetname "")
		)
		(fill yes
			(thermal_gap 0.5)
			(thermal_bridge_width 0.5)
			(island_removal_mode 0)
		)
		(polygon
			(pts
				(arc
					(start 170.815 -52.197)
					(mid 169.037 -52.197)
					(end 170.815 -52.197)
				)
			)
		)
	)
	(zone
		(layers "In4.Cu" "In5.Cu")
		(hatch none 0.5)
		(connect_pads
			(clearance 0)
		)
		(min_thickness 0.25)
		(keepout
			(tracks not_allowed)
			(vias allowed)
			(pads allowed)
			(copperpour not_allowed)
			(footprints allowed)
		)
		(placement
			(enabled no)
			(sheetname "")
		)
		(fill yes
			(thermal_gap 0.5)
			(thermal_bridge_width 0.5)
			(island_removal_mode 0)
		)
		(polygon
			(pts
				(arc
					(start 87.249 -50.419)
					(mid 85.471 -50.419)
					(end 87.249 -50.419)
				)
			)
		)
	)
	(zone
		(layers "In4.Cu" "In5.Cu")
		(hatch none 0.5)
		(connect_pads
			(clearance 0)
		)
		(min_thickness 0.25)
		(keepout
			(tracks not_allowed)
			(vias allowed)
			(pads allowed)
			(copperpour not_allowed)
			(footprints allowed)
		)
		(placement
			(enabled no)
			(sheetname "")
		)
		(fill yes
			(thermal_gap 0.5)
			(thermal_bridge_width 0.5)
			(island_removal_mode 0)
		)
		(polygon
			(pts
				(arc
					(start 227.838 -92.964)
					(mid 226.06 -92.964)
					(end 227.838 -92.964)
				)
			)
		)
	)
	(zone
		(layers "In4.Cu" "In5.Cu")
		(hatch none 0.5)
		(connect_pads
			(clearance 0)
		)
		(min_thickness 0.25)
		(keepout
			(tracks not_allowed)
			(vias allowed)
			(pads allowed)
			(copperpour not_allowed)
			(footprints allowed)
		)
		(placement
			(enabled no)
			(sheetname "")
		)
		(fill yes
			(thermal_gap 0.5)
			(thermal_bridge_width 0.5)
			(island_removal_mode 0)
		)
		(polygon
			(pts
				(arc
					(start 210.688174 -55.96001)
					(mid 207.894174 -55.96001)
					(end 210.688174 -55.96001)
				)
			)
		)
	)
	(zone
		(layers "In4.Cu" "In5.Cu")
		(hatch none 0.5)
		(connect_pads
			(clearance 0)
		)
		(min_thickness 0.25)
		(keepout
			(tracks not_allowed)
			(vias allowed)
			(pads allowed)
			(copperpour not_allowed)
			(footprints allowed)
		)
		(placement
			(enabled no)
			(sheetname "")
		)
		(fill yes
			(thermal_gap 0.5)
			(thermal_bridge_width 0.5)
			(island_removal_mode 0)
		)
		(polygon
			(pts
				(arc
					(start 276.61235 -42.545)
					(mid 274.83435 -42.545)
					(end 276.61235 -42.545)
				)
			)
		)
	)
	(zone
		(layers "In4.Cu" "In5.Cu")
		(hatch none 0.5)
		(connect_pads
			(clearance 0)
		)
		(min_thickness 0.25)
		(keepout
			(tracks not_allowed)
			(vias allowed)
			(pads allowed)
			(copperpour not_allowed)
			(footprints allowed)
		)
		(placement
			(enabled no)
			(sheetname "")
		)
		(fill yes
			(thermal_gap 0.5)
			(thermal_bridge_width 0.5)
			(island_removal_mode 0)
		)
		(polygon
			(pts
				(arc
					(start 85.662008 -32.93999)
					(mid 82.868008 -32.93999)
					(end 85.662008 -32.93999)
				)
			)
		)
	)
	(zone
		(layers "In4.Cu" "In5.Cu")
		(hatch none 0.5)
		(connect_pads
			(clearance 0)
		)
		(min_thickness 0.25)
		(keepout
			(tracks not_allowed)
			(vias allowed)
			(pads allowed)
			(copperpour not_allowed)
			(footprints allowed)
		)
		(placement
			(enabled no)
			(sheetname "")
		)
		(fill yes
			(thermal_gap 0.5)
			(thermal_bridge_width 0.5)
			(island_removal_mode 0)
		)
		(polygon
			(pts
				(arc
					(start 223.901 -91.05265)
					(mid 222.123 -91.05265)
					(end 223.901 -91.05265)
				)
			)
		)
	)
	(zone
		(layers "In4.Cu" "In5.Cu")
		(hatch none 0.5)
		(connect_pads
			(clearance 0)
		)
		(min_thickness 0.25)
		(keepout
			(tracks not_allowed)
			(vias allowed)
			(pads allowed)
			(copperpour not_allowed)
			(footprints allowed)
		)
		(placement
			(enabled no)
			(sheetname "")
		)
		(fill yes
			(thermal_gap 0.5)
			(thermal_bridge_width 0.5)
			(island_removal_mode 0)
		)
		(polygon
			(pts
				(arc
					(start 228.6 -92.964)
					(mid 226.822 -92.964)
					(end 228.6 -92.964)
				)
			)
		)
	)
	(zone
		(layers "In4.Cu" "In5.Cu")
		(hatch none 0.5)
		(connect_pads
			(clearance 0)
		)
		(min_thickness 0.25)
		(keepout
			(tracks not_allowed)
			(vias allowed)
			(pads allowed)
			(copperpour not_allowed)
			(footprints allowed)
		)
		(placement
			(enabled no)
			(sheetname "")
		)
		(fill yes
			(thermal_gap 0.5)
			(thermal_bridge_width 0.5)
			(island_removal_mode 0)
		)
		(polygon
			(pts
				(arc
					(start 58.666126 -121.209816)
					(mid 55.033926 -121.209816)
					(end 58.666126 -121.209816)
				)
			)
		)
	)
	(zone
		(layers "In4.Cu" "In5.Cu")
		(hatch none 0.5)
		(connect_pads
			(clearance 0)
		)
		(min_thickness 0.25)
		(keepout
			(tracks not_allowed)
			(vias allowed)
			(pads allowed)
			(copperpour not_allowed)
			(footprints allowed)
		)
		(placement
			(enabled no)
			(sheetname "")
		)
		(fill yes
			(thermal_gap 0.5)
			(thermal_bridge_width 0.5)
			(island_removal_mode 0)
		)
		(polygon
			(pts
				(arc
					(start 178.938174 -131.572)
					(mid 177.160174 -131.572)
					(end 178.938174 -131.572)
				)
			)
		)
	)
	(zone
		(layers "In4.Cu" "In5.Cu")
		(hatch none 0.5)
		(connect_pads
			(clearance 0)
		)
		(min_thickness 0.25)
		(keepout
			(tracks not_allowed)
			(vias allowed)
			(pads allowed)
			(copperpour not_allowed)
			(footprints allowed)
		)
		(placement
			(enabled no)
			(sheetname "")
		)
		(fill yes
			(thermal_gap 0.5)
			(thermal_bridge_width 0.5)
			(island_removal_mode 0)
		)
		(polygon
			(pts
				(arc
					(start 282.321 -43.688)
					(mid 280.543 -43.688)
					(end 282.321 -43.688)
				)
			)
		)
	)
	(zone
		(layers "In4.Cu" "In5.Cu")
		(hatch none 0.5)
		(connect_pads
			(clearance 0)
		)
		(min_thickness 0.25)
		(keepout
			(tracks not_allowed)
			(vias allowed)
			(pads allowed)
			(copperpour not_allowed)
			(footprints allowed)
		)
		(placement
			(enabled no)
			(sheetname "")
		)
		(fill yes
			(thermal_gap 0.5)
			(thermal_bridge_width 0.5)
			(island_removal_mode 0)
		)
		(polygon
			(pts
				(arc
					(start 92.71 -52.324)
					(mid 90.932 -52.324)
					(end 92.71 -52.324)
				)
			)
		)
	)
	(zone
		(layers "In4.Cu" "In5.Cu")
		(hatch none 0.5)
		(connect_pads
			(clearance 0)
		)
		(min_thickness 0.25)
		(keepout
			(tracks not_allowed)
			(vias allowed)
			(pads allowed)
			(copperpour not_allowed)
			(footprints allowed)
		)
		(placement
			(enabled no)
			(sheetname "")
		)
		(fill yes
			(thermal_gap 0.5)
			(thermal_bridge_width 0.5)
			(island_removal_mode 0)
		)
		(polygon
			(pts
				(arc
					(start 94.552008 -38.01999)
					(mid 91.758008 -38.01999)
					(end 94.552008 -38.01999)
				)
			)
		)
	)
	(zone
		(layers "In4.Cu" "In5.Cu")
		(hatch none 0.5)
		(connect_pads
			(clearance 0)
		)
		(min_thickness 0.25)
		(keepout
			(tracks not_allowed)
			(vias allowed)
			(pads allowed)
			(copperpour not_allowed)
			(footprints allowed)
		)
		(placement
			(enabled no)
			(sheetname "")
		)
		(fill yes
			(thermal_gap 0.5)
			(thermal_bridge_width 0.5)
			(island_removal_mode 0)
		)
		(polygon
			(pts
				(arc
					(start 181.73446 -49.657)
					(mid 179.95646 -49.657)
					(end 181.73446 -49.657)
				)
			)
		)
	)
	(zone
		(layers "In4.Cu" "In5.Cu")
		(hatch none 0.5)
		(connect_pads
			(clearance 0)
		)
		(min_thickness 0.25)
		(keepout
			(tracks not_allowed)
			(vias allowed)
			(pads allowed)
			(copperpour not_allowed)
			(footprints allowed)
		)
		(placement
			(enabled no)
			(sheetname "")
		)
		(fill yes
			(thermal_gap 0.5)
			(thermal_bridge_width 0.5)
			(island_removal_mode 0)
		)
		(polygon
			(pts
				(arc
					(start 222.885 -91.05265)
					(mid 221.107 -91.05265)
					(end 222.885 -91.05265)
				)
			)
		)
	)
	(zone
		(layers "In4.Cu" "In5.Cu")
		(hatch none 0.5)
		(connect_pads
			(clearance 0)
		)
		(min_thickness 0.25)
		(keepout
			(tracks not_allowed)
			(vias allowed)
			(pads allowed)
			(copperpour not_allowed)
			(footprints allowed)
		)
		(placement
			(enabled no)
			(sheetname "")
		)
		(fill yes
			(thermal_gap 0.5)
			(thermal_bridge_width 0.5)
			(island_removal_mode 0)
		)
		(polygon
			(pts
				(arc
					(start 69.469 -55.96001)
					(mid 66.675 -55.96001)
					(end 69.469 -55.96001)
				)
			)
		)
	)
	(zone
		(layers "In4.Cu" "In5.Cu")
		(hatch none 0.5)
		(connect_pads
			(clearance 0)
		)
		(min_thickness 0.25)
		(keepout
			(tracks not_allowed)
			(vias allowed)
			(pads allowed)
			(copperpour not_allowed)
			(footprints allowed)
		)
		(placement
			(enabled no)
			(sheetname "")
		)
		(fill yes
			(thermal_gap 0.5)
			(thermal_bridge_width 0.5)
			(island_removal_mode 0)
		)
		(polygon
			(pts
				(arc
					(start 282.529534 -42.3672)
					(mid 280.751534 -42.3672)
					(end 282.529534 -42.3672)
				)
			)
		)
	)
	(zone
		(layers "In4.Cu" "In5.Cu")
		(hatch none 0.5)
		(connect_pads
			(clearance 0)
		)
		(min_thickness 0.25)
		(keepout
			(tracks not_allowed)
			(vias allowed)
			(pads allowed)
			(copperpour not_allowed)
			(footprints allowed)
		)
		(placement
			(enabled no)
			(sheetname "")
		)
		(fill yes
			(thermal_gap 0.5)
			(thermal_bridge_width 0.5)
			(island_removal_mode 0)
		)
		(polygon
			(pts
				(arc
					(start 219.202 -92.964)
					(mid 217.424 -92.964)
					(end 219.202 -92.964)
				)
			)
		)
	)
	(zone
		(layers "In4.Cu" "In5.Cu")
		(hatch none 0.5)
		(connect_pads
			(clearance 0)
		)
		(min_thickness 0.25)
		(keepout
			(tracks not_allowed)
			(vias allowed)
			(pads allowed)
			(copperpour not_allowed)
			(footprints allowed)
		)
		(placement
			(enabled no)
			(sheetname "")
		)
		(fill yes
			(thermal_gap 0.5)
			(thermal_bridge_width 0.5)
			(island_removal_mode 0)
		)
		(polygon
			(pts
				(arc
					(start 94.552008 -40.55999)
					(mid 91.758008 -40.55999)
					(end 94.552008 -40.55999)
				)
			)
		)
	)
	(zone
		(layers "In4.Cu" "In5.Cu")
		(hatch none 0.5)
		(connect_pads
			(clearance 0)
		)
		(min_thickness 0.25)
		(keepout
			(tracks not_allowed)
			(vias allowed)
			(pads allowed)
			(copperpour not_allowed)
			(footprints allowed)
		)
		(placement
			(enabled no)
			(sheetname "")
		)
		(fill yes
			(thermal_gap 0.5)
			(thermal_bridge_width 0.5)
			(island_removal_mode 0)
		)
		(polygon
			(pts
				(arc
					(start 159.893 -50.292)
					(mid 158.115 -50.292)
					(end 159.893 -50.292)
				)
			)
		)
	)
	(zone
		(layers "In4.Cu" "In5.Cu")
		(hatch none 0.5)
		(connect_pads
			(clearance 0)
		)
		(min_thickness 0.25)
		(keepout
			(tracks not_allowed)
			(vias allowed)
			(pads allowed)
			(copperpour not_allowed)
			(footprints allowed)
		)
		(placement
			(enabled no)
			(sheetname "")
		)
		(fill yes
			(thermal_gap 0.5)
			(thermal_bridge_width 0.5)
			(island_removal_mode 0)
		)
		(polygon
			(pts
				(arc
					(start 177.739294 -113.036096)
					(mid 175.961294 -113.036096)
					(end 177.739294 -113.036096)
				)
			)
		)
	)
	(zone
		(layers "In4.Cu" "In5.Cu")
		(hatch none 0.5)
		(connect_pads
			(clearance 0)
		)
		(min_thickness 0.25)
		(keepout
			(tracks not_allowed)
			(vias allowed)
			(pads allowed)
			(copperpour not_allowed)
			(footprints allowed)
		)
		(placement
			(enabled no)
			(sheetname "")
		)
		(fill yes
			(thermal_gap 0.5)
			(thermal_bridge_width 0.5)
			(island_removal_mode 0)
		)
		(polygon
			(pts
				(arc
					(start 287.655 -39.878)
					(mid 285.877 -39.878)
					(end 287.655 -39.878)
				)
			)
		)
	)
	(zone
		(layers "In4.Cu" "In5.Cu")
		(hatch none 0.5)
		(connect_pads
			(clearance 0)
		)
		(min_thickness 0.25)
		(keepout
			(tracks not_allowed)
			(vias allowed)
			(pads allowed)
			(copperpour not_allowed)
			(footprints allowed)
		)
		(placement
			(enabled no)
			(sheetname "")
		)
		(fill yes
			(thermal_gap 0.5)
			(thermal_bridge_width 0.5)
			(island_removal_mode 0)
		)
		(polygon
			(pts
				(arc
					(start 81.788 -52.324)
					(mid 80.01 -52.324)
					(end 81.788 -52.324)
				)
			)
		)
	)
	(zone
		(layers "In4.Cu" "In5.Cu")
		(hatch none 0.5)
		(connect_pads
			(clearance 0)
		)
		(min_thickness 0.25)
		(keepout
			(tracks not_allowed)
			(vias allowed)
			(pads allowed)
			(copperpour not_allowed)
			(footprints allowed)
		)
		(placement
			(enabled no)
			(sheetname "")
		)
		(fill yes
			(thermal_gap 0.5)
			(thermal_bridge_width 0.5)
			(island_removal_mode 0)
		)
		(polygon
			(pts
				(arc
					(start 204.84465 -91.948)
					(mid 203.06665 -91.948)
					(end 204.84465 -91.948)
				)
			)
		)
	)
	(zone
		(layers "In4.Cu" "In5.Cu")
		(hatch none 0.5)
		(connect_pads
			(clearance 0)
		)
		(min_thickness 0.25)
		(keepout
			(tracks not_allowed)
			(vias allowed)
			(pads allowed)
			(copperpour not_allowed)
			(footprints allowed)
		)
		(placement
			(enabled no)
			(sheetname "")
		)
		(fill yes
			(thermal_gap 0.5)
			(thermal_bridge_width 0.5)
			(island_removal_mode 0)
		)
		(polygon
			(pts
				(arc
					(start 91.046046 -121.209816)
					(mid 87.413846 -121.209816)
					(end 91.046046 -121.209816)
				)
			)
		)
	)
	(zone
		(layers "In4.Cu" "In5.Cu")
		(hatch none 0.5)
		(connect_pads
			(clearance 0)
		)
		(min_thickness 0.25)
		(keepout
			(tracks not_allowed)
			(vias allowed)
			(pads allowed)
			(copperpour not_allowed)
			(footprints allowed)
		)
		(placement
			(enabled no)
			(sheetname "")
		)
		(fill yes
			(thermal_gap 0.5)
			(thermal_bridge_width 0.5)
			(island_removal_mode 0)
		)
		(polygon
			(pts
				(arc
					(start 47.507906 -131.572)
					(mid 45.729906 -131.572)
					(end 47.507906 -131.572)
				)
			)
		)
	)
	(zone
		(layers "In4.Cu" "In5.Cu")
		(hatch none 0.5)
		(connect_pads
			(clearance 0)
		)
		(min_thickness 0.25)
		(keepout
			(tracks not_allowed)
			(vias allowed)
			(pads allowed)
			(copperpour not_allowed)
			(footprints allowed)
		)
		(placement
			(enabled no)
			(sheetname "")
		)
		(fill yes
			(thermal_gap 0.5)
			(thermal_bridge_width 0.5)
			(island_removal_mode 0)
		)
		(polygon
			(pts
				(arc
					(start 199.512174 -55.96001)
					(mid 196.718174 -55.96001)
					(end 199.512174 -55.96001)
				)
			)
		)
	)
	(zone
		(layers "In4.Cu" "In5.Cu")
		(hatch none 0.5)
		(connect_pads
			(clearance 0)
		)
		(min_thickness 0.25)
		(keepout
			(tracks not_allowed)
			(vias allowed)
			(pads allowed)
			(copperpour not_allowed)
			(footprints allowed)
		)
		(placement
			(enabled no)
			(sheetname "")
		)
		(fill yes
			(thermal_gap 0.5)
			(thermal_bridge_width 0.5)
			(island_removal_mode 0)
		)
		(polygon
			(pts
				(arc
					(start 39.87292 -54.1909)
					(mid 38.09492 -54.1909)
					(end 39.87292 -54.1909)
				)
			)
		)
	)
	(zone
		(layers "In4.Cu" "In5.Cu")
		(hatch none 0.5)
		(connect_pads
			(clearance 0)
		)
		(min_thickness 0.25)
		(keepout
			(tracks not_allowed)
			(vias allowed)
			(pads allowed)
			(copperpour not_allowed)
			(footprints allowed)
		)
		(placement
			(enabled no)
			(sheetname "")
		)
		(fill yes
			(thermal_gap 0.5)
			(thermal_bridge_width 0.5)
			(island_removal_mode 0)
		)
		(polygon
			(pts
				(arc
					(start 238.252 -92.964)
					(mid 236.474 -92.964)
					(end 238.252 -92.964)
				)
			)
		)
	)
	(zone
		(layers "In4.Cu" "In5.Cu")
		(hatch none 0.5)
		(connect_pads
			(clearance 0)
		)
		(min_thickness 0.25)
		(keepout
			(tracks not_allowed)
			(vias allowed)
			(pads allowed)
			(copperpour not_allowed)
			(footprints allowed)
		)
		(placement
			(enabled no)
			(sheetname "")
		)
		(fill yes
			(thermal_gap 0.5)
			(thermal_bridge_width 0.5)
			(island_removal_mode 0)
		)
		(polygon
			(pts
				(arc
					(start 234.569 -90.30335)
					(mid 232.791 -90.30335)
					(end 234.569 -90.30335)
				)
			)
		)
	)
	(zone
		(layers "In4.Cu" "In5.Cu")
		(hatch none 0.5)
		(connect_pads
			(clearance 0)
		)
		(min_thickness 0.25)
		(keepout
			(tracks not_allowed)
			(vias allowed)
			(pads allowed)
			(copperpour not_allowed)
			(footprints allowed)
		)
		(placement
			(enabled no)
			(sheetname "")
		)
		(fill yes
			(thermal_gap 0.5)
			(thermal_bridge_width 0.5)
			(island_removal_mode 0)
		)
		(polygon
			(pts
				(arc
					(start 225.425 -92.964)
					(mid 223.647 -92.964)
					(end 225.425 -92.964)
				)
			)
		)
	)
	(zone
		(layers "In4.Cu" "In5.Cu")
		(hatch none 0.5)
		(connect_pads
			(clearance 0)
		)
		(min_thickness 0.25)
		(keepout
			(tracks not_allowed)
			(vias allowed)
			(pads allowed)
			(copperpour not_allowed)
			(footprints allowed)
		)
		(placement
			(enabled no)
			(sheetname "")
		)
		(fill yes
			(thermal_gap 0.5)
			(thermal_bridge_width 0.5)
			(island_removal_mode 0)
		)
		(polygon
			(pts
				(arc
					(start 285.683452 -36.703)
					(mid 283.905452 -36.703)
					(end 285.683452 -36.703)
				)
			)
		)
	)
	(zone
		(layers "In4.Cu" "In5.Cu")
		(hatch none 0.5)
		(connect_pads
			(clearance 0)
		)
		(min_thickness 0.25)
		(keepout
			(tracks not_allowed)
			(vias allowed)
			(pads allowed)
			(copperpour not_allowed)
			(footprints allowed)
		)
		(placement
			(enabled no)
			(sheetname "")
		)
		(fill yes
			(thermal_gap 0.5)
			(thermal_bridge_width 0.5)
			(island_removal_mode 0)
		)
		(polygon
			(pts
				(arc
					(start 237.920784 -78.71714)
					(mid 236.142784 -78.71714)
					(end 237.920784 -78.71714)
				)
			)
		)
	)
	(zone
		(layers "In4.Cu" "In5.Cu")
		(hatch none 0.5)
		(connect_pads
			(clearance 0)
		)
		(min_thickness 0.25)
		(keepout
			(tracks not_allowed)
			(vias allowed)
			(pads allowed)
			(copperpour not_allowed)
			(footprints allowed)
		)
		(placement
			(enabled no)
			(sheetname "")
		)
		(fill yes
			(thermal_gap 0.5)
			(thermal_bridge_width 0.5)
			(island_removal_mode 0)
		)
		(polygon
			(pts
				(arc
					(start 132.588 -55.96001)
					(mid 129.794 -55.96001)
					(end 132.588 -55.96001)
				)
			)
		)
	)
	(zone
		(layers "In4.Cu" "In5.Cu")
		(hatch none 0.5)
		(connect_pads
			(clearance 0)
		)
		(min_thickness 0.25)
		(keepout
			(tracks not_allowed)
			(vias allowed)
			(pads allowed)
			(copperpour not_allowed)
			(footprints allowed)
		)
		(placement
			(enabled no)
			(sheetname "")
		)
		(fill yes
			(thermal_gap 0.5)
			(thermal_bridge_width 0.5)
			(island_removal_mode 0)
		)
		(polygon
			(pts
				(arc
					(start 176.276 -52.197)
					(mid 174.498 -52.197)
					(end 176.276 -52.197)
				)
			)
		)
	)
	(zone
		(layers "In4.Cu" "In5.Cu")
		(hatch none 0.5)
		(connect_pads
			(clearance 0)
		)
		(min_thickness 0.25)
		(keepout
			(tracks not_allowed)
			(vias allowed)
			(pads allowed)
			(copperpour not_allowed)
			(footprints allowed)
		)
		(placement
			(enabled no)
			(sheetname "")
		)
		(fill yes
			(thermal_gap 0.5)
			(thermal_bridge_width 0.5)
			(island_removal_mode 0)
		)
		(polygon
			(pts
				(arc
					(start 79.312008 -40.55999)
					(mid 76.518008 -40.55999)
					(end 79.312008 -40.55999)
				)
			)
		)
	)
	(zone
		(layers "In4.Cu" "In5.Cu")
		(hatch none 0.5)
		(connect_pads
			(clearance 0)
		)
		(min_thickness 0.25)
		(keepout
			(tracks not_allowed)
			(vias allowed)
			(pads allowed)
			(copperpour not_allowed)
			(footprints allowed)
		)
		(placement
			(enabled no)
			(sheetname "")
		)
		(fill yes
			(thermal_gap 0.5)
			(thermal_bridge_width 0.5)
			(island_removal_mode 0)
		)
		(polygon
			(pts
				(arc
					(start 154.432 -49.657)
					(mid 152.654 -49.657)
					(end 154.432 -49.657)
				)
			)
		)
	)
	(zone
		(layers "In4.Cu" "In5.Cu")
		(hatch none 0.5)
		(connect_pads
			(clearance 0)
		)
		(min_thickness 0.25)
		(keepout
			(tracks not_allowed)
			(vias allowed)
			(pads allowed)
			(copperpour not_allowed)
			(footprints allowed)
		)
		(placement
			(enabled no)
			(sheetname "")
		)
		(fill yes
			(thermal_gap 0.5)
			(thermal_bridge_width 0.5)
			(island_removal_mode 0)
		)
		(polygon
			(pts
				(arc
					(start 111.891826 -131.572)
					(mid 110.113826 -131.572)
					(end 111.891826 -131.572)
				)
			)
		)
	)
	(zone
		(layers "In4.Cu" "In5.Cu")
		(hatch none 0.5)
		(connect_pads
			(clearance 0)
		)
		(min_thickness 0.25)
		(keepout
			(tracks not_allowed)
			(vias allowed)
			(pads allowed)
			(copperpour not_allowed)
			(footprints allowed)
		)
		(placement
			(enabled no)
			(sheetname "")
		)
		(fill yes
			(thermal_gap 0.5)
			(thermal_bridge_width 0.5)
			(island_removal_mode 0)
		)
		(polygon
			(pts
				(arc
					(start 190.90005 -93.091)
					(mid 189.12205 -93.091)
					(end 190.90005 -93.091)
				)
			)
		)
	)
	(zone
		(layers "In4.Cu" "In5.Cu")
		(hatch none 0.5)
		(connect_pads
			(clearance 0)
		)
		(min_thickness 0.25)
		(keepout
			(tracks not_allowed)
			(vias allowed)
			(pads allowed)
			(copperpour not_allowed)
			(footprints allowed)
		)
		(placement
			(enabled no)
			(sheetname "")
		)
		(fill yes
			(thermal_gap 0.5)
			(thermal_bridge_width 0.5)
			(island_removal_mode 0)
		)
		(polygon
			(pts
				(arc
					(start 59.699906 -126.492)
					(mid 57.921906 -126.492)
					(end 59.699906 -126.492)
				)
			)
		)
	)
	(zone
		(layers "In4.Cu" "In5.Cu")
		(hatch none 0.5)
		(connect_pads
			(clearance 0)
		)
		(min_thickness 0.25)
		(keepout
			(tracks not_allowed)
			(vias allowed)
			(pads allowed)
			(copperpour not_allowed)
			(footprints allowed)
		)
		(placement
			(enabled no)
			(sheetname "")
		)
		(fill yes
			(thermal_gap 0.5)
			(thermal_bridge_width 0.5)
			(island_removal_mode 0)
		)
		(polygon
			(pts
				(arc
					(start 283.1084 -41.592246)
					(mid 281.3304 -41.592246)
					(end 283.1084 -41.592246)
				)
			)
		)
	)
	(zone
		(layers "In4.Cu" "In5.Cu")
		(hatch none 0.5)
		(connect_pads
			(clearance 0)
		)
		(min_thickness 0.25)
		(keepout
			(tracks not_allowed)
			(vias allowed)
			(pads allowed)
			(copperpour not_allowed)
			(footprints allowed)
		)
		(placement
			(enabled no)
			(sheetname "")
		)
		(fill yes
			(thermal_gap 0.5)
			(thermal_bridge_width 0.5)
			(island_removal_mode 0)
		)
		(polygon
			(pts
				(arc
					(start 165.354 -49.657)
					(mid 163.576 -49.657)
					(end 165.354 -49.657)
				)
			)
		)
	)
	(zone
		(layers "In4.Cu" "In5.Cu")
		(hatch none 0.5)
		(connect_pads
			(clearance 0)
		)
		(min_thickness 0.25)
		(keepout
			(tracks not_allowed)
			(vias allowed)
			(pads allowed)
			(copperpour not_allowed)
			(footprints allowed)
		)
		(placement
			(enabled no)
			(sheetname "")
		)
		(fill yes
			(thermal_gap 0.5)
			(thermal_bridge_width 0.5)
			(island_removal_mode 0)
		)
		(polygon
			(pts
				(arc
					(start 111.129826 -131.572)
					(mid 109.351826 -131.572)
					(end 111.129826 -131.572)
				)
			)
		)
	)
	(zone
		(layers "In4.Cu" "In5.Cu")
		(hatch none 0.5)
		(connect_pads
			(clearance 0)
		)
		(min_thickness 0.25)
		(keepout
			(tracks not_allowed)
			(vias allowed)
			(pads allowed)
			(copperpour not_allowed)
			(footprints allowed)
		)
		(placement
			(enabled no)
			(sheetname "")
		)
		(fill yes
			(thermal_gap 0.5)
			(thermal_bridge_width 0.5)
			(island_removal_mode 0)
		)
		(polygon
			(pts
				(arc
					(start 97.092008 -38.01999)
					(mid 94.298008 -38.01999)
					(end 97.092008 -38.01999)
				)
			)
		)
	)
	(zone
		(layers "In4.Cu" "In5.Cu")
		(hatch none 0.5)
		(connect_pads
			(clearance 0)
		)
		(min_thickness 0.25)
		(keepout
			(tracks not_allowed)
			(vias allowed)
			(pads allowed)
			(copperpour not_allowed)
			(footprints allowed)
		)
		(placement
			(enabled no)
			(sheetname "")
		)
		(fill yes
			(thermal_gap 0.5)
			(thermal_bridge_width 0.5)
			(island_removal_mode 0)
		)
		(polygon
			(pts
				(arc
					(start 283.623766 -42.092626)
					(mid 281.845766 -42.092626)
					(end 283.623766 -42.092626)
				)
			)
		)
	)
	(zone
		(layers "In4.Cu" "In5.Cu")
		(hatch none 0.5)
		(connect_pads
			(clearance 0)
		)
		(min_thickness 0.25)
		(keepout
			(tracks not_allowed)
			(vias allowed)
			(pads allowed)
			(copperpour not_allowed)
			(footprints allowed)
		)
		(placement
			(enabled no)
			(sheetname "")
		)
		(fill yes
			(thermal_gap 0.5)
			(thermal_bridge_width 0.5)
			(island_removal_mode 0)
		)
		(polygon
			(pts
				(arc
					(start 278.771096 -45.593)
					(mid 276.993096 -45.593)
					(end 278.771096 -45.593)
				)
			)
		)
	)
	(zone
		(layers "In4.Cu" "In5.Cu")
		(hatch none 0.5)
		(connect_pads
			(clearance 0)
		)
		(min_thickness 0.25)
		(keepout
			(tracks not_allowed)
			(vias allowed)
			(pads allowed)
			(copperpour not_allowed)
			(footprints allowed)
		)
		(placement
			(enabled no)
			(sheetname "")
		)
		(fill yes
			(thermal_gap 0.5)
			(thermal_bridge_width 0.5)
			(island_removal_mode 0)
		)
		(polygon
			(pts
				(arc
					(start 87.249 -51.689)
					(mid 85.471 -51.689)
					(end 87.249 -51.689)
				)
			)
		)
	)
	(zone
		(layers "In4.Cu" "In5.Cu")
		(hatch none 0.5)
		(connect_pads
			(clearance 0)
		)
		(min_thickness 0.25)
		(keepout
			(tracks not_allowed)
			(vias allowed)
			(pads allowed)
			(copperpour not_allowed)
			(footprints allowed)
		)
		(placement
			(enabled no)
			(sheetname "")
		)
		(fill yes
			(thermal_gap 0.5)
			(thermal_bridge_width 0.5)
			(island_removal_mode 0)
		)
		(polygon
			(pts
				(arc
					(start 49.85004 -61.4934)
					(mid 48.07204 -61.4934)
					(end 49.85004 -61.4934)
				)
			)
		)
	)
	(zone
		(layers "In4.Cu" "In5.Cu")
		(hatch none 0.5)
		(connect_pads
			(clearance 0)
		)
		(min_thickness 0.25)
		(keepout
			(tracks not_allowed)
			(vias allowed)
			(pads allowed)
			(copperpour not_allowed)
			(footprints allowed)
		)
		(placement
			(enabled no)
			(sheetname "")
		)
		(fill yes
			(thermal_gap 0.5)
			(thermal_bridge_width 0.5)
			(island_removal_mode 0)
		)
		(polygon
			(pts
				(arc
					(start 51.37404 -61.4934)
					(mid 49.59604 -61.4934)
					(end 51.37404 -61.4934)
				)
			)
		)
	)
	(zone
		(layers "In4.Cu" "In5.Cu")
		(hatch none 0.5)
		(connect_pads
			(clearance 0)
		)
		(min_thickness 0.25)
		(keepout
			(tracks not_allowed)
			(vias allowed)
			(pads allowed)
			(copperpour not_allowed)
			(footprints allowed)
		)
		(placement
			(enabled no)
			(sheetname "")
		)
		(fill yes
			(thermal_gap 0.5)
			(thermal_bridge_width 0.5)
			(island_removal_mode 0)
		)
		(polygon
			(pts
				(arc
					(start 237.961678 -87.590122)
					(mid 236.183678 -87.590122)
					(end 237.961678 -87.590122)
				)
			)
		)
	)
	(zone
		(layers "In4.Cu" "In5.Cu")
		(hatch none 0.5)
		(connect_pads
			(clearance 0)
		)
		(min_thickness 0.25)
		(keepout
			(tracks not_allowed)
			(vias allowed)
			(pads allowed)
			(copperpour not_allowed)
			(footprints allowed)
		)
		(placement
			(enabled no)
			(sheetname "")
		)
		(fill yes
			(thermal_gap 0.5)
			(thermal_bridge_width 0.5)
			(island_removal_mode 0)
		)
		(polygon
			(pts
				(arc
					(start 50.61204 -62.2554)
					(mid 48.83404 -62.2554)
					(end 50.61204 -62.2554)
				)
			)
		)
	)
	(zone
		(layers "In4.Cu" "In5.Cu")
		(hatch none 0.5)
		(connect_pads
			(clearance 0)
		)
		(min_thickness 0.25)
		(keepout
			(tracks not_allowed)
			(vias allowed)
			(pads allowed)
			(copperpour not_allowed)
			(footprints allowed)
		)
		(placement
			(enabled no)
			(sheetname "")
		)
		(fill yes
			(thermal_gap 0.5)
			(thermal_bridge_width 0.5)
			(island_removal_mode 0)
		)
		(polygon
			(pts
				(arc
					(start 241.427 -74.542904)
					(mid 239.649 -74.542904)
					(end 241.427 -74.542904)
				)
			)
		)
	)
	(zone
		(layers "In4.Cu" "In5.Cu")
		(hatch none 0.5)
		(connect_pads
			(clearance 0)
		)
		(min_thickness 0.25)
		(keepout
			(tracks not_allowed)
			(vias allowed)
			(pads allowed)
			(copperpour not_allowed)
			(footprints allowed)
		)
		(placement
			(enabled no)
			(sheetname "")
		)
		(fill yes
			(thermal_gap 0.5)
			(thermal_bridge_width 0.5)
			(island_removal_mode 0)
		)
		(polygon
			(pts
				(arc
					(start 231.521 -83.30565)
					(mid 229.743 -83.30565)
					(end 231.521 -83.30565)
				)
			)
		)
	)
	(zone
		(layers "In4.Cu" "In5.Cu")
		(hatch none 0.5)
		(connect_pads
			(clearance 0)
		)
		(min_thickness 0.25)
		(keepout
			(tracks not_allowed)
			(vias allowed)
			(pads allowed)
			(copperpour not_allowed)
			(footprints allowed)
		)
		(placement
			(enabled no)
			(sheetname "")
		)
		(fill yes
			(thermal_gap 0.5)
			(thermal_bridge_width 0.5)
			(island_removal_mode 0)
		)
		(polygon
			(pts
				(arc
					(start 88.469216 -136.906)
					(mid 85.624416 -136.906)
					(end 88.469216 -136.906)
				)
			)
		)
	)
	(zone
		(layers "In4.Cu" "In5.Cu")
		(hatch none 0.5)
		(connect_pads
			(clearance 0)
		)
		(min_thickness 0.25)
		(keepout
			(tracks not_allowed)
			(vias allowed)
			(pads allowed)
			(copperpour not_allowed)
			(footprints allowed)
		)
		(placement
			(enabled no)
			(sheetname "")
		)
		(fill yes
			(thermal_gap 0.5)
			(thermal_bridge_width 0.5)
			(island_removal_mode 0)
		)
		(polygon
			(pts
				(arc
					(start 139.7 -126.492)
					(mid 137.922 -126.492)
					(end 139.7 -126.492)
				)
			)
		)
	)
	(zone
		(layers "In4.Cu" "In5.Cu")
		(hatch none 0.5)
		(connect_pads
			(clearance 0)
		)
		(min_thickness 0.25)
		(keepout
			(tracks not_allowed)
			(vias allowed)
			(pads allowed)
			(copperpour not_allowed)
			(footprints allowed)
		)
		(placement
			(enabled no)
			(sheetname "")
		)
		(fill yes
			(thermal_gap 0.5)
			(thermal_bridge_width 0.5)
			(island_removal_mode 0)
		)
		(polygon
			(pts
				(arc
					(start 216.916 -92.964)
					(mid 215.138 -92.964)
					(end 216.916 -92.964)
				)
			)
		)
	)
	(zone
		(layers "In4.Cu" "In5.Cu")
		(hatch none 0.5)
		(connect_pads
			(clearance 0)
		)
		(min_thickness 0.25)
		(keepout
			(tracks not_allowed)
			(vias allowed)
			(pads allowed)
			(copperpour not_allowed)
			(footprints allowed)
		)
		(placement
			(enabled no)
			(sheetname "")
		)
		(fill yes
			(thermal_gap 0.5)
			(thermal_bridge_width 0.5)
			(island_removal_mode 0)
		)
		(polygon
			(pts
				(arc
					(start 139.7 -131.572)
					(mid 137.922 -131.572)
					(end 139.7 -131.572)
				)
			)
		)
	)
	(zone
		(layers "In4.Cu" "In5.Cu")
		(hatch none 0.5)
		(connect_pads
			(clearance 0)
		)
		(min_thickness 0.25)
		(keepout
			(tracks not_allowed)
			(vias allowed)
			(pads allowed)
			(copperpour not_allowed)
			(footprints allowed)
		)
		(placement
			(enabled no)
			(sheetname "")
		)
		(fill yes
			(thermal_gap 0.5)
			(thermal_bridge_width 0.5)
			(island_removal_mode 0)
		)
		(polygon
			(pts
				(arc
					(start 137.73912 -113.03635)
					(mid 135.96112 -113.03635)
					(end 137.73912 -113.03635)
				)
			)
		)
	)
	(zone
		(layers "In4.Cu" "In5.Cu")
		(hatch none 0.5)
		(connect_pads
			(clearance 0)
		)
		(min_thickness 0.25)
		(keepout
			(tracks not_allowed)
			(vias allowed)
			(pads allowed)
			(copperpour not_allowed)
			(footprints allowed)
		)
		(placement
			(enabled no)
			(sheetname "")
		)
		(fill yes
			(thermal_gap 0.5)
			(thermal_bridge_width 0.5)
			(island_removal_mode 0)
		)
		(polygon
			(pts
				(arc
					(start 187.19546 -51.562)
					(mid 185.41746 -51.562)
					(end 187.19546 -51.562)
				)
			)
		)
	)
	(zone
		(layers "In4.Cu" "In5.Cu")
		(hatch none 0.5)
		(connect_pads
			(clearance 0)
		)
		(min_thickness 0.25)
		(keepout
			(tracks not_allowed)
			(vias allowed)
			(pads allowed)
			(copperpour not_allowed)
			(footprints allowed)
		)
		(placement
			(enabled no)
			(sheetname "")
		)
		(fill yes
			(thermal_gap 0.5)
			(thermal_bridge_width 0.5)
			(island_removal_mode 0)
		)
		(polygon
			(pts
				(arc
					(start 225.171 -74.65695)
					(mid 223.393 -74.65695)
					(end 225.171 -74.65695)
				)
			)
		)
	)
	(zone
		(layers "In4.Cu" "In5.Cu")
		(hatch none 0.5)
		(connect_pads
			(clearance 0)
		)
		(min_thickness 0.25)
		(keepout
			(tracks not_allowed)
			(vias allowed)
			(pads allowed)
			(copperpour not_allowed)
			(footprints allowed)
		)
		(placement
			(enabled no)
			(sheetname "")
		)
		(fill yes
			(thermal_gap 0.5)
			(thermal_bridge_width 0.5)
			(island_removal_mode 0)
		)
		(polygon
			(pts
				(arc
					(start 283.972 -47.9298)
					(mid 282.194 -47.9298)
					(end 283.972 -47.9298)
				)
			)
		)
	)
	(zone
		(layers "In4.Cu" "In5.Cu")
		(hatch none 0.5)
		(connect_pads
			(clearance 0)
		)
		(min_thickness 0.25)
		(keepout
			(tracks not_allowed)
			(vias allowed)
			(pads allowed)
			(copperpour not_allowed)
			(footprints allowed)
		)
		(placement
			(enabled no)
			(sheetname "")
		)
		(fill yes
			(thermal_gap 0.5)
			(thermal_bridge_width 0.5)
			(island_removal_mode 0)
		)
		(polygon
			(pts
				(arc
					(start 44.814236 -55.65394)
					(mid 43.036236 -55.65394)
					(end 44.814236 -55.65394)
				)
			)
		)
	)
	(zone
		(layers "In4.Cu" "In5.Cu")
		(hatch none 0.5)
		(connect_pads
			(clearance 0)
		)
		(min_thickness 0.25)
		(keepout
			(tracks not_allowed)
			(vias allowed)
			(pads allowed)
			(copperpour not_allowed)
			(footprints allowed)
		)
		(placement
			(enabled no)
			(sheetname "")
		)
		(fill yes
			(thermal_gap 0.5)
			(thermal_bridge_width 0.5)
			(island_removal_mode 0)
		)
		(polygon
			(pts
				(arc
					(start 151.13 -131.572)
					(mid 149.352 -131.572)
					(end 151.13 -131.572)
				)
			)
		)
	)
	(zone
		(layers "In4.Cu" "In5.Cu")
		(hatch none 0.5)
		(connect_pads
			(clearance 0)
		)
		(min_thickness 0.25)
		(keepout
			(tracks not_allowed)
			(vias allowed)
			(pads allowed)
			(copperpour not_allowed)
			(footprints allowed)
		)
		(placement
			(enabled no)
			(sheetname "")
		)
		(fill yes
			(thermal_gap 0.5)
			(thermal_bridge_width 0.5)
			(island_removal_mode 0)
		)
		(polygon
			(pts
				(arc
					(start 191.130174 -131.572)
					(mid 189.352174 -131.572)
					(end 191.130174 -131.572)
				)
			)
		)
	)
	(zone
		(layers "In4.Cu" "In5.Cu")
		(hatch none 0.5)
		(connect_pads
			(clearance 0)
		)
		(min_thickness 0.25)
		(keepout
			(tracks not_allowed)
			(vias allowed)
			(pads allowed)
			(copperpour not_allowed)
			(footprints allowed)
		)
		(placement
			(enabled no)
			(sheetname "")
		)
		(fill yes
			(thermal_gap 0.5)
			(thermal_bridge_width 0.5)
			(island_removal_mode 0)
		)
		(polygon
			(pts
				(arc
					(start 221.615 -91.567)
					(mid 219.837 -91.567)
					(end 221.615 -91.567)
				)
			)
		)
	)
	(zone
		(layers "In4.Cu" "In5.Cu")
		(hatch none 0.5)
		(connect_pads
			(clearance 0)
		)
		(min_thickness 0.25)
		(keepout
			(tracks not_allowed)
			(vias allowed)
			(pads allowed)
			(copperpour not_allowed)
			(footprints allowed)
		)
		(placement
			(enabled no)
			(sheetname "")
		)
		(fill yes
			(thermal_gap 0.5)
			(thermal_bridge_width 0.5)
			(island_removal_mode 0)
		)
		(polygon
			(pts
				(arc
					(start 179.700174 -126.492)
					(mid 177.922174 -126.492)
					(end 179.700174 -126.492)
				)
			)
		)
	)
	(zone
		(layers "In4.Cu" "In5.Cu")
		(hatch none 0.5)
		(connect_pads
			(clearance 0)
		)
		(min_thickness 0.25)
		(keepout
			(tracks not_allowed)
			(vias allowed)
			(pads allowed)
			(copperpour not_allowed)
			(footprints allowed)
		)
		(placement
			(enabled no)
			(sheetname "")
		)
		(fill yes
			(thermal_gap 0.5)
			(thermal_bridge_width 0.5)
			(island_removal_mode 0)
		)
		(polygon
			(pts
				(arc
					(start 141.986 -60.706)
					(mid 140.208 -60.706)
					(end 141.986 -60.706)
				)
			)
		)
	)
	(zone
		(layers "In4.Cu" "In5.Cu")
		(hatch none 0.5)
		(connect_pads
			(clearance 0)
		)
		(min_thickness 0.25)
		(keepout
			(tracks not_allowed)
			(vias allowed)
			(pads allowed)
			(copperpour not_allowed)
			(footprints allowed)
		)
		(placement
			(enabled no)
			(sheetname "")
		)
		(fill yes
			(thermal_gap 0.5)
			(thermal_bridge_width 0.5)
			(island_removal_mode 0)
		)
		(polygon
			(pts
				(arc
					(start 41.8846 -82.0928)
					(mid 40.1066 -82.0928)
					(end 41.8846 -82.0928)
				)
			)
		)
	)
	(zone
		(layers "In4.Cu" "In5.Cu")
		(hatch none 0.5)
		(connect_pads
			(clearance 0)
		)
		(min_thickness 0.25)
		(keepout
			(tracks not_allowed)
			(vias allowed)
			(pads allowed)
			(copperpour not_allowed)
			(footprints allowed)
		)
		(placement
			(enabled no)
			(sheetname "")
		)
		(fill yes
			(thermal_gap 0.5)
			(thermal_bridge_width 0.5)
			(island_removal_mode 0)
		)
		(polygon
			(pts
				(arc
					(start 230.378 -83.30565)
					(mid 228.6 -83.30565)
					(end 230.378 -83.30565)
				)
			)
		)
	)
	(zone
		(layers "In4.Cu" "In5.Cu")
		(hatch none 0.5)
		(connect_pads
			(clearance 0)
		)
		(min_thickness 0.25)
		(keepout
			(tracks not_allowed)
			(vias allowed)
			(pads allowed)
			(copperpour not_allowed)
			(footprints allowed)
		)
		(placement
			(enabled no)
			(sheetname "")
		)
		(fill yes
			(thermal_gap 0.5)
			(thermal_bridge_width 0.5)
			(island_removal_mode 0)
		)
		(polygon
			(pts
				(arc
					(start 154.432 -52.197)
					(mid 152.654 -52.197)
					(end 154.432 -52.197)
				)
			)
		)
	)
	(zone
		(layers "In4.Cu" "In5.Cu")
		(hatch none 0.5)
		(connect_pads
			(clearance 0)
		)
		(min_thickness 0.25)
		(keepout
			(tracks not_allowed)
			(vias allowed)
			(pads allowed)
			(copperpour not_allowed)
			(footprints allowed)
		)
		(placement
			(enabled no)
			(sheetname "")
		)
		(fill yes
			(thermal_gap 0.5)
			(thermal_bridge_width 0.5)
			(island_removal_mode 0)
		)
		(polygon
			(pts
				(arc
					(start 239.79505 -77.216)
					(mid 238.01705 -77.216)
					(end 239.79505 -77.216)
				)
			)
		)
	)
	(zone
		(layers "In4.Cu" "In5.Cu")
		(hatch none 0.5)
		(connect_pads
			(clearance 0)
		)
		(min_thickness 0.25)
		(keepout
			(tracks not_allowed)
			(vias allowed)
			(pads allowed)
			(copperpour not_allowed)
			(footprints allowed)
		)
		(placement
			(enabled no)
			(sheetname "")
		)
		(fill yes
			(thermal_gap 0.5)
			(thermal_bridge_width 0.5)
			(island_removal_mode 0)
		)
		(polygon
			(pts
				(arc
					(start 111.129826 -126.492)
					(mid 109.351826 -126.492)
					(end 111.129826 -126.492)
				)
			)
		)
	)
	(zone
		(layers "In4.Cu" "In5.Cu")
		(hatch none 0.5)
		(connect_pads
			(clearance 0)
		)
		(min_thickness 0.25)
		(keepout
			(tracks not_allowed)
			(vias allowed)
			(pads allowed)
			(copperpour not_allowed)
			(footprints allowed)
		)
		(placement
			(enabled no)
			(sheetname "")
		)
		(fill yes
			(thermal_gap 0.5)
			(thermal_bridge_width 0.5)
			(island_removal_mode 0)
		)
		(polygon
			(pts
				(arc
					(start 99.699826 -126.492)
					(mid 97.921826 -126.492)
					(end 99.699826 -126.492)
				)
			)
		)
	)
	(zone
		(layers "In4.Cu" "In5.Cu")
		(hatch none 0.5)
		(connect_pads
			(clearance 0)
		)
		(min_thickness 0.25)
		(keepout
			(tracks not_allowed)
			(vias allowed)
			(pads allowed)
			(copperpour not_allowed)
			(footprints allowed)
		)
		(placement
			(enabled no)
			(sheetname "")
		)
		(fill yes
			(thermal_gap 0.5)
			(thermal_bridge_width 0.5)
			(island_removal_mode 0)
		)
		(polygon
			(pts
				(arc
					(start 97.092008 -32.93999)
					(mid 94.298008 -32.93999)
					(end 97.092008 -32.93999)
				)
			)
		)
	)
	(zone
		(layers "In4.Cu" "In5.Cu")
		(hatch none 0.5)
		(connect_pads
			(clearance 0)
		)
		(min_thickness 0.25)
		(keepout
			(tracks not_allowed)
			(vias allowed)
			(pads allowed)
			(copperpour not_allowed)
			(footprints allowed)
		)
		(placement
			(enabled no)
			(sheetname "")
		)
		(fill yes
			(thermal_gap 0.5)
			(thermal_bridge_width 0.5)
			(island_removal_mode 0)
		)
		(polygon
			(pts
				(arc
					(start 237.236 -80.12684)
					(mid 235.458 -80.12684)
					(end 237.236 -80.12684)
				)
			)
		)
	)
	(zone
		(layers "In4.Cu" "In5.Cu")
		(hatch none 0.5)
		(connect_pads
			(clearance 0)
		)
		(min_thickness 0.25)
		(keepout
			(tracks not_allowed)
			(vias allowed)
			(pads allowed)
			(copperpour not_allowed)
			(footprints allowed)
		)
		(placement
			(enabled no)
			(sheetname "")
		)
		(fill yes
			(thermal_gap 0.5)
			(thermal_bridge_width 0.5)
			(island_removal_mode 0)
		)
		(polygon
			(pts
				(arc
					(start 230.251 -92.964)
					(mid 228.473 -92.964)
					(end 230.251 -92.964)
				)
			)
		)
	)
	(zone
		(layers "In4.Cu" "In5.Cu")
		(hatch none 0.5)
		(connect_pads
			(clearance 0)
		)
		(min_thickness 0.25)
		(keepout
			(tracks not_allowed)
			(vias allowed)
			(pads allowed)
			(copperpour not_allowed)
			(footprints allowed)
		)
		(placement
			(enabled no)
			(sheetname "")
		)
		(fill yes
			(thermal_gap 0.5)
			(thermal_bridge_width 0.5)
			(island_removal_mode 0)
		)
		(polygon
			(pts
				(arc
					(start 47.507906 -126.492)
					(mid 45.729906 -126.492)
					(end 47.507906 -126.492)
				)
			)
		)
	)
	(zone
		(layers "In4.Cu" "In5.Cu")
		(hatch none 0.5)
		(connect_pads
			(clearance 0)
		)
		(min_thickness 0.25)
		(keepout
			(tracks not_allowed)
			(vias allowed)
			(pads allowed)
			(copperpour not_allowed)
			(footprints allowed)
		)
		(placement
			(enabled no)
			(sheetname "")
		)
		(fill yes
			(thermal_gap 0.5)
			(thermal_bridge_width 0.5)
			(island_removal_mode 0)
		)
		(polygon
			(pts
				(arc
					(start 76.772008 -32.93999)
					(mid 73.978008 -32.93999)
					(end 76.772008 -32.93999)
				)
			)
		)
	)
	(zone
		(layers "In4.Cu" "In5.Cu")
		(hatch none 0.5)
		(connect_pads
			(clearance 0)
		)
		(min_thickness 0.25)
		(keepout
			(tracks not_allowed)
			(vias allowed)
			(pads allowed)
			(copperpour not_allowed)
			(footprints allowed)
		)
		(placement
			(enabled no)
			(sheetname "")
		)
		(fill yes
			(thermal_gap 0.5)
			(thermal_bridge_width 0.5)
			(island_removal_mode 0)
		)
		(polygon
			(pts
				(arc
					(start 238.510064 -91.71305)
					(mid 236.732064 -91.71305)
					(end 238.510064 -91.71305)
				)
			)
		)
	)
	(zone
		(layers "In4.Cu" "In5.Cu")
		(hatch none 0.5)
		(connect_pads
			(clearance 0)
		)
		(min_thickness 0.25)
		(keepout
			(tracks not_allowed)
			(vias allowed)
			(pads allowed)
			(copperpour not_allowed)
			(footprints allowed)
		)
		(placement
			(enabled no)
			(sheetname "")
		)
		(fill yes
			(thermal_gap 0.5)
			(thermal_bridge_width 0.5)
			(island_removal_mode 0)
		)
		(polygon
			(pts
				(arc
					(start 109.093 -50.419)
					(mid 107.315 -50.419)
					(end 109.093 -50.419)
				)
			)
		)
	)
	(zone
		(layers "In4.Cu" "In5.Cu")
		(hatch none 0.5)
		(connect_pads
			(clearance 0)
		)
		(min_thickness 0.25)
		(keepout
			(tracks not_allowed)
			(vias allowed)
			(pads allowed)
			(copperpour not_allowed)
			(footprints allowed)
		)
		(placement
			(enabled no)
			(sheetname "")
		)
		(fill yes
			(thermal_gap 0.5)
			(thermal_bridge_width 0.5)
			(island_removal_mode 0)
		)
		(polygon
			(pts
				(arc
					(start 225.171 -91.059)
					(mid 223.393 -91.059)
					(end 225.171 -91.059)
				)
			)
		)
	)
	(zone
		(layers "In4.Cu" "In5.Cu")
		(hatch none 0.5)
		(connect_pads
			(clearance 0)
		)
		(min_thickness 0.25)
		(keepout
			(tracks not_allowed)
			(vias allowed)
			(pads allowed)
			(copperpour not_allowed)
			(footprints allowed)
		)
		(placement
			(enabled no)
			(sheetname "")
		)
		(fill yes
			(thermal_gap 0.5)
			(thermal_bridge_width 0.5)
			(island_removal_mode 0)
		)
		(polygon
			(pts
				(arc
					(start 49.08804 -61.4934)
					(mid 47.31004 -61.4934)
					(end 49.08804 -61.4934)
				)
			)
		)
	)
	(zone
		(layers "In4.Cu" "In5.Cu")
		(hatch none 0.5)
		(connect_pads
			(clearance 0)
		)
		(min_thickness 0.25)
		(keepout
			(tracks not_allowed)
			(vias allowed)
			(pads allowed)
			(copperpour not_allowed)
			(footprints allowed)
		)
		(placement
			(enabled no)
			(sheetname "")
		)
		(fill yes
			(thermal_gap 0.5)
			(thermal_bridge_width 0.5)
			(island_removal_mode 0)
		)
		(polygon
			(pts
				(arc
					(start 176.276 -49.657)
					(mid 174.498 -49.657)
					(end 176.276 -49.657)
				)
			)
		)
	)
	(zone
		(layers "In4.Cu" "In5.Cu")
		(hatch none 0.5)
		(connect_pads
			(clearance 0)
		)
		(min_thickness 0.25)
		(keepout
			(tracks not_allowed)
			(vias allowed)
			(pads allowed)
			(copperpour not_allowed)
			(footprints allowed)
		)
		(placement
			(enabled no)
			(sheetname "")
		)
		(fill yes
			(thermal_gap 0.5)
			(thermal_bridge_width 0.5)
			(island_removal_mode 0)
		)
		(polygon
			(pts
				(arc
					(start 285.502096 -35.168078)
					(mid 283.724096 -35.168078)
					(end 285.502096 -35.168078)
				)
			)
		)
	)
	(zone
		(layers "In4.Cu" "In5.Cu")
		(hatch none 0.5)
		(connect_pads
			(clearance 0)
		)
		(min_thickness 0.25)
		(keepout
			(tracks not_allowed)
			(vias allowed)
			(pads allowed)
			(copperpour not_allowed)
			(footprints allowed)
		)
		(placement
			(enabled no)
			(sheetname "")
		)
		(fill yes
			(thermal_gap 0.5)
			(thermal_bridge_width 0.5)
			(island_removal_mode 0)
		)
		(polygon
			(pts
				(arc
					(start 242.316 -92.964)
					(mid 240.538 -92.964)
					(end 242.316 -92.964)
				)
			)
		)
	)
	(zone
		(layers "In4.Cu" "In5.Cu")
		(hatch none 0.5)
		(connect_pads
			(clearance 0)
		)
		(min_thickness 0.25)
		(keepout
			(tracks not_allowed)
			(vias allowed)
			(pads allowed)
			(copperpour not_allowed)
			(footprints allowed)
		)
		(placement
			(enabled no)
			(sheetname "")
		)
		(fill yes
			(thermal_gap 0.5)
			(thermal_bridge_width 0.5)
			(island_removal_mode 0)
		)
		(polygon
			(pts
				(arc
					(start 86.745826 -131.572)
					(mid 84.967826 -131.572)
					(end 86.745826 -131.572)
				)
			)
		)
	)
	(zone
		(layers "In4.Cu" "In5.Cu")
		(hatch none 0.5)
		(connect_pads
			(clearance 0)
		)
		(min_thickness 0.25)
		(keepout
			(tracks not_allowed)
			(vias allowed)
			(pads allowed)
			(copperpour not_allowed)
			(footprints allowed)
		)
		(placement
			(enabled no)
			(sheetname "")
		)
		(fill yes
			(thermal_gap 0.5)
			(thermal_bridge_width 0.5)
			(island_removal_mode 0)
		)
		(polygon
			(pts
				(arc
					(start 141.097 -61.849)
					(mid 139.319 -61.849)
					(end 141.097 -61.849)
				)
			)
		)
	)
	(zone
		(layers "In4.Cu" "In5.Cu")
		(hatch none 0.5)
		(connect_pads
			(clearance 0)
		)
		(min_thickness 0.25)
		(keepout
			(tracks not_allowed)
			(vias allowed)
			(pads allowed)
			(copperpour not_allowed)
			(footprints allowed)
		)
		(placement
			(enabled no)
			(sheetname "")
		)
		(fill yes
			(thermal_gap 0.5)
			(thermal_bridge_width 0.5)
			(island_removal_mode 0)
		)
		(polygon
			(pts
				(arc
					(start 277.861522 -106.005122)
					(mid 276.083522 -106.005122)
					(end 277.861522 -106.005122)
				)
			)
		)
	)
	(zone
		(layers "In4.Cu" "In5.Cu")
		(hatch none 0.5)
		(connect_pads
			(clearance 0)
		)
		(min_thickness 0.25)
		(keepout
			(tracks not_allowed)
			(vias allowed)
			(pads allowed)
			(copperpour not_allowed)
			(footprints allowed)
		)
		(placement
			(enabled no)
			(sheetname "")
		)
		(fill yes
			(thermal_gap 0.5)
			(thermal_bridge_width 0.5)
			(island_removal_mode 0)
		)
		(polygon
			(pts
				(arc
					(start 110.113826 -112.84204)
					(mid 108.335826 -112.84204)
					(end 110.113826 -112.84204)
				)
			)
		)
	)
	(zone
		(layers "In4.Cu" "In5.Cu")
		(hatch none 0.5)
		(connect_pads
			(clearance 0)
		)
		(min_thickness 0.25)
		(keepout
			(tracks not_allowed)
			(vias allowed)
			(pads allowed)
			(copperpour not_allowed)
			(footprints allowed)
		)
		(placement
			(enabled no)
			(sheetname "")
		)
		(fill yes
			(thermal_gap 0.5)
			(thermal_bridge_width 0.5)
			(island_removal_mode 0)
		)
		(polygon
			(pts
				(arc
					(start 181.73446 -52.197)
					(mid 179.95646 -52.197)
					(end 181.73446 -52.197)
				)
			)
		)
	)
	(zone
		(layers "In4.Cu" "In5.Cu")
		(hatch none 0.5)
		(connect_pads
			(clearance 0)
		)
		(min_thickness 0.25)
		(keepout
			(tracks not_allowed)
			(vias allowed)
			(pads allowed)
			(copperpour not_allowed)
			(footprints allowed)
		)
		(placement
			(enabled no)
			(sheetname "")
		)
		(fill yes
			(thermal_gap 0.5)
			(thermal_bridge_width 0.5)
			(island_removal_mode 0)
		)
		(polygon
			(pts
				(arc
					(start 52.13604 -61.4934)
					(mid 50.35804 -61.4934)
					(end 52.13604 -61.4934)
				)
			)
		)
	)
	(zone
		(layers "In4.Cu" "In5.Cu")
		(hatch none 0.5)
		(connect_pads
			(clearance 0)
		)
		(min_thickness 0.25)
		(keepout
			(tracks not_allowed)
			(vias allowed)
			(pads allowed)
			(copperpour not_allowed)
			(footprints allowed)
		)
		(placement
			(enabled no)
			(sheetname "")
		)
		(fill yes
			(thermal_gap 0.5)
			(thermal_bridge_width 0.5)
			(island_removal_mode 0)
		)
		(polygon
			(pts
				(arc
					(start 114.49177 -86.446106)
					(mid 112.71377 -86.446106)
					(end 114.49177 -86.446106)
				)
			)
		)
	)
	(zone
		(layers "In4.Cu" "In5.Cu")
		(hatch none 0.5)
		(connect_pads
			(clearance 0)
		)
		(min_thickness 0.25)
		(keepout
			(tracks not_allowed)
			(vias allowed)
			(pads allowed)
			(copperpour not_allowed)
			(footprints allowed)
		)
		(placement
			(enabled no)
			(sheetname "")
		)
		(fill yes
			(thermal_gap 0.5)
			(thermal_bridge_width 0.5)
			(island_removal_mode 0)
		)
		(polygon
			(pts
				(arc
					(start 221.869 -79.448152)
					(mid 220.091 -79.448152)
					(end 221.869 -79.448152)
				)
			)
		)
	)
	(zone
		(layers "In4.Cu" "In5.Cu")
		(hatch none 0.5)
		(connect_pads
			(clearance 0)
		)
		(min_thickness 0.25)
		(keepout
			(tracks not_allowed)
			(vias allowed)
			(pads allowed)
			(copperpour not_allowed)
			(footprints allowed)
		)
		(placement
			(enabled no)
			(sheetname "")
		)
		(fill yes
			(thermal_gap 0.5)
			(thermal_bridge_width 0.5)
			(island_removal_mode 0)
		)
		(polygon
			(pts
				(arc
					(start 99.699826 -131.572)
					(mid 97.921826 -131.572)
					(end 99.699826 -131.572)
				)
			)
		)
	)
	(zone
		(layers "In4.Cu" "In5.Cu")
		(hatch none 0.5)
		(connect_pads
			(clearance 0)
		)
		(min_thickness 0.25)
		(keepout
			(tracks not_allowed)
			(vias allowed)
			(pads allowed)
			(copperpour not_allowed)
			(footprints allowed)
		)
		(placement
			(enabled no)
			(sheetname "")
		)
		(fill yes
			(thermal_gap 0.5)
			(thermal_bridge_width 0.5)
			(island_removal_mode 0)
		)
		(polygon
			(pts
				(arc
					(start 63.373 -60.579)
					(mid 61.595 -60.579)
					(end 63.373 -60.579)
				)
			)
		)
	)
	(zone
		(layers "In4.Cu" "In5.Cu")
		(hatch none 0.5)
		(connect_pads
			(clearance 0)
		)
		(min_thickness 0.25)
		(keepout
			(tracks not_allowed)
			(vias allowed)
			(pads allowed)
			(copperpour not_allowed)
			(footprints allowed)
		)
		(placement
			(enabled no)
			(sheetname "")
		)
		(fill yes
			(thermal_gap 0.5)
			(thermal_bridge_width 0.5)
			(island_removal_mode 0)
		)
		(polygon
			(pts
				(arc
					(start 121.05513 -86.446106)
					(mid 119.27713 -86.446106)
					(end 121.05513 -86.446106)
				)
			)
		)
	)
	(zone
		(layers "In4.Cu" "In5.Cu")
		(hatch none 0.5)
		(connect_pads
			(clearance 0)
		)
		(min_thickness 0.25)
		(keepout
			(tracks not_allowed)
			(vias allowed)
			(pads allowed)
			(copperpour not_allowed)
			(footprints allowed)
		)
		(placement
			(enabled no)
			(sheetname "")
		)
		(fill yes
			(thermal_gap 0.5)
			(thermal_bridge_width 0.5)
			(island_removal_mode 0)
		)
		(polygon
			(pts
				(arc
					(start 48.469296 -136.906)
					(mid 45.624496 -136.906)
					(end 48.469296 -136.906)
				)
			)
		)
	)
	(zone
		(layers "In4.Cu" "In5.Cu")
		(hatch none 0.5)
		(connect_pads
			(clearance 0)
		)
		(min_thickness 0.25)
		(keepout
			(tracks not_allowed)
			(vias allowed)
			(pads allowed)
			(copperpour not_allowed)
			(footprints allowed)
		)
		(placement
			(enabled no)
			(sheetname "")
		)
		(fill yes
			(thermal_gap 0.5)
			(thermal_bridge_width 0.5)
			(island_removal_mode 0)
		)
		(polygon
			(pts
				(arc
					(start 191.892174 -131.572)
					(mid 190.114174 -131.572)
					(end 191.892174 -131.572)
				)
			)
		)
	)
	(zone
		(layers "In4.Cu" "In5.Cu")
		(hatch none 0.5)
		(connect_pads
			(clearance 0)
		)
		(min_thickness 0.25)
		(keepout
			(tracks not_allowed)
			(vias allowed)
			(pads allowed)
			(copperpour not_allowed)
			(footprints allowed)
		)
		(placement
			(enabled no)
			(sheetname "")
		)
		(fill yes
			(thermal_gap 0.5)
			(thermal_bridge_width 0.5)
			(island_removal_mode 0)
		)
		(polygon
			(pts
				(arc
					(start 58.937906 -131.572)
					(mid 57.159906 -131.572)
					(end 58.937906 -131.572)
				)
			)
		)
	)
	(zone
		(layers "In4.Cu" "In5.Cu")
		(hatch none 0.5)
		(connect_pads
			(clearance 0)
		)
		(min_thickness 0.25)
		(keepout
			(tracks not_allowed)
			(vias allowed)
			(pads allowed)
			(copperpour not_allowed)
			(footprints allowed)
		)
		(placement
			(enabled no)
			(sheetname "")
		)
		(fill yes
			(thermal_gap 0.5)
			(thermal_bridge_width 0.5)
			(island_removal_mode 0)
		)
		(polygon
			(pts
				(arc
					(start 285.115 -48.133)
					(mid 283.337 -48.133)
					(end 285.115 -48.133)
				)
			)
		)
	)
	(zone
		(layers "In4.Cu" "In5.Cu")
		(hatch none 0.5)
		(connect_pads
			(clearance 0)
		)
		(min_thickness 0.25)
		(keepout
			(tracks not_allowed)
			(vias allowed)
			(pads allowed)
			(copperpour not_allowed)
			(footprints allowed)
		)
		(placement
			(enabled no)
			(sheetname "")
		)
		(fill yes
			(thermal_gap 0.5)
			(thermal_bridge_width 0.5)
			(island_removal_mode 0)
		)
		(polygon
			(pts
				(arc
					(start 280.289 -51.7398)
					(mid 278.511 -51.7398)
					(end 280.289 -51.7398)
				)
			)
		)
	)
	(zone
		(layers "In4.Cu" "In5.Cu")
		(hatch none 0.5)
		(connect_pads
			(clearance 0)
		)
		(min_thickness 0.25)
		(keepout
			(tracks not_allowed)
			(vias allowed)
			(pads allowed)
			(copperpour not_allowed)
			(footprints allowed)
		)
		(placement
			(enabled no)
			(sheetname "")
		)
		(fill yes
			(thermal_gap 0.5)
			(thermal_bridge_width 0.5)
			(island_removal_mode 0)
		)
		(polygon
			(pts
				(arc
					(start 230.632 -74.168)
					(mid 228.854 -74.168)
					(end 230.632 -74.168)
				)
			)
		)
	)
	(zone
		(layers "In4.Cu" "In5.Cu")
		(hatch none 0.5)
		(connect_pads
			(clearance 0)
		)
		(min_thickness 0.25)
		(keepout
			(tracks not_allowed)
			(vias allowed)
			(pads allowed)
			(copperpour not_allowed)
			(footprints allowed)
		)
		(placement
			(enabled no)
			(sheetname "")
		)
		(fill yes
			(thermal_gap 0.5)
			(thermal_bridge_width 0.5)
			(island_removal_mode 0)
		)
		(polygon
			(pts
				(arc
					(start 154.432 -50.292)
					(mid 152.654 -50.292)
					(end 154.432 -50.292)
				)
			)
		)
	)
	(zone
		(layers "In4.Cu" "In5.Cu")
		(hatch none 0.5)
		(connect_pads
			(clearance 0)
		)
		(min_thickness 0.25)
		(keepout
			(tracks not_allowed)
			(vias allowed)
			(pads allowed)
			(copperpour not_allowed)
			(footprints allowed)
		)
		(placement
			(enabled no)
			(sheetname "")
		)
		(fill yes
			(thermal_gap 0.5)
			(thermal_bridge_width 0.5)
			(island_removal_mode 0)
		)
		(polygon
			(pts
				(arc
					(start 44.757848 -56.454802)
					(mid 42.979848 -56.454802)
					(end 44.757848 -56.454802)
				)
			)
		)
	)
	(zone
		(layers "In4.Cu" "In5.Cu")
		(hatch none 0.5)
		(connect_pads
			(clearance 0)
		)
		(min_thickness 0.25)
		(keepout
			(tracks not_allowed)
			(vias allowed)
			(pads allowed)
			(copperpour not_allowed)
			(footprints allowed)
		)
		(placement
			(enabled no)
			(sheetname "")
		)
		(fill yes
			(thermal_gap 0.5)
			(thermal_bridge_width 0.5)
			(island_removal_mode 0)
		)
		(polygon
			(pts
				(arc
					(start 237.49 -92.964)
					(mid 235.712 -92.964)
					(end 237.49 -92.964)
				)
			)
		)
	)
	(zone
		(layers "In4.Cu" "In5.Cu")
		(hatch none 0.5)
		(connect_pads
			(clearance 0)
		)
		(min_thickness 0.25)
		(keepout
			(tracks not_allowed)
			(vias allowed)
			(pads allowed)
			(copperpour not_allowed)
			(footprints allowed)
		)
		(placement
			(enabled no)
			(sheetname "")
		)
		(fill yes
			(thermal_gap 0.5)
			(thermal_bridge_width 0.5)
			(island_removal_mode 0)
		)
		(polygon
			(pts
				(arc
					(start 170.815 -51.562)
					(mid 169.037 -51.562)
					(end 170.815 -51.562)
				)
			)
		)
	)
	(zone
		(layers "In4.Cu" "In5.Cu")
		(hatch none 0.5)
		(connect_pads
			(clearance 0)
		)
		(min_thickness 0.25)
		(keepout
			(tracks not_allowed)
			(vias allowed)
			(pads allowed)
			(copperpour not_allowed)
			(footprints allowed)
		)
		(placement
			(enabled no)
			(sheetname "")
		)
		(fill yes
			(thermal_gap 0.5)
			(thermal_bridge_width 0.5)
			(island_removal_mode 0)
		)
		(polygon
			(pts
				(arc
					(start 286.258 -47.498)
					(mid 284.48 -47.498)
					(end 286.258 -47.498)
				)
			)
		)
	)
	(zone
		(layers "In4.Cu" "In5.Cu")
		(hatch none 0.5)
		(connect_pads
			(clearance 0)
		)
		(min_thickness 0.25)
		(keepout
			(tracks not_allowed)
			(vias allowed)
			(pads allowed)
			(copperpour not_allowed)
			(footprints allowed)
		)
		(placement
			(enabled no)
			(sheetname "")
		)
		(fill yes
			(thermal_gap 0.5)
			(thermal_bridge_width 0.5)
			(island_removal_mode 0)
		)
		(polygon
			(pts
				(arc
					(start 233.299 -81.89595)
					(mid 231.521 -81.89595)
					(end 233.299 -81.89595)
				)
			)
		)
	)
	(zone
		(layers "In4.Cu" "In5.Cu")
		(hatch none 0.5)
		(connect_pads
			(clearance 0)
		)
		(min_thickness 0.25)
		(keepout
			(tracks not_allowed)
			(vias allowed)
			(pads allowed)
			(copperpour not_allowed)
			(footprints allowed)
		)
		(placement
			(enabled no)
			(sheetname "")
		)
		(fill yes
			(thermal_gap 0.5)
			(thermal_bridge_width 0.5)
			(island_removal_mode 0)
		)
		(polygon
			(pts
				(arc
					(start 95.869506 -36.787328)
					(mid 93.075506 -36.787328)
					(end 95.869506 -36.787328)
				)
			)
		)
	)
	(zone
		(layers "In4.Cu" "In5.Cu")
		(hatch none 0.5)
		(connect_pads
			(clearance 0)
		)
		(min_thickness 0.25)
		(keepout
			(tracks not_allowed)
			(vias allowed)
			(pads allowed)
			(copperpour not_allowed)
			(footprints allowed)
		)
		(placement
			(enabled no)
			(sheetname "")
		)
		(fill yes
			(thermal_gap 0.5)
			(thermal_bridge_width 0.5)
			(island_removal_mode 0)
		)
		(polygon
			(pts
				(arc
					(start 241.427 -76.82865)
					(mid 239.649 -76.82865)
					(end 241.427 -76.82865)
				)
			)
		)
	)
	(zone
		(layers "In4.Cu" "In5.Cu")
		(hatch none 0.5)
		(connect_pads
			(clearance 0)
		)
		(min_thickness 0.25)
		(keepout
			(tracks not_allowed)
			(vias allowed)
			(pads allowed)
			(copperpour not_allowed)
			(footprints allowed)
		)
		(placement
			(enabled no)
			(sheetname "")
		)
		(fill yes
			(thermal_gap 0.5)
			(thermal_bridge_width 0.5)
			(island_removal_mode 0)
		)
		(polygon
			(pts
				(arc
					(start 88.202008 -40.55999)
					(mid 85.408008 -40.55999)
					(end 88.202008 -40.55999)
				)
			)
		)
	)
	(zone
		(layers "In4.Cu" "In5.Cu")
		(hatch none 0.5)
		(connect_pads
			(clearance 0)
		)
		(min_thickness 0.25)
		(keepout
			(tracks not_allowed)
			(vias allowed)
			(pads allowed)
			(copperpour not_allowed)
			(footprints allowed)
		)
		(placement
			(enabled no)
			(sheetname "")
		)
		(fill yes
			(thermal_gap 0.5)
			(thermal_bridge_width 0.5)
			(island_removal_mode 0)
		)
		(polygon
			(pts
				(arc
					(start 287.655 -42.291)
					(mid 285.877 -42.291)
					(end 287.655 -42.291)
				)
			)
		)
	)
	(zone
		(layers "In4.Cu" "In5.Cu")
		(hatch none 0.5)
		(connect_pads
			(clearance 0)
		)
		(min_thickness 0.25)
		(keepout
			(tracks not_allowed)
			(vias allowed)
			(pads allowed)
			(copperpour not_allowed)
			(footprints allowed)
		)
		(placement
			(enabled no)
			(sheetname "")
		)
		(fill yes
			(thermal_gap 0.5)
			(thermal_bridge_width 0.5)
			(island_removal_mode 0)
		)
		(polygon
			(pts
				(arc
					(start 139.335002 -86.446106)
					(mid 137.557002 -86.446106)
					(end 139.335002 -86.446106)
				)
			)
		)
	)
	(zone
		(layers "In4.Cu" "In5.Cu")
		(hatch none 0.5)
		(connect_pads
			(clearance 0)
		)
		(min_thickness 0.25)
		(keepout
			(tracks not_allowed)
			(vias allowed)
			(pads allowed)
			(copperpour not_allowed)
			(footprints allowed)
		)
		(placement
			(enabled no)
			(sheetname "")
		)
		(fill yes
			(thermal_gap 0.5)
			(thermal_bridge_width 0.5)
			(island_removal_mode 0)
		)
		(polygon
			(pts
				(arc
					(start 191.892174 -126.492)
					(mid 190.114174 -126.492)
					(end 191.892174 -126.492)
				)
			)
		)
	)
	(zone
		(layers "In4.Cu" "In5.Cu")
		(hatch none 0.5)
		(connect_pads
			(clearance 0)
		)
		(min_thickness 0.25)
		(keepout
			(tracks not_allowed)
			(vias allowed)
			(pads allowed)
			(copperpour not_allowed)
			(footprints allowed)
		)
		(placement
			(enabled no)
			(sheetname "")
		)
		(fill yes
			(thermal_gap 0.5)
			(thermal_bridge_width 0.5)
			(island_removal_mode 0)
		)
		(polygon
			(pts
				(arc
					(start 102.108 -62.738)
					(mid 100.33 -62.738)
					(end 102.108 -62.738)
				)
			)
		)
	)
	(zone
		(layers "In4.Cu" "In5.Cu")
		(hatch none 0.5)
		(connect_pads
			(clearance 0)
		)
		(min_thickness 0.25)
		(keepout
			(tracks not_allowed)
			(vias allowed)
			(pads allowed)
			(copperpour not_allowed)
			(footprints allowed)
		)
		(placement
			(enabled no)
			(sheetname "")
		)
		(fill yes
			(thermal_gap 0.5)
			(thermal_bridge_width 0.5)
			(island_removal_mode 0)
		)
		(polygon
			(pts
				(arc
					(start 165.354 -52.197)
					(mid 163.576 -52.197)
					(end 165.354 -52.197)
				)
			)
		)
	)
	(zone
		(layers "In4.Cu" "In5.Cu")
		(hatch none 0.5)
		(connect_pads
			(clearance 0)
		)
		(min_thickness 0.25)
		(keepout
			(tracks not_allowed)
			(vias allowed)
			(pads allowed)
			(copperpour not_allowed)
			(footprints allowed)
		)
		(placement
			(enabled no)
			(sheetname "")
		)
		(fill yes
			(thermal_gap 0.5)
			(thermal_bridge_width 0.5)
			(island_removal_mode 0)
		)
		(polygon
			(pts
				(arc
					(start 80.536034 -86.500208)
					(mid 78.758034 -86.500208)
					(end 80.536034 -86.500208)
				)
			)
		)
	)
	(zone
		(layers "In4.Cu" "In5.Cu")
		(hatch none 0.5)
		(connect_pads
			(clearance 0)
		)
		(min_thickness 0.25)
		(keepout
			(tracks not_allowed)
			(vias allowed)
			(pads allowed)
			(copperpour not_allowed)
			(footprints allowed)
		)
		(placement
			(enabled no)
			(sheetname "")
		)
		(fill yes
			(thermal_gap 0.5)
			(thermal_bridge_width 0.5)
			(island_removal_mode 0)
		)
		(polygon
			(pts
				(arc
					(start 277.876 -95.631)
					(mid 276.098 -95.631)
					(end 277.876 -95.631)
				)
			)
		)
	)
	(zone
		(layers "In4.Cu" "In5.Cu")
		(hatch none 0.5)
		(connect_pads
			(clearance 0)
		)
		(min_thickness 0.25)
		(keepout
			(tracks not_allowed)
			(vias allowed)
			(pads allowed)
			(copperpour not_allowed)
			(footprints allowed)
		)
		(placement
			(enabled no)
			(sheetname "")
		)
		(fill yes
			(thermal_gap 0.5)
			(thermal_bridge_width 0.5)
			(island_removal_mode 0)
		)
		(polygon
			(pts
				(arc
					(start 127.508 -126.492)
					(mid 125.73 -126.492)
					(end 127.508 -126.492)
				)
			)
		)
	)
	(zone
		(layers "In4.Cu" "In5.Cu")
		(hatch none 0.5)
		(connect_pads
			(clearance 0)
		)
		(min_thickness 0.25)
		(keepout
			(tracks not_allowed)
			(vias allowed)
			(pads allowed)
			(copperpour not_allowed)
			(footprints allowed)
		)
		(placement
			(enabled no)
			(sheetname "")
		)
		(fill yes
			(thermal_gap 0.5)
			(thermal_bridge_width 0.5)
			(island_removal_mode 0)
		)
		(polygon
			(pts
				(arc
					(start 239.018064 -76.21905)
					(mid 237.240064 -76.21905)
					(end 239.018064 -76.21905)
				)
			)
		)
	)
	(zone
		(layers "In4.Cu" "In5.Cu")
		(hatch none 0.5)
		(connect_pads
			(clearance 0)
		)
		(min_thickness 0.25)
		(keepout
			(tracks not_allowed)
			(vias allowed)
			(pads allowed)
			(copperpour not_allowed)
			(footprints allowed)
		)
		(placement
			(enabled no)
			(sheetname "")
		)
		(fill yes
			(thermal_gap 0.5)
			(thermal_bridge_width 0.5)
			(island_removal_mode 0)
		)
		(polygon
			(pts
				(arc
					(start 109.093 -52.324)
					(mid 107.315 -52.324)
					(end 109.093 -52.324)
				)
			)
		)
	)
	(zone
		(layers "In4.Cu" "In5.Cu")
		(hatch none 0.5)
		(connect_pads
			(clearance 0)
		)
		(min_thickness 0.25)
		(keepout
			(tracks not_allowed)
			(vias allowed)
			(pads allowed)
			(copperpour not_allowed)
			(footprints allowed)
		)
		(placement
			(enabled no)
			(sheetname "")
		)
		(fill yes
			(thermal_gap 0.5)
			(thermal_bridge_width 0.5)
			(island_removal_mode 0)
		)
		(polygon
			(pts
				(arc
					(start 74.73188 -86.445852)
					(mid 72.95388 -86.445852)
					(end 74.73188 -86.445852)
				)
			)
		)
	)
	(zone
		(layers "In4.Cu" "In5.Cu")
		(hatch none 0.5)
		(connect_pads
			(clearance 0)
		)
		(min_thickness 0.25)
		(keepout
			(tracks not_allowed)
			(vias allowed)
			(pads allowed)
			(copperpour not_allowed)
			(footprints allowed)
		)
		(placement
			(enabled no)
			(sheetname "")
		)
		(fill yes
			(thermal_gap 0.5)
			(thermal_bridge_width 0.5)
			(island_removal_mode 0)
		)
		(polygon
			(pts
				(arc
					(start 76.327 -52.324)
					(mid 74.549 -52.324)
					(end 76.327 -52.324)
				)
			)
		)
	)
	(zone
		(layers "In4.Cu" "In5.Cu")
		(hatch none 0.5)
		(connect_pads
			(clearance 0)
		)
		(min_thickness 0.25)
		(keepout
			(tracks not_allowed)
			(vias allowed)
			(pads allowed)
			(copperpour not_allowed)
			(footprints allowed)
		)
		(placement
			(enabled no)
			(sheetname "")
		)
		(fill yes
			(thermal_gap 0.5)
			(thermal_bridge_width 0.5)
			(island_removal_mode 0)
		)
		(polygon
			(pts
				(arc
					(start 165.354 -50.292)
					(mid 163.576 -50.292)
					(end 165.354 -50.292)
				)
			)
		)
	)
	(zone
		(layers "In4.Cu" "In5.Cu")
		(hatch none 0.5)
		(connect_pads
			(clearance 0)
		)
		(min_thickness 0.25)
		(keepout
			(tracks not_allowed)
			(vias allowed)
			(pads allowed)
			(copperpour not_allowed)
			(footprints allowed)
		)
		(placement
			(enabled no)
			(sheetname "")
		)
		(fill yes
			(thermal_gap 0.5)
			(thermal_bridge_width 0.5)
			(island_removal_mode 0)
		)
		(polygon
			(pts
				(arc
					(start 181.097174 -61.849)
					(mid 179.319174 -61.849)
					(end 181.097174 -61.849)
				)
			)
		)
	)
	(zone
		(layers "In4.Cu" "In5.Cu")
		(hatch none 0.5)
		(connect_pads
			(clearance 0)
		)
		(min_thickness 0.25)
		(keepout
			(tracks not_allowed)
			(vias allowed)
			(pads allowed)
			(copperpour not_allowed)
			(footprints allowed)
		)
		(placement
			(enabled no)
			(sheetname "")
		)
		(fill yes
			(thermal_gap 0.5)
			(thermal_bridge_width 0.5)
			(island_removal_mode 0)
		)
		(polygon
			(pts
				(arc
					(start 102.997 -59.69)
					(mid 101.219 -59.69)
					(end 102.997 -59.69)
				)
			)
		)
	)
	(zone
		(layers "In4.Cu" "In5.Cu")
		(hatch none 0.5)
		(connect_pads
			(clearance 0)
		)
		(min_thickness 0.25)
		(keepout
			(tracks not_allowed)
			(vias allowed)
			(pads allowed)
			(copperpour not_allowed)
			(footprints allowed)
		)
		(placement
			(enabled no)
			(sheetname "")
		)
		(fill yes
			(thermal_gap 0.5)
			(thermal_bridge_width 0.5)
			(island_removal_mode 0)
		)
		(polygon
			(pts
				(arc
					(start 240.665 -92.964)
					(mid 238.887 -92.964)
					(end 240.665 -92.964)
				)
			)
		)
	)
	(zone
		(layers "In4.Cu" "In5.Cu")
		(hatch none 0.5)
		(connect_pads
			(clearance 0)
		)
		(min_thickness 0.25)
		(keepout
			(tracks not_allowed)
			(vias allowed)
			(pads allowed)
			(copperpour not_allowed)
			(footprints allowed)
		)
		(placement
			(enabled no)
			(sheetname "")
		)
		(fill yes
			(thermal_gap 0.5)
			(thermal_bridge_width 0.5)
			(island_removal_mode 0)
		)
		(polygon
			(pts
				(arc
					(start 223.139 -88.207342)
					(mid 221.361 -88.207342)
					(end 223.139 -88.207342)
				)
			)
		)
	)
	(zone
		(layers "In4.Cu" "In5.Cu")
		(hatch none 0.5)
		(connect_pads
			(clearance 0)
		)
		(min_thickness 0.25)
		(keepout
			(tracks not_allowed)
			(vias allowed)
			(pads allowed)
			(copperpour not_allowed)
			(footprints allowed)
		)
		(placement
			(enabled no)
			(sheetname "")
		)
		(fill yes
			(thermal_gap 0.5)
			(thermal_bridge_width 0.5)
			(island_removal_mode 0)
		)
		(polygon
			(pts
				(arc
					(start 237.871 -74.542904)
					(mid 236.093 -74.542904)
					(end 237.871 -74.542904)
				)
			)
		)
	)
	(zone
		(layers "In4.Cu" "In5.Cu")
		(hatch none 0.5)
		(connect_pads
			(clearance 0)
		)
		(min_thickness 0.25)
		(keepout
			(tracks not_allowed)
			(vias allowed)
			(pads allowed)
			(copperpour not_allowed)
			(footprints allowed)
		)
		(placement
			(enabled no)
			(sheetname "")
		)
		(fill yes
			(thermal_gap 0.5)
			(thermal_bridge_width 0.5)
			(island_removal_mode 0)
		)
		(polygon
			(pts
				(arc
					(start 59.699906 -131.572)
					(mid 57.921906 -131.572)
					(end 59.699906 -131.572)
				)
			)
		)
	)
	(zone
		(layers "In4.Cu" "In5.Cu")
		(hatch none 0.5)
		(connect_pads
			(clearance 0)
		)
		(min_thickness 0.25)
		(keepout
			(tracks not_allowed)
			(vias allowed)
			(pads allowed)
			(copperpour not_allowed)
			(footprints allowed)
		)
		(placement
			(enabled no)
			(sheetname "")
		)
		(fill yes
			(thermal_gap 0.5)
			(thermal_bridge_width 0.5)
			(island_removal_mode 0)
		)
		(polygon
			(pts
				(arc
					(start 220.726 -92.964)
					(mid 218.948 -92.964)
					(end 220.726 -92.964)
				)
			)
		)
	)
	(zone
		(layers "In4.Cu" "In5.Cu")
		(hatch none 0.5)
		(connect_pads
			(clearance 0)
		)
		(min_thickness 0.25)
		(keepout
			(tracks not_allowed)
			(vias allowed)
			(pads allowed)
			(copperpour not_allowed)
			(footprints allowed)
		)
		(placement
			(enabled no)
			(sheetname "")
		)
		(fill yes
			(thermal_gap 0.5)
			(thermal_bridge_width 0.5)
			(island_removal_mode 0)
		)
		(polygon
			(pts
				(arc
					(start 230.998014 -81.372964)
					(mid 229.220014 -81.372964)
					(end 230.998014 -81.372964)
				)
			)
		)
	)
	(zone
		(layers "In4.Cu" "In5.Cu")
		(hatch none 0.5)
		(connect_pads
			(clearance 0)
		)
		(min_thickness 0.25)
		(keepout
			(tracks not_allowed)
			(vias allowed)
			(pads allowed)
			(copperpour not_allowed)
			(footprints allowed)
		)
		(placement
			(enabled no)
			(sheetname "")
		)
		(fill yes
			(thermal_gap 0.5)
			(thermal_bridge_width 0.5)
			(island_removal_mode 0)
		)
		(polygon
			(pts
				(arc
					(start 287.94075 -34.52876)
					(mid 286.16275 -34.52876)
					(end 287.94075 -34.52876)
				)
			)
		)
	)
	(zone
		(layers "In4.Cu" "In5.Cu")
		(hatch none 0.5)
		(connect_pads
			(clearance 0)
		)
		(min_thickness 0.25)
		(keepout
			(tracks not_allowed)
			(vias allowed)
			(pads allowed)
			(copperpour not_allowed)
			(footprints allowed)
		)
		(placement
			(enabled no)
			(sheetname "")
		)
		(fill yes
			(thermal_gap 0.5)
			(thermal_bridge_width 0.5)
			(island_removal_mode 0)
		)
		(polygon
			(pts
				(arc
					(start 151.892 -126.492)
					(mid 150.114 -126.492)
					(end 151.892 -126.492)
				)
			)
		)
	)
	(zone
		(layers "In4.Cu" "In5.Cu")
		(hatch none 0.5)
		(connect_pads
			(clearance 0)
		)
		(min_thickness 0.25)
		(keepout
			(tracks not_allowed)
			(vias allowed)
			(pads allowed)
			(copperpour not_allowed)
			(footprints allowed)
		)
		(placement
			(enabled no)
			(sheetname "")
		)
		(fill yes
			(thermal_gap 0.5)
			(thermal_bridge_width 0.5)
			(island_removal_mode 0)
		)
		(polygon
			(pts
				(arc
					(start 121.412 -55.96001)
					(mid 118.618 -55.96001)
					(end 121.412 -55.96001)
				)
			)
		)
	)
	(zone
		(layers "In4.Cu" "In5.Cu")
		(hatch none 0.5)
		(connect_pads
			(clearance 0)
		)
		(min_thickness 0.25)
		(keepout
			(tracks not_allowed)
			(vias allowed)
			(pads allowed)
			(copperpour not_allowed)
			(footprints allowed)
		)
		(placement
			(enabled no)
			(sheetname "")
		)
		(fill yes
			(thermal_gap 0.5)
			(thermal_bridge_width 0.5)
			(island_removal_mode 0)
		)
		(polygon
			(pts
				(arc
					(start 44.89831 -86.500208)
					(mid 43.12031 -86.500208)
					(end 44.89831 -86.500208)
				)
			)
		)
	)
	(zone
		(layers "In4.Cu" "In5.Cu")
		(hatch none 0.5)
		(connect_pads
			(clearance 0)
		)
		(min_thickness 0.25)
		(keepout
			(tracks not_allowed)
			(vias allowed)
			(pads allowed)
			(copperpour not_allowed)
			(footprints allowed)
		)
		(placement
			(enabled no)
			(sheetname "")
		)
		(fill yes
			(thermal_gap 0.5)
			(thermal_bridge_width 0.5)
			(island_removal_mode 0)
		)
		(polygon
			(pts
				(arc
					(start 126.746 -131.572)
					(mid 124.968 -131.572)
					(end 126.746 -131.572)
				)
			)
		)
	)
	(zone
		(layers "In4.Cu" "In5.Cu")
		(hatch none 0.5)
		(connect_pads
			(clearance 0)
		)
		(min_thickness 0.25)
		(keepout
			(tracks not_allowed)
			(vias allowed)
			(pads allowed)
			(copperpour not_allowed)
			(footprints allowed)
		)
		(placement
			(enabled no)
			(sheetname "")
		)
		(fill yes
			(thermal_gap 0.5)
			(thermal_bridge_width 0.5)
			(island_removal_mode 0)
		)
		(polygon
			(pts
				(arc
					(start 275.082 -46.88205)
					(mid 273.304 -46.88205)
					(end 275.082 -46.88205)
				)
			)
		)
	)
	(zone
		(layers "In4.Cu" "In5.Cu")
		(hatch none 0.5)
		(connect_pads
			(clearance 0)
		)
		(min_thickness 0.25)
		(keepout
			(tracks not_allowed)
			(vias allowed)
			(pads allowed)
			(copperpour not_allowed)
			(footprints allowed)
		)
		(placement
			(enabled no)
			(sheetname "")
		)
		(fill yes
			(thermal_gap 0.5)
			(thermal_bridge_width 0.5)
			(island_removal_mode 0)
		)
		(polygon
			(pts
				(arc
					(start 240.63579 -89.50579)
					(mid 238.85779 -89.50579)
					(end 240.63579 -89.50579)
				)
			)
		)
	)
	(zone
		(layers "In4.Cu" "In5.Cu")
		(hatch none 0.5)
		(connect_pads
			(clearance 0)
		)
		(min_thickness 0.25)
		(keepout
			(tracks not_allowed)
			(vias allowed)
			(pads allowed)
			(copperpour not_allowed)
			(footprints allowed)
		)
		(placement
			(enabled no)
			(sheetname "")
		)
		(fill yes
			(thermal_gap 0.5)
			(thermal_bridge_width 0.5)
			(island_removal_mode 0)
		)
		(polygon
			(pts
				(arc
					(start 178.666394 -121.209816)
					(mid 175.034194 -121.209816)
					(end 178.666394 -121.209816)
				)
			)
		)
	)
	(zone
		(layers "In4.Cu" "In5.Cu")
		(hatch none 0.5)
		(connect_pads
			(clearance 0)
		)
		(min_thickness 0.25)
		(keepout
			(tracks not_allowed)
			(vias allowed)
			(pads allowed)
			(copperpour not_allowed)
			(footprints allowed)
		)
		(placement
			(enabled no)
			(sheetname "")
		)
		(fill yes
			(thermal_gap 0.5)
			(thermal_bridge_width 0.5)
			(island_removal_mode 0)
		)
		(polygon
			(pts
				(arc
					(start 150.622 -113.411)
					(mid 148.844 -113.411)
					(end 150.622 -113.411)
				)
			)
		)
	)
	(zone
		(layers "In4.Cu" "In5.Cu")
		(hatch none 0.5)
		(connect_pads
			(clearance 0)
		)
		(min_thickness 0.25)
		(keepout
			(tracks not_allowed)
			(vias allowed)
			(pads allowed)
			(copperpour not_allowed)
			(footprints allowed)
		)
		(placement
			(enabled no)
			(sheetname "")
		)
		(fill yes
			(thermal_gap 0.5)
			(thermal_bridge_width 0.5)
			(island_removal_mode 0)
		)
		(polygon
			(pts
				(arc
					(start 236.347 -91.71305)
					(mid 234.569 -91.71305)
					(end 236.347 -91.71305)
				)
			)
		)
	)
	(zone
		(layers "In4.Cu" "In5.Cu")
		(hatch none 0.5)
		(connect_pads
			(clearance 0)
		)
		(min_thickness 0.25)
		(keepout
			(tracks not_allowed)
			(vias allowed)
			(pads allowed)
			(copperpour not_allowed)
			(footprints allowed)
		)
		(placement
			(enabled no)
			(sheetname "")
		)
		(fill yes
			(thermal_gap 0.5)
			(thermal_bridge_width 0.5)
			(island_removal_mode 0)
		)
		(polygon
			(pts
				(arc
					(start 283.684472 -43.591226)
					(mid 281.906472 -43.591226)
					(end 283.684472 -43.591226)
				)
			)
		)
	)
	(zone
		(layers "In4.Cu" "In5.Cu")
		(hatch none 0.5)
		(connect_pads
			(clearance 0)
		)
		(min_thickness 0.25)
		(keepout
			(tracks not_allowed)
			(vias allowed)
			(pads allowed)
			(copperpour not_allowed)
			(footprints allowed)
		)
		(placement
			(enabled no)
			(sheetname "")
		)
		(fill yes
			(thermal_gap 0.5)
			(thermal_bridge_width 0.5)
			(island_removal_mode 0)
		)
		(polygon
			(pts
				(arc
					(start 235.51896 -87.757)
					(mid 233.74096 -87.757)
					(end 235.51896 -87.757)
				)
			)
		)
	)
	(zone
		(layers "In4.Cu" "In5.Cu")
		(hatch none 0.5)
		(connect_pads
			(clearance 0)
		)
		(min_thickness 0.25)
		(keepout
			(tracks not_allowed)
			(vias allowed)
			(pads allowed)
			(copperpour not_allowed)
			(footprints allowed)
		)
		(placement
			(enabled no)
			(sheetname "")
		)
		(fill yes
			(thermal_gap 0.5)
			(thermal_bridge_width 0.5)
			(island_removal_mode 0)
		)
		(polygon
			(pts
				(arc
					(start 87.507826 -126.492)
					(mid 85.729826 -126.492)
					(end 87.507826 -126.492)
				)
			)
		)
	)
	(zone
		(layers "In4.Cu" "In5.Cu")
		(hatch none 0.5)
		(connect_pads
			(clearance 0)
		)
		(min_thickness 0.25)
		(keepout
			(tracks not_allowed)
			(vias allowed)
			(pads allowed)
			(copperpour not_allowed)
			(footprints allowed)
		)
		(placement
			(enabled no)
			(sheetname "")
		)
		(fill yes
			(thermal_gap 0.5)
			(thermal_bridge_width 0.5)
			(island_removal_mode 0)
		)
		(polygon
			(pts
				(arc
					(start 102.997 -60.452)
					(mid 101.219 -60.452)
					(end 102.997 -60.452)
				)
			)
		)
	)
	(zone
		(layers "In4.Cu" "In5.Cu")
		(hatch none 0.5)
		(connect_pads
			(clearance 0)
		)
		(min_thickness 0.25)
		(keepout
			(tracks not_allowed)
			(vias allowed)
			(pads allowed)
			(copperpour not_allowed)
			(footprints allowed)
		)
		(placement
			(enabled no)
			(sheetname "")
		)
		(fill yes
			(thermal_gap 0.5)
			(thermal_bridge_width 0.5)
			(island_removal_mode 0)
		)
		(polygon
			(pts
				(arc
					(start 79.312008 -35.47999)
					(mid 76.518008 -35.47999)
					(end 79.312008 -35.47999)
				)
			)
		)
	)
	(zone
		(layers "In4.Cu" "In5.Cu")
		(hatch none 0.5)
		(connect_pads
			(clearance 0)
		)
		(min_thickness 0.25)
		(keepout
			(tracks not_allowed)
			(vias allowed)
			(pads allowed)
			(copperpour not_allowed)
			(footprints allowed)
		)
		(placement
			(enabled no)
			(sheetname "")
		)
		(fill yes
			(thermal_gap 0.5)
			(thermal_bridge_width 0.5)
			(island_removal_mode 0)
		)
		(polygon
			(pts
				(arc
					(start 140.462 -113.036096)
					(mid 138.684 -113.036096)
					(end 140.462 -113.036096)
				)
			)
		)
	)
	(zone
		(layers "In4.Cu" "In5.Cu")
		(hatch none 0.5)
		(connect_pads
			(clearance 0)
		)
		(min_thickness 0.25)
		(keepout
			(tracks not_allowed)
			(vias allowed)
			(pads allowed)
			(copperpour not_allowed)
			(footprints allowed)
		)
		(placement
			(enabled no)
			(sheetname "")
		)
		(fill yes
			(thermal_gap 0.5)
			(thermal_bridge_width 0.5)
			(island_removal_mode 0)
		)
		(polygon
			(pts
				(arc
					(start 141.986 -59.944)
					(mid 140.208 -59.944)
					(end 141.986 -59.944)
				)
			)
		)
	)
	(zone
		(layers "In4.Cu" "In5.Cu")
		(hatch none 0.5)
		(connect_pads
			(clearance 0)
		)
		(min_thickness 0.25)
		(keepout
			(tracks not_allowed)
			(vias allowed)
			(pads allowed)
			(copperpour not_allowed)
			(footprints allowed)
		)
		(placement
			(enabled no)
			(sheetname "")
		)
		(fill yes
			(thermal_gap 0.5)
			(thermal_bridge_width 0.5)
			(island_removal_mode 0)
		)
		(polygon
			(pts
				(arc
					(start 150.114 -112.84204)
					(mid 148.336 -112.84204)
					(end 150.114 -112.84204)
				)
			)
		)
	)
	(zone
		(layers "In4.Cu" "In5.Cu")
		(hatch none 0.5)
		(connect_pads
			(clearance 0)
		)
		(min_thickness 0.25)
		(keepout
			(tracks not_allowed)
			(vias allowed)
			(pads allowed)
			(copperpour not_allowed)
			(footprints allowed)
		)
		(placement
			(enabled no)
			(sheetname "")
		)
		(fill yes
			(thermal_gap 0.5)
			(thermal_bridge_width 0.5)
			(island_removal_mode 0)
		)
		(polygon
			(pts
				(arc
					(start 94.552008 -35.47999)
					(mid 91.758008 -35.47999)
					(end 94.552008 -35.47999)
				)
			)
		)
	)
	(zone
		(layers "In4.Cu" "In5.Cu")
		(hatch none 0.5)
		(connect_pads
			(clearance 0)
		)
		(min_thickness 0.25)
		(keepout
			(tracks not_allowed)
			(vias allowed)
			(pads allowed)
			(copperpour not_allowed)
			(footprints allowed)
		)
		(placement
			(enabled no)
			(sheetname "")
		)
		(fill yes
			(thermal_gap 0.5)
			(thermal_bridge_width 0.5)
			(island_removal_mode 0)
		)
		(polygon
			(pts
				(arc
					(start 203.543916 -65.922906)
					(mid 201.765916 -65.922906)
					(end 203.543916 -65.922906)
				)
			)
		)
	)
	(zone
		(layers "In4.Cu" "In5.Cu")
		(hatch none 0.5)
		(connect_pads
			(clearance 0)
		)
		(min_thickness 0.25)
		(keepout
			(tracks not_allowed)
			(vias allowed)
			(pads allowed)
			(copperpour not_allowed)
			(footprints allowed)
		)
		(placement
			(enabled no)
			(sheetname "")
		)
		(fill yes
			(thermal_gap 0.5)
			(thermal_bridge_width 0.5)
			(island_removal_mode 0)
		)
		(polygon
			(pts
				(arc
					(start 166.746174 -126.492)
					(mid 164.968174 -126.492)
					(end 166.746174 -126.492)
				)
			)
		)
	)
	(zone
		(layers "In4.Cu" "In5.Cu")
		(hatch none 0.5)
		(connect_pads
			(clearance 0)
		)
		(min_thickness 0.25)
		(keepout
			(tracks not_allowed)
			(vias allowed)
			(pads allowed)
			(copperpour not_allowed)
			(footprints allowed)
		)
		(placement
			(enabled no)
			(sheetname "")
		)
		(fill yes
			(thermal_gap 0.5)
			(thermal_bridge_width 0.5)
			(island_removal_mode 0)
		)
		(polygon
			(pts
				(arc
					(start 103.632 -49.784)
					(mid 101.854 -49.784)
					(end 103.632 -49.784)
				)
			)
		)
	)
	(zone
		(layers "In4.Cu" "In5.Cu")
		(hatch none 0.5)
		(connect_pads
			(clearance 0)
		)
		(min_thickness 0.25)
		(keepout
			(tracks not_allowed)
			(vias allowed)
			(pads allowed)
			(copperpour not_allowed)
			(footprints allowed)
		)
		(placement
			(enabled no)
			(sheetname "")
		)
		(fill yes
			(thermal_gap 0.5)
			(thermal_bridge_width 0.5)
			(island_removal_mode 0)
		)
		(polygon
			(pts
				(arc
					(start 62.484 -62.865)
					(mid 60.706 -62.865)
					(end 62.484 -62.865)
				)
			)
		)
	)
	(zone
		(layers "In4.Cu" "In5.Cu")
		(hatch none 0.5)
		(connect_pads
			(clearance 0)
		)
		(min_thickness 0.25)
		(keepout
			(tracks not_allowed)
			(vias allowed)
			(pads allowed)
			(copperpour not_allowed)
			(footprints allowed)
		)
		(placement
			(enabled no)
			(sheetname "")
		)
		(fill yes
			(thermal_gap 0.5)
			(thermal_bridge_width 0.5)
			(island_removal_mode 0)
		)
		(polygon
			(pts
				(arc
					(start 98.171 -52.324)
					(mid 96.393 -52.324)
					(end 98.171 -52.324)
				)
			)
		)
	)
	(zone
		(layers "In4.Cu" "In5.Cu")
		(hatch none 0.5)
		(connect_pads
			(clearance 0)
		)
		(min_thickness 0.25)
		(keepout
			(tracks not_allowed)
			(vias allowed)
			(pads allowed)
			(copperpour not_allowed)
			(footprints allowed)
		)
		(placement
			(enabled no)
			(sheetname "")
		)
		(fill yes
			(thermal_gap 0.5)
			(thermal_bridge_width 0.5)
			(island_removal_mode 0)
		)
		(polygon
			(pts
				(arc
					(start 46.745906 -131.572)
					(mid 44.967906 -131.572)
					(end 46.745906 -131.572)
				)
			)
		)
	)
	(zone
		(layers "In4.Cu" "In5.Cu")
		(hatch none 0.5)
		(connect_pads
			(clearance 0)
		)
		(min_thickness 0.25)
		(keepout
			(tracks not_allowed)
			(vias allowed)
			(pads allowed)
			(copperpour not_allowed)
			(footprints allowed)
		)
		(placement
			(enabled no)
			(sheetname "")
		)
		(fill yes
			(thermal_gap 0.5)
			(thermal_bridge_width 0.5)
			(island_removal_mode 0)
		)
		(polygon
			(pts
				(arc
					(start 224.409 -77.34935)
					(mid 222.631 -77.34935)
					(end 224.409 -77.34935)
				)
			)
		)
	)
	(zone
		(layers "In4.Cu" "In5.Cu")
		(hatch none 0.5)
		(connect_pads
			(clearance 0)
		)
		(min_thickness 0.25)
		(keepout
			(tracks not_allowed)
			(vias allowed)
			(pads allowed)
			(copperpour not_allowed)
			(footprints allowed)
		)
		(placement
			(enabled no)
			(sheetname "")
		)
		(fill yes
			(thermal_gap 0.5)
			(thermal_bridge_width 0.5)
			(island_removal_mode 0)
		)
		(polygon
			(pts
				(arc
					(start 86.745826 -126.492)
					(mid 84.967826 -126.492)
					(end 86.745826 -126.492)
				)
			)
		)
	)
	(zone
		(layers "In4.Cu" "In5.Cu")
		(hatch none 0.5)
		(connect_pads
			(clearance 0)
		)
		(min_thickness 0.25)
		(keepout
			(tracks not_allowed)
			(vias allowed)
			(pads allowed)
			(copperpour not_allowed)
			(footprints allowed)
		)
		(placement
			(enabled no)
			(sheetname "")
		)
		(fill yes
			(thermal_gap 0.5)
			(thermal_bridge_width 0.5)
			(island_removal_mode 0)
		)
		(polygon
			(pts
				(arc
					(start 76.772008 -40.55999)
					(mid 73.978008 -40.55999)
					(end 76.772008 -40.55999)
				)
			)
		)
	)
	(zone
		(layers "In4.Cu" "In5.Cu")
		(hatch none 0.5)
		(connect_pads
			(clearance 0)
		)
		(min_thickness 0.25)
		(keepout
			(tracks not_allowed)
			(vias allowed)
			(pads allowed)
			(copperpour not_allowed)
			(footprints allowed)
		)
		(placement
			(enabled no)
			(sheetname "")
		)
		(fill yes
			(thermal_gap 0.5)
			(thermal_bridge_width 0.5)
			(island_removal_mode 0)
		)
		(polygon
			(pts
				(arc
					(start 148.336 -55.96001)
					(mid 145.542 -55.96001)
					(end 148.336 -55.96001)
				)
			)
		)
	)
	(zone
		(layers "In4.Cu" "In5.Cu")
		(hatch none 0.5)
		(connect_pads
			(clearance 0)
		)
		(min_thickness 0.25)
		(keepout
			(tracks not_allowed)
			(vias allowed)
			(pads allowed)
			(copperpour not_allowed)
			(footprints allowed)
		)
		(placement
			(enabled no)
			(sheetname "")
		)
		(fill yes
			(thermal_gap 0.5)
			(thermal_bridge_width 0.5)
			(island_removal_mode 0)
		)
		(polygon
			(pts
				(arc
					(start 230.759 -72.00265)
					(mid 228.981 -72.00265)
					(end 230.759 -72.00265)
				)
			)
		)
	)
	(zone
		(layers "In4.Cu" "In5.Cu")
		(hatch none 0.5)
		(connect_pads
			(clearance 0)
		)
		(min_thickness 0.25)
		(keepout
			(tracks not_allowed)
			(vias allowed)
			(pads allowed)
			(copperpour not_allowed)
			(footprints allowed)
		)
		(placement
			(enabled no)
			(sheetname "")
		)
		(fill yes
			(thermal_gap 0.5)
			(thermal_bridge_width 0.5)
			(island_removal_mode 0)
		)
		(polygon
			(pts
				(arc
					(start 232.537 -84.43595)
					(mid 230.759 -84.43595)
					(end 232.537 -84.43595)
				)
			)
		)
	)
	(zone
		(layers "In4.Cu" "In5.Cu")
		(hatch none 0.5)
		(connect_pads
			(clearance 0)
		)
		(min_thickness 0.25)
		(keepout
			(tracks not_allowed)
			(vias allowed)
			(pads allowed)
			(copperpour not_allowed)
			(footprints allowed)
		)
		(placement
			(enabled no)
			(sheetname "")
		)
		(fill yes
			(thermal_gap 0.5)
			(thermal_bridge_width 0.5)
			(island_removal_mode 0)
		)
		(polygon
			(pts
				(arc
					(start 225.425 -72.00265)
					(mid 223.647 -72.00265)
					(end 225.425 -72.00265)
				)
			)
		)
	)
	(zone
		(layers "In4.Cu" "In5.Cu")
		(hatch none 0.5)
		(connect_pads
			(clearance 0)
		)
		(min_thickness 0.25)
		(keepout
			(tracks not_allowed)
			(vias allowed)
			(pads allowed)
			(copperpour not_allowed)
			(footprints allowed)
		)
		(placement
			(enabled no)
			(sheetname "")
		)
		(fill yes
			(thermal_gap 0.5)
			(thermal_bridge_width 0.5)
			(island_removal_mode 0)
		)
		(polygon
			(pts
				(arc
					(start 285.4198 -42.291)
					(mid 283.6418 -42.291)
					(end 285.4198 -42.291)
				)
			)
		)
	)
	(zone
		(layers "In4.Cu" "In5.Cu")
		(hatch none 0.5)
		(connect_pads
			(clearance 0)
		)
		(min_thickness 0.25)
		(keepout
			(tracks not_allowed)
			(vias allowed)
			(pads allowed)
			(copperpour not_allowed)
			(footprints allowed)
		)
		(placement
			(enabled no)
			(sheetname "")
		)
		(fill yes
			(thermal_gap 0.5)
			(thermal_bridge_width 0.5)
			(island_removal_mode 0)
		)
		(polygon
			(pts
				(arc
					(start 103.632 -50.419)
					(mid 101.854 -50.419)
					(end 103.632 -50.419)
				)
			)
		)
	)
	(zone
		(layers "In4.Cu" "In5.Cu")
		(hatch none 0.5)
		(connect_pads
			(clearance 0)
		)
		(min_thickness 0.25)
		(keepout
			(tracks not_allowed)
			(vias allowed)
			(pads allowed)
			(copperpour not_allowed)
			(footprints allowed)
		)
		(placement
			(enabled no)
			(sheetname "")
		)
		(fill yes
			(thermal_gap 0.5)
			(thermal_bridge_width 0.5)
			(island_removal_mode 0)
		)
		(polygon
			(pts
				(arc
					(start 231.013 -92.964)
					(mid 229.235 -92.964)
					(end 231.013 -92.964)
				)
			)
		)
	)
	(zone
		(layers "In4.Cu" "In5.Cu")
		(hatch none 0.5)
		(connect_pads
			(clearance 0)
		)
		(min_thickness 0.25)
		(keepout
			(tracks not_allowed)
			(vias allowed)
			(pads allowed)
			(copperpour not_allowed)
			(footprints allowed)
		)
		(placement
			(enabled no)
			(sheetname "")
		)
		(fill yes
			(thermal_gap 0.5)
			(thermal_bridge_width 0.5)
			(island_removal_mode 0)
		)
		(polygon
			(pts
				(arc
					(start 88.202008 -32.93999)
					(mid 85.408008 -32.93999)
					(end 88.202008 -32.93999)
				)
			)
		)
	)
	(zone
		(layers "In4.Cu" "In5.Cu")
		(hatch none 0.5)
		(connect_pads
			(clearance 0)
		)
		(min_thickness 0.25)
		(keepout
			(tracks not_allowed)
			(vias allowed)
			(pads allowed)
			(copperpour not_allowed)
			(footprints allowed)
		)
		(placement
			(enabled no)
			(sheetname "")
		)
		(fill yes
			(thermal_gap 0.5)
			(thermal_bridge_width 0.5)
			(island_removal_mode 0)
		)
		(polygon
			(pts
				(arc
					(start 216.154 -92.964)
					(mid 214.376 -92.964)
					(end 216.154 -92.964)
				)
			)
		)
	)
	(zone
		(layers "In4.Cu" "In5.Cu")
		(hatch none 0.5)
		(connect_pads
			(clearance 0)
		)
		(min_thickness 0.25)
		(keepout
			(tracks not_allowed)
			(vias allowed)
			(pads allowed)
			(copperpour not_allowed)
			(footprints allowed)
		)
		(placement
			(enabled no)
			(sheetname "")
		)
		(fill yes
			(thermal_gap 0.5)
			(thermal_bridge_width 0.5)
			(island_removal_mode 0)
		)
		(polygon
			(pts
				(arc
					(start 276.61235 -43.434)
					(mid 274.83435 -43.434)
					(end 276.61235 -43.434)
				)
			)
		)
	)
	(zone
		(layers "In4.Cu" "In5.Cu")
		(hatch none 0.5)
		(connect_pads
			(clearance 0)
		)
		(min_thickness 0.25)
		(keepout
			(tracks not_allowed)
			(vias allowed)
			(pads allowed)
			(copperpour not_allowed)
			(footprints allowed)
		)
		(placement
			(enabled no)
			(sheetname "")
		)
		(fill yes
			(thermal_gap 0.5)
			(thermal_bridge_width 0.5)
			(island_removal_mode 0)
		)
		(polygon
			(pts
				(arc
					(start 276.61235 -44.323)
					(mid 274.83435 -44.323)
					(end 276.61235 -44.323)
				)
			)
		)
	)
	(zone
		(layers "In4.Cu" "In5.Cu")
		(hatch none 0.5)
		(connect_pads
			(clearance 0)
		)
		(min_thickness 0.25)
		(keepout
			(tracks not_allowed)
			(vias allowed)
			(pads allowed)
			(copperpour not_allowed)
			(footprints allowed)
		)
		(placement
			(enabled no)
			(sheetname "")
		)
		(fill yes
			(thermal_gap 0.5)
			(thermal_bridge_width 0.5)
			(island_removal_mode 0)
		)
		(polygon
			(pts
				(arc
					(start 188.336174 -55.96001)
					(mid 185.542174 -55.96001)
					(end 188.336174 -55.96001)
				)
			)
		)
	)
	(zone
		(layers "In4.Cu" "In5.Cu")
		(hatch none 0.5)
		(connect_pads
			(clearance 0)
		)
		(min_thickness 0.25)
		(keepout
			(tracks not_allowed)
			(vias allowed)
			(pads allowed)
			(copperpour not_allowed)
			(footprints allowed)
		)
		(placement
			(enabled no)
			(sheetname "")
		)
		(fill yes
			(thermal_gap 0.5)
			(thermal_bridge_width 0.5)
			(island_removal_mode 0)
		)
		(polygon
			(pts
				(arc
					(start 181.102 -62.738)
					(mid 179.324 -62.738)
					(end 181.102 -62.738)
				)
			)
		)
	)
	(zone
		(layers "In4.Cu" "In5.Cu")
		(hatch none 0.5)
		(connect_pads
			(clearance 0)
		)
		(min_thickness 0.25)
		(keepout
			(tracks not_allowed)
			(vias allowed)
			(pads allowed)
			(copperpour not_allowed)
			(footprints allowed)
		)
		(placement
			(enabled no)
			(sheetname "")
		)
		(fill yes
			(thermal_gap 0.5)
			(thermal_bridge_width 0.5)
			(island_removal_mode 0)
		)
		(polygon
			(pts
				(arc
					(start 226.441 -72.00265)
					(mid 224.663 -72.00265)
					(end 226.441 -72.00265)
				)
			)
		)
	)
	(zone
		(layers "In4.Cu" "In5.Cu")
		(hatch none 0.5)
		(connect_pads
			(clearance 0)
		)
		(min_thickness 0.25)
		(keepout
			(tracks not_allowed)
			(vias allowed)
			(pads allowed)
			(copperpour not_allowed)
			(footprints allowed)
		)
		(placement
			(enabled no)
			(sheetname "")
		)
		(fill yes
			(thermal_gap 0.5)
			(thermal_bridge_width 0.5)
			(island_removal_mode 0)
		)
		(polygon
			(pts
				(arc
					(start 103.632 -51.689)
					(mid 101.854 -51.689)
					(end 103.632 -51.689)
				)
			)
		)
	)
	(zone
		(layers "In4.Cu" "In5.Cu")
		(hatch none 0.5)
		(connect_pads
			(clearance 0)
		)
		(min_thickness 0.25)
		(keepout
			(tracks not_allowed)
			(vias allowed)
			(pads allowed)
			(copperpour not_allowed)
			(footprints allowed)
		)
		(placement
			(enabled no)
			(sheetname "")
		)
		(fill yes
			(thermal_gap 0.5)
			(thermal_bridge_width 0.5)
			(island_removal_mode 0)
		)
		(polygon
			(pts
				(arc
					(start 112.853216 -136.906)
					(mid 110.008416 -136.906)
					(end 112.853216 -136.906)
				)
			)
		)
	)
	(zone
		(layers "In4.Cu" "In5.Cu")
		(hatch none 0.5)
		(connect_pads
			(clearance 0)
		)
		(min_thickness 0.25)
		(keepout
			(tracks not_allowed)
			(vias allowed)
			(pads allowed)
			(copperpour not_allowed)
			(footprints allowed)
		)
		(placement
			(enabled no)
			(sheetname "")
		)
		(fill yes
			(thermal_gap 0.5)
			(thermal_bridge_width 0.5)
			(island_removal_mode 0)
		)
		(polygon
			(pts
				(arc
					(start 199.39 -92.1258)
					(mid 197.612 -92.1258)
					(end 199.39 -92.1258)
				)
			)
		)
	)
	(zone
		(layers "In4.Cu" "In5.Cu")
		(hatch none 0.5)
		(connect_pads
			(clearance 0)
		)
		(min_thickness 0.25)
		(keepout
			(tracks not_allowed)
			(vias allowed)
			(pads allowed)
			(copperpour not_allowed)
			(footprints allowed)
		)
		(placement
			(enabled no)
			(sheetname "")
		)
		(fill yes
			(thermal_gap 0.5)
			(thermal_bridge_width 0.5)
			(island_removal_mode 0)
		)
		(polygon
			(pts
				(arc
					(start 167.508174 -126.492)
					(mid 165.730174 -126.492)
					(end 167.508174 -126.492)
				)
			)
		)
	)
	(zone
		(layers "In4.Cu" "In5.Cu")
		(hatch none 0.5)
		(connect_pads
			(clearance 0)
		)
		(min_thickness 0.25)
		(keepout
			(tracks not_allowed)
			(vias allowed)
			(pads allowed)
			(copperpour not_allowed)
			(footprints allowed)
		)
		(placement
			(enabled no)
			(sheetname "")
		)
		(fill yes
			(thermal_gap 0.5)
			(thermal_bridge_width 0.5)
			(island_removal_mode 0)
		)
		(polygon
			(pts
				(arc
					(start 98.171 -50.419)
					(mid 96.393 -50.419)
					(end 98.171 -50.419)
				)
			)
		)
	)
	(zone
		(layers "In4.Cu" "In5.Cu")
		(hatch none 0.5)
		(connect_pads
			(clearance 0)
		)
		(min_thickness 0.25)
		(keepout
			(tracks not_allowed)
			(vias allowed)
			(pads allowed)
			(copperpour not_allowed)
			(footprints allowed)
		)
		(placement
			(enabled no)
			(sheetname "")
		)
		(fill yes
			(thermal_gap 0.5)
			(thermal_bridge_width 0.5)
			(island_removal_mode 0)
		)
		(polygon
			(pts
				(arc
					(start 187.19546 -52.197)
					(mid 185.41746 -52.197)
					(end 187.19546 -52.197)
				)
			)
		)
	)
	(zone
		(layers "In4.Cu" "In5.Cu")
		(hatch none 0.5)
		(connect_pads
			(clearance 0)
		)
		(min_thickness 0.25)
		(keepout
			(tracks not_allowed)
			(vias allowed)
			(pads allowed)
			(copperpour not_allowed)
			(footprints allowed)
		)
		(placement
			(enabled no)
			(sheetname "")
		)
		(fill yes
			(thermal_gap 0.5)
			(thermal_bridge_width 0.5)
			(island_removal_mode 0)
		)
		(polygon
			(pts
				(arc
					(start 62.484 -61.722)
					(mid 60.706 -61.722)
					(end 62.484 -61.722)
				)
			)
		)
	)
	(zone
		(layers "In4.Cu" "In5.Cu")
		(hatch none 0.5)
		(connect_pads
			(clearance 0)
		)
		(min_thickness 0.25)
		(keepout
			(tracks not_allowed)
			(vias allowed)
			(pads allowed)
			(copperpour not_allowed)
			(footprints allowed)
		)
		(placement
			(enabled no)
			(sheetname "")
		)
		(fill yes
			(thermal_gap 0.5)
			(thermal_bridge_width 0.5)
			(island_removal_mode 0)
		)
		(polygon
			(pts
				(arc
					(start 87.507826 -131.572)
					(mid 85.729826 -131.572)
					(end 87.507826 -131.572)
				)
			)
		)
	)
	(zone
		(layers "In4.Cu" "In5.Cu")
		(hatch none 0.5)
		(connect_pads
			(clearance 0)
		)
		(min_thickness 0.25)
		(keepout
			(tracks not_allowed)
			(vias allowed)
			(pads allowed)
			(copperpour not_allowed)
			(footprints allowed)
		)
		(placement
			(enabled no)
			(sheetname "")
		)
		(fill yes
			(thermal_gap 0.5)
			(thermal_bridge_width 0.5)
			(island_removal_mode 0)
		)
		(polygon
			(pts
				(arc
					(start 87.249 -52.324)
					(mid 85.471 -52.324)
					(end 87.249 -52.324)
				)
			)
		)
	)
	(zone
		(layers "In4.Cu" "In5.Cu")
		(hatch none 0.5)
		(connect_pads
			(clearance 0)
		)
		(min_thickness 0.25)
		(keepout
			(tracks not_allowed)
			(vias allowed)
			(pads allowed)
			(copperpour not_allowed)
			(footprints allowed)
		)
		(placement
			(enabled no)
			(sheetname "")
		)
		(fill yes
			(thermal_gap 0.5)
			(thermal_bridge_width 0.5)
			(island_removal_mode 0)
		)
		(polygon
			(pts
				(arc
					(start 151.13 -126.492)
					(mid 149.352 -126.492)
					(end 151.13 -126.492)
				)
			)
		)
	)
	(zone
		(layers "In4.Cu" "In5.Cu")
		(hatch none 0.5)
		(connect_pads
			(clearance 0)
		)
		(min_thickness 0.25)
		(keepout
			(tracks not_allowed)
			(vias allowed)
			(pads allowed)
			(copperpour not_allowed)
			(footprints allowed)
		)
		(placement
			(enabled no)
			(sheetname "")
		)
		(fill yes
			(thermal_gap 0.5)
			(thermal_bridge_width 0.5)
			(island_removal_mode 0)
		)
		(polygon
			(pts
				(arc
					(start 239.91189 -87.496396)
					(mid 238.13389 -87.496396)
					(end 239.91189 -87.496396)
				)
			)
		)
	)
	(zone
		(layers "In4.Cu" "In5.Cu")
		(hatch none 0.5)
		(connect_pads
			(clearance 0)
		)
		(min_thickness 0.25)
		(keepout
			(tracks not_allowed)
			(vias allowed)
			(pads allowed)
			(copperpour not_allowed)
			(footprints allowed)
		)
		(placement
			(enabled no)
			(sheetname "")
		)
		(fill yes
			(thermal_gap 0.5)
			(thermal_bridge_width 0.5)
			(island_removal_mode 0)
		)
		(polygon
			(pts
				(arc
					(start 140.66139 -136.906)
					(mid 137.81659 -136.906)
					(end 140.66139 -136.906)
				)
			)
		)
	)
	(zone
		(layers "In4.Cu" "In5.Cu")
		(hatch none 0.5)
		(connect_pads
			(clearance 0)
		)
		(min_thickness 0.25)
		(keepout
			(tracks not_allowed)
			(vias allowed)
			(pads allowed)
			(copperpour not_allowed)
			(footprints allowed)
		)
		(placement
			(enabled no)
			(sheetname "")
		)
		(fill yes
			(thermal_gap 0.5)
			(thermal_bridge_width 0.5)
			(island_removal_mode 0)
		)
		(polygon
			(pts
				(arc
					(start 94.552008 -32.93999)
					(mid 91.758008 -32.93999)
					(end 94.552008 -32.93999)
				)
			)
		)
	)
	(zone
		(layers "In4.Cu" "In5.Cu")
		(hatch none 0.5)
		(connect_pads
			(clearance 0)
		)
		(min_thickness 0.25)
		(keepout
			(tracks not_allowed)
			(vias allowed)
			(pads allowed)
			(copperpour not_allowed)
			(footprints allowed)
		)
		(placement
			(enabled no)
			(sheetname "")
		)
		(fill yes
			(thermal_gap 0.5)
			(thermal_bridge_width 0.5)
			(island_removal_mode 0)
		)
		(polygon
			(pts
				(arc
					(start 71.129906 -131.572)
					(mid 69.351906 -131.572)
					(end 71.129906 -131.572)
				)
			)
		)
	)
	(zone
		(layers "In4.Cu" "In5.Cu")
		(hatch none 0.5)
		(connect_pads
			(clearance 0)
		)
		(min_thickness 0.25)
		(keepout
			(tracks not_allowed)
			(vias allowed)
			(pads allowed)
			(copperpour not_allowed)
			(footprints allowed)
		)
		(placement
			(enabled no)
			(sheetname "")
		)
		(fill yes
			(thermal_gap 0.5)
			(thermal_bridge_width 0.5)
			(island_removal_mode 0)
		)
		(polygon
			(pts
				(arc
					(start 60.145422 -67.869816)
					(mid 57.554622 -67.869816)
					(end 60.145422 -67.869816)
				)
			)
		)
	)
	(zone
		(layers "In4.Cu" "In5.Cu")
		(hatch none 0.5)
		(connect_pads
			(clearance 0)
		)
		(min_thickness 0.25)
		(keepout
			(tracks not_allowed)
			(vias allowed)
			(pads allowed)
			(copperpour not_allowed)
			(footprints allowed)
		)
		(placement
			(enabled no)
			(sheetname "")
		)
		(fill yes
			(thermal_gap 0.5)
			(thermal_bridge_width 0.5)
			(island_removal_mode 0)
		)
		(polygon
			(pts
				(arc
					(start 138.938 -126.492)
					(mid 137.16 -126.492)
					(end 138.938 -126.492)
				)
			)
		)
	)
	(zone
		(layers "In4.Cu" "In5.Cu")
		(hatch none 0.5)
		(connect_pads
			(clearance 0)
		)
		(min_thickness 0.25)
		(keepout
			(tracks not_allowed)
			(vias allowed)
			(pads allowed)
			(copperpour not_allowed)
			(footprints allowed)
		)
		(placement
			(enabled no)
			(sheetname "")
		)
		(fill yes
			(thermal_gap 0.5)
			(thermal_bridge_width 0.5)
			(island_removal_mode 0)
		)
		(polygon
			(pts
				(arc
					(start 47.57801 -56.109362)
					(mid 45.80001 -56.109362)
					(end 47.57801 -56.109362)
				)
			)
		)
	)
	(zone
		(layers "In4.Cu" "In5.Cu")
		(hatch none 0.5)
		(connect_pads
			(clearance 0)
		)
		(min_thickness 0.25)
		(keepout
			(tracks not_allowed)
			(vias allowed)
			(pads allowed)
			(copperpour not_allowed)
			(footprints allowed)
		)
		(placement
			(enabled no)
			(sheetname "")
		)
		(fill yes
			(thermal_gap 0.5)
			(thermal_bridge_width 0.5)
			(island_removal_mode 0)
		)
		(polygon
			(pts
				(arc
					(start 102.108 -61.595)
					(mid 100.33 -61.595)
					(end 102.108 -61.595)
				)
			)
		)
	)
	(zone
		(layers "In4.Cu" "In5.Cu")
		(hatch none 0.5)
		(connect_pads
			(clearance 0)
		)
		(min_thickness 0.25)
		(keepout
			(tracks not_allowed)
			(vias allowed)
			(pads allowed)
			(copperpour not_allowed)
			(footprints allowed)
		)
		(placement
			(enabled no)
			(sheetname "")
		)
		(fill yes
			(thermal_gap 0.5)
			(thermal_bridge_width 0.5)
			(island_removal_mode 0)
		)
		(polygon
			(pts
				(arc
					(start 240.454434 -80.10779)
					(mid 238.676434 -80.10779)
					(end 240.454434 -80.10779)
				)
			)
		)
	)
	(zone
		(layers "In4.Cu" "In5.Cu")
		(hatch none 0.5)
		(connect_pads
			(clearance 0)
		)
		(min_thickness 0.25)
		(keepout
			(tracks not_allowed)
			(vias allowed)
			(pads allowed)
			(copperpour not_allowed)
			(footprints allowed)
		)
		(placement
			(enabled no)
			(sheetname "")
		)
		(fill yes
			(thermal_gap 0.5)
			(thermal_bridge_width 0.5)
			(island_removal_mode 0)
		)
		(polygon
			(pts
				(arc
					(start 168.469564 -136.906)
					(mid 165.624764 -136.906)
					(end 168.469564 -136.906)
				)
			)
		)
	)
	(zone
		(layers "In4.Cu" "In5.Cu")
		(hatch none 0.5)
		(connect_pads
			(clearance 0)
		)
		(min_thickness 0.25)
		(keepout
			(tracks not_allowed)
			(vias allowed)
			(pads allowed)
			(copperpour not_allowed)
			(footprints allowed)
		)
		(placement
			(enabled no)
			(sheetname "")
		)
		(fill yes
			(thermal_gap 0.5)
			(thermal_bridge_width 0.5)
			(island_removal_mode 0)
		)
		(polygon
			(pts
				(arc
					(start 62.145418 -67.869816)
					(mid 59.554618 -67.869816)
					(end 62.145418 -67.869816)
				)
			)
		)
	)
	(zone
		(layers "In4.Cu" "In5.Cu")
		(hatch none 0.5)
		(connect_pads
			(clearance 0)
		)
		(min_thickness 0.25)
		(keepout
			(tracks not_allowed)
			(vias allowed)
			(pads allowed)
			(copperpour not_allowed)
			(footprints allowed)
		)
		(placement
			(enabled no)
			(sheetname "")
		)
		(fill yes
			(thermal_gap 0.5)
			(thermal_bridge_width 0.5)
			(island_removal_mode 0)
		)
		(polygon
			(pts
				(arc
					(start 233.426 -92.964)
					(mid 231.648 -92.964)
					(end 233.426 -92.964)
				)
			)
		)
	)
	(zone
		(layers "In4.Cu" "In5.Cu")
		(hatch none 0.5)
		(connect_pads
			(clearance 0)
		)
		(min_thickness 0.25)
		(keepout
			(tracks not_allowed)
			(vias allowed)
			(pads allowed)
			(copperpour not_allowed)
			(footprints allowed)
		)
		(placement
			(enabled no)
			(sheetname "")
		)
		(fill yes
			(thermal_gap 0.5)
			(thermal_bridge_width 0.5)
			(island_removal_mode 0)
		)
		(polygon
			(pts
				(arc
					(start 58.145426 -67.869816)
					(mid 55.554626 -67.869816)
					(end 58.145426 -67.869816)
				)
			)
		)
	)
	(zone
		(layers "In4.Cu" "In5.Cu")
		(hatch none 0.5)
		(connect_pads
			(clearance 0)
		)
		(min_thickness 0.25)
		(keepout
			(tracks not_allowed)
			(vias allowed)
			(pads allowed)
			(copperpour not_allowed)
			(footprints allowed)
		)
		(placement
			(enabled no)
			(sheetname "")
		)
		(fill yes
			(thermal_gap 0.5)
			(thermal_bridge_width 0.5)
			(island_removal_mode 0)
		)
		(polygon
			(pts
				(arc
					(start 187.19546 -49.657)
					(mid 185.41746 -49.657)
					(end 187.19546 -49.657)
				)
			)
		)
	)
	(zone
		(layers "In4.Cu" "In5.Cu")
		(hatch none 0.5)
		(connect_pads
			(clearance 0)
		)
		(min_thickness 0.25)
		(keepout
			(tracks not_allowed)
			(vias allowed)
			(pads allowed)
			(copperpour not_allowed)
			(footprints allowed)
		)
		(placement
			(enabled no)
			(sheetname "")
		)
		(fill yes
			(thermal_gap 0.5)
			(thermal_bridge_width 0.5)
			(island_removal_mode 0)
		)
		(polygon
			(pts
				(arc
					(start 232.664 -83.30565)
					(mid 230.886 -83.30565)
					(end 232.664 -83.30565)
				)
			)
		)
	)
	(zone
		(layers "In4.Cu" "In5.Cu")
		(hatch none 0.5)
		(connect_pads
			(clearance 0)
		)
		(min_thickness 0.25)
		(keepout
			(tracks not_allowed)
			(vias allowed)
			(pads allowed)
			(copperpour not_allowed)
			(footprints allowed)
		)
		(placement
			(enabled no)
			(sheetname "")
		)
		(fill yes
			(thermal_gap 0.5)
			(thermal_bridge_width 0.5)
			(island_removal_mode 0)
		)
		(polygon
			(pts
				(arc
					(start 285.4198 -44.831)
					(mid 283.6418 -44.831)
					(end 285.4198 -44.831)
				)
			)
		)
	)
	(zone
		(layers "In4.Cu" "In5.Cu")
		(hatch none 0.5)
		(connect_pads
			(clearance 0)
		)
		(min_thickness 0.25)
		(keepout
			(tracks not_allowed)
			(vias allowed)
			(pads allowed)
			(copperpour not_allowed)
			(footprints allowed)
		)
		(placement
			(enabled no)
			(sheetname "")
		)
		(fill yes
			(thermal_gap 0.5)
			(thermal_bridge_width 0.5)
			(island_removal_mode 0)
		)
		(polygon
			(pts
				(arc
					(start 230.998014 -77.851)
					(mid 229.220014 -77.851)
					(end 230.998014 -77.851)
				)
			)
		)
	)
	(zone
		(layers "In4.Cu" "In5.Cu")
		(hatch none 0.5)
		(connect_pads
			(clearance 0)
		)
		(min_thickness 0.25)
		(keepout
			(tracks not_allowed)
			(vias allowed)
			(pads allowed)
			(copperpour not_allowed)
			(footprints allowed)
		)
		(placement
			(enabled no)
			(sheetname "")
		)
		(fill yes
			(thermal_gap 0.5)
			(thermal_bridge_width 0.5)
			(island_removal_mode 0)
		)
		(polygon
			(pts
				(arc
					(start 128.46939 -136.906)
					(mid 125.62459 -136.906)
					(end 128.46939 -136.906)
				)
			)
		)
	)
	(zone
		(layers "In4.Cu" "In5.Cu")
		(hatch none 0.5)
		(connect_pads
			(clearance 0)
		)
		(min_thickness 0.25)
		(keepout
			(tracks not_allowed)
			(vias allowed)
			(pads allowed)
			(copperpour not_allowed)
			(footprints allowed)
		)
		(placement
			(enabled no)
			(sheetname "")
		)
		(fill yes
			(thermal_gap 0.5)
			(thermal_bridge_width 0.5)
			(island_removal_mode 0)
		)
		(polygon
			(pts
				(arc
					(start 206.502 -65.89522)
					(mid 204.724 -65.89522)
					(end 206.502 -65.89522)
				)
			)
		)
	)
	(zone
		(layers "In4.Cu" "In5.Cu")
		(hatch none 0.5)
		(connect_pads
			(clearance 0)
		)
		(min_thickness 0.25)
		(keepout
			(tracks not_allowed)
			(vias allowed)
			(pads allowed)
			(copperpour not_allowed)
			(footprints allowed)
		)
		(placement
			(enabled no)
			(sheetname "")
		)
		(fill yes
			(thermal_gap 0.5)
			(thermal_bridge_width 0.5)
			(island_removal_mode 0)
		)
		(polygon
			(pts
				(arc
					(start 211.963 -66.167)
					(mid 210.185 -66.167)
					(end 211.963 -66.167)
				)
			)
		)
	)
	(zone
		(layers "In4.Cu" "In5.Cu")
		(hatch none 0.5)
		(connect_pads
			(clearance 0)
		)
		(min_thickness 0.25)
		(keepout
			(tracks not_allowed)
			(vias allowed)
			(pads allowed)
			(copperpour not_allowed)
			(footprints allowed)
		)
		(placement
			(enabled no)
			(sheetname "")
		)
		(fill yes
			(thermal_gap 0.5)
			(thermal_bridge_width 0.5)
			(island_removal_mode 0)
		)
		(polygon
			(pts
				(arc
					(start 103.632 -52.324)
					(mid 101.854 -52.324)
					(end 103.632 -52.324)
				)
			)
		)
	)
	(zone
		(layers "In4.Cu" "In5.Cu")
		(hatch none 0.5)
		(connect_pads
			(clearance 0)
		)
		(min_thickness 0.25)
		(keepout
			(tracks not_allowed)
			(vias allowed)
			(pads allowed)
			(copperpour not_allowed)
			(footprints allowed)
		)
		(placement
			(enabled no)
			(sheetname "")
		)
		(fill yes
			(thermal_gap 0.5)
			(thermal_bridge_width 0.5)
			(island_removal_mode 0)
		)
		(polygon
			(pts
				(arc
					(start 95.904304 -34.26206)
					(mid 93.110304 -34.26206)
					(end 95.904304 -34.26206)
				)
			)
		)
	)
	(zone
		(layers "In4.Cu" "In5.Cu")
		(hatch none 0.5)
		(connect_pads
			(clearance 0)
		)
		(min_thickness 0.25)
		(keepout
			(tracks not_allowed)
			(vias allowed)
			(pads allowed)
			(copperpour not_allowed)
			(footprints allowed)
		)
		(placement
			(enabled no)
			(sheetname "")
		)
		(fill yes
			(thermal_gap 0.5)
			(thermal_bridge_width 0.5)
			(island_removal_mode 0)
		)
		(polygon
			(pts
				(arc
					(start 80.772 -55.96001)
					(mid 77.978 -55.96001)
					(end 80.772 -55.96001)
				)
			)
		)
	)
	(zone
		(layers "In4.Cu" "In5.Cu")
		(hatch none 0.5)
		(connect_pads
			(clearance 0)
		)
		(min_thickness 0.25)
		(keepout
			(tracks not_allowed)
			(vias allowed)
			(pads allowed)
			(copperpour not_allowed)
			(footprints allowed)
		)
		(placement
			(enabled no)
			(sheetname "")
		)
		(fill yes
			(thermal_gap 0.5)
			(thermal_bridge_width 0.5)
			(island_removal_mode 0)
		)
		(polygon
			(pts
				(arc
					(start 72.853296 -136.906)
					(mid 70.008496 -136.906)
					(end 72.853296 -136.906)
				)
			)
		)
	)
	(zone
		(layers "In4.Cu" "In5.Cu")
		(hatch none 0.5)
		(connect_pads
			(clearance 0)
		)
		(min_thickness 0.25)
		(keepout
			(tracks not_allowed)
			(vias allowed)
			(pads allowed)
			(copperpour not_allowed)
			(footprints allowed)
		)
		(placement
			(enabled no)
			(sheetname "")
		)
		(fill yes
			(thermal_gap 0.5)
			(thermal_bridge_width 0.5)
			(island_removal_mode 0)
		)
		(polygon
			(pts
				(arc
					(start 56.14543 -67.869816)
					(mid 53.55463 -67.869816)
					(end 56.14543 -67.869816)
				)
			)
		)
	)
	(zone
		(layers "In4.Cu" "In5.Cu")
		(hatch none 0.5)
		(connect_pads
			(clearance 0)
		)
		(min_thickness 0.25)
		(keepout
			(tracks not_allowed)
			(vias allowed)
			(pads allowed)
			(copperpour not_allowed)
			(footprints allowed)
		)
		(placement
			(enabled no)
			(sheetname "")
		)
		(fill yes
			(thermal_gap 0.5)
			(thermal_bridge_width 0.5)
			(island_removal_mode 0)
		)
		(polygon
			(pts
				(arc
					(start 98.937826 -131.572)
					(mid 97.159826 -131.572)
					(end 98.937826 -131.572)
				)
			)
		)
	)
	(zone
		(layers "In4.Cu" "In5.Cu")
		(hatch none 0.5)
		(connect_pads
			(clearance 0)
		)
		(min_thickness 0.25)
		(keepout
			(tracks not_allowed)
			(vias allowed)
			(pads allowed)
			(copperpour not_allowed)
			(footprints allowed)
		)
		(placement
			(enabled no)
			(sheetname "")
		)
		(fill yes
			(thermal_gap 0.5)
			(thermal_bridge_width 0.5)
			(island_removal_mode 0)
		)
		(polygon
			(pts
				(arc
					(start 109.093 -49.784)
					(mid 107.315 -49.784)
					(end 109.093 -49.784)
				)
			)
		)
	)
	(zone
		(layers "In4.Cu" "In5.Cu")
		(hatch none 0.5)
		(connect_pads
			(clearance 0)
		)
		(min_thickness 0.25)
		(keepout
			(tracks not_allowed)
			(vias allowed)
			(pads allowed)
			(copperpour not_allowed)
			(footprints allowed)
		)
		(placement
			(enabled no)
			(sheetname "")
		)
		(fill yes
			(thermal_gap 0.5)
			(thermal_bridge_width 0.5)
			(island_removal_mode 0)
		)
		(polygon
			(pts
				(arc
					(start 92.71 -51.689)
					(mid 90.932 -51.689)
					(end 92.71 -51.689)
				)
			)
		)
	)
	(zone
		(layers "In4.Cu" "In5.Cu")
		(hatch none 0.5)
		(connect_pads
			(clearance 0)
		)
		(min_thickness 0.25)
		(keepout
			(tracks not_allowed)
			(vias allowed)
			(pads allowed)
			(copperpour not_allowed)
			(footprints allowed)
		)
		(placement
			(enabled no)
			(sheetname "")
		)
		(fill yes
			(thermal_gap 0.5)
			(thermal_bridge_width 0.5)
			(island_removal_mode 0)
		)
		(polygon
			(pts
				(arc
					(start 86.979506 -36.787328)
					(mid 84.185506 -36.787328)
					(end 86.979506 -36.787328)
				)
			)
		)
	)
	(zone
		(layers "In4.Cu" "In5.Cu")
		(hatch none 0.5)
		(connect_pads
			(clearance 0)
		)
		(min_thickness 0.25)
		(keepout
			(tracks not_allowed)
			(vias allowed)
			(pads allowed)
			(copperpour not_allowed)
			(footprints allowed)
		)
		(placement
			(enabled no)
			(sheetname "")
		)
		(fill yes
			(thermal_gap 0.5)
			(thermal_bridge_width 0.5)
			(island_removal_mode 0)
		)
		(polygon
			(pts
				(arc
					(start 81.788 -50.419)
					(mid 80.01 -50.419)
					(end 81.788 -50.419)
				)
			)
		)
	)
	(zone
		(layers "In4.Cu" "In5.Cu")
		(hatch none 0.5)
		(connect_pads
			(clearance 0)
		)
		(min_thickness 0.25)
		(keepout
			(tracks not_allowed)
			(vias allowed)
			(pads allowed)
			(copperpour not_allowed)
			(footprints allowed)
		)
		(placement
			(enabled no)
			(sheetname "")
		)
		(fill yes
			(thermal_gap 0.5)
			(thermal_bridge_width 0.5)
			(island_removal_mode 0)
		)
		(polygon
			(pts
				(arc
					(start 229.759002 -89.49436)
					(mid 227.981002 -89.49436)
					(end 229.759002 -89.49436)
				)
			)
		)
	)
	(zone
		(layers "In4.Cu" "In5.Cu")
		(hatch none 0.5)
		(connect_pads
			(clearance 0)
		)
		(min_thickness 0.25)
		(keepout
			(tracks not_allowed)
			(vias allowed)
			(pads allowed)
			(copperpour not_allowed)
			(footprints allowed)
		)
		(placement
			(enabled no)
			(sheetname "")
		)
		(fill yes
			(thermal_gap 0.5)
			(thermal_bridge_width 0.5)
			(island_removal_mode 0)
		)
		(polygon
			(pts
				(arc
					(start 240.454688 -78.96479)
					(mid 238.676688 -78.96479)
					(end 240.454688 -78.96479)
				)
			)
		)
	)
	(zone
		(layers "In4.Cu" "In5.Cu")
		(hatch none 0.5)
		(connect_pads
			(clearance 0)
		)
		(min_thickness 0.25)
		(keepout
			(tracks not_allowed)
			(vias allowed)
			(pads allowed)
			(copperpour not_allowed)
			(footprints allowed)
		)
		(placement
			(enabled no)
			(sheetname "")
		)
		(fill yes
			(thermal_gap 0.5)
			(thermal_bridge_width 0.5)
			(island_removal_mode 0)
		)
		(polygon
			(pts
				(arc
					(start 138.938 -131.572)
					(mid 137.16 -131.572)
					(end 138.938 -131.572)
				)
			)
		)
	)
	(zone
		(layers "In4.Cu" "In5.Cu")
		(hatch none 0.5)
		(connect_pads
			(clearance 0)
		)
		(min_thickness 0.25)
		(keepout
			(tracks not_allowed)
			(vias allowed)
			(pads allowed)
			(copperpour not_allowed)
			(footprints allowed)
		)
		(placement
			(enabled no)
			(sheetname "")
		)
		(fill yes
			(thermal_gap 0.5)
			(thermal_bridge_width 0.5)
			(island_removal_mode 0)
		)
		(polygon
			(pts
				(arc
					(start 131.04622 -121.209816)
					(mid 127.41402 -121.209816)
					(end 131.04622 -121.209816)
				)
			)
		)
	)
	(zone
		(layers "In4.Cu" "In5.Cu")
		(hatch none 0.5)
		(connect_pads
			(clearance 0)
		)
		(min_thickness 0.25)
		(keepout
			(tracks not_allowed)
			(vias allowed)
			(pads allowed)
			(copperpour not_allowed)
			(footprints allowed)
		)
		(placement
			(enabled no)
			(sheetname "")
		)
		(fill yes
			(thermal_gap 0.5)
			(thermal_bridge_width 0.5)
			(island_removal_mode 0)
		)
		(polygon
			(pts
				(arc
					(start 152.85339 -136.906)
					(mid 150.00859 -136.906)
					(end 152.85339 -136.906)
				)
			)
		)
	)
	(zone
		(layers "In4.Cu" "In5.Cu")
		(hatch none 0.5)
		(connect_pads
			(clearance 0)
		)
		(min_thickness 0.25)
		(keepout
			(tracks not_allowed)
			(vias allowed)
			(pads allowed)
			(copperpour not_allowed)
			(footprints allowed)
		)
		(placement
			(enabled no)
			(sheetname "")
		)
		(fill yes
			(thermal_gap 0.5)
			(thermal_bridge_width 0.5)
			(island_removal_mode 0)
		)
		(polygon
			(pts
				(arc
					(start 98.171 -51.689)
					(mid 96.393 -51.689)
					(end 98.171 -51.689)
				)
			)
		)
	)
	(zone
		(layers "In4.Cu" "In5.Cu")
		(hatch none 0.5)
		(connect_pads
			(clearance 0)
		)
		(min_thickness 0.25)
		(keepout
			(tracks not_allowed)
			(vias allowed)
			(pads allowed)
			(copperpour not_allowed)
			(footprints allowed)
		)
		(placement
			(enabled no)
			(sheetname "")
		)
		(fill yes
			(thermal_gap 0.5)
			(thermal_bridge_width 0.5)
			(island_removal_mode 0)
		)
		(polygon
			(pts
				(arc
					(start 111.891826 -126.492)
					(mid 110.113826 -126.492)
					(end 111.891826 -126.492)
				)
			)
		)
	)
	(zone
		(layers "In4.Cu" "In5.Cu")
		(hatch none 0.5)
		(connect_pads
			(clearance 0)
		)
		(min_thickness 0.25)
		(keepout
			(tracks not_allowed)
			(vias allowed)
			(pads allowed)
			(copperpour not_allowed)
			(footprints allowed)
		)
		(placement
			(enabled no)
			(sheetname "")
		)
		(fill yes
			(thermal_gap 0.5)
			(thermal_bridge_width 0.5)
			(island_removal_mode 0)
		)
		(polygon
			(pts
				(arc
					(start 223.774 -92.964)
					(mid 221.996 -92.964)
					(end 223.774 -92.964)
				)
			)
		)
	)
	(zone
		(layers "In4.Cu" "In5.Cu")
		(hatch none 0.5)
		(connect_pads
			(clearance 0)
		)
		(min_thickness 0.25)
		(keepout
			(tracks not_allowed)
			(vias allowed)
			(pads allowed)
			(copperpour not_allowed)
			(footprints allowed)
		)
		(placement
			(enabled no)
			(sheetname "")
		)
		(fill yes
			(thermal_gap 0.5)
			(thermal_bridge_width 0.5)
			(island_removal_mode 0)
		)
		(polygon
			(pts
				(arc
					(start 233.61904 -90.17)
					(mid 231.84104 -90.17)
					(end 233.61904 -90.17)
				)
			)
		)
	)
	(zone
		(layers "In4.Cu" "In5.Cu")
		(hatch none 0.5)
		(connect_pads
			(clearance 0)
		)
		(min_thickness 0.25)
		(keepout
			(tracks not_allowed)
			(vias allowed)
			(pads allowed)
			(copperpour not_allowed)
			(footprints allowed)
		)
		(placement
			(enabled no)
			(sheetname "")
		)
		(fill yes
			(thermal_gap 0.5)
			(thermal_bridge_width 0.5)
			(island_removal_mode 0)
		)
		(polygon
			(pts
				(arc
					(start 79.312008 -38.01999)
					(mid 76.518008 -38.01999)
					(end 79.312008 -38.01999)
				)
			)
		)
	)
	(zone
		(layers "In4.Cu" "In5.Cu")
		(hatch none 0.5)
		(connect_pads
			(clearance 0)
		)
		(min_thickness 0.25)
		(keepout
			(tracks not_allowed)
			(vias allowed)
			(pads allowed)
			(copperpour not_allowed)
			(footprints allowed)
		)
		(placement
			(enabled no)
			(sheetname "")
		)
		(fill yes
			(thermal_gap 0.5)
			(thermal_bridge_width 0.5)
			(island_removal_mode 0)
		)
		(polygon
			(pts
				(arc
					(start 226.187 -92.964)
					(mid 224.409 -92.964)
					(end 226.187 -92.964)
				)
			)
		)
	)
	(zone
		(layers "In4.Cu" "In5.Cu")
		(hatch none 0.5)
		(connect_pads
			(clearance 0)
		)
		(min_thickness 0.25)
		(keepout
			(tracks not_allowed)
			(vias allowed)
			(pads allowed)
			(copperpour not_allowed)
			(footprints allowed)
		)
		(placement
			(enabled no)
			(sheetname "")
		)
		(fill yes
			(thermal_gap 0.5)
			(thermal_bridge_width 0.5)
			(island_removal_mode 0)
		)
		(polygon
			(pts
				(arc
					(start 98.666046 -121.209816)
					(mid 95.033846 -121.209816)
					(end 98.666046 -121.209816)
				)
			)
		)
	)
	(zone
		(layers "In4.Cu" "In5.Cu")
		(hatch none 0.5)
		(connect_pads
			(clearance 0)
		)
		(min_thickness 0.25)
		(keepout
			(tracks not_allowed)
			(vias allowed)
			(pads allowed)
			(copperpour not_allowed)
			(footprints allowed)
		)
		(placement
			(enabled no)
			(sheetname "")
		)
		(fill yes
			(thermal_gap 0.5)
			(thermal_bridge_width 0.5)
			(island_removal_mode 0)
		)
		(polygon
			(pts
				(arc
					(start 181.986174 -60.706)
					(mid 180.208174 -60.706)
					(end 181.986174 -60.706)
				)
			)
		)
	)
	(zone
		(layers "In4.Cu" "In5.Cu")
		(hatch none 0.5)
		(connect_pads
			(clearance 0)
		)
		(min_thickness 0.25)
		(keepout
			(tracks not_allowed)
			(vias allowed)
			(pads allowed)
			(copperpour not_allowed)
			(footprints allowed)
		)
		(placement
			(enabled no)
			(sheetname "")
		)
		(fill yes
			(thermal_gap 0.5)
			(thermal_bridge_width 0.5)
			(island_removal_mode 0)
		)
		(polygon
			(pts
				(arc
					(start 97.092008 -35.47999)
					(mid 94.298008 -35.47999)
					(end 97.092008 -35.47999)
				)
			)
		)
	)
	(zone
		(layers "In4.Cu" "In5.Cu")
		(hatch none 0.5)
		(connect_pads
			(clearance 0)
		)
		(min_thickness 0.25)
		(keepout
			(tracks not_allowed)
			(vias allowed)
			(pads allowed)
			(copperpour not_allowed)
			(footprints allowed)
		)
		(placement
			(enabled no)
			(sheetname "")
		)
		(fill yes
			(thermal_gap 0.5)
			(thermal_bridge_width 0.5)
			(island_removal_mode 0)
		)
		(polygon
			(pts
				(arc
					(start 127.508 -131.572)
					(mid 125.73 -131.572)
					(end 127.508 -131.572)
				)
			)
		)
	)
	(zone
		(layers "In4.Cu" "In5.Cu")
		(hatch none 0.5)
		(connect_pads
			(clearance 0)
		)
		(min_thickness 0.25)
		(keepout
			(tracks not_allowed)
			(vias allowed)
			(pads allowed)
			(copperpour not_allowed)
			(footprints allowed)
		)
		(placement
			(enabled no)
			(sheetname "")
		)
		(fill yes
			(thermal_gap 0.5)
			(thermal_bridge_width 0.5)
			(island_removal_mode 0)
		)
		(polygon
			(pts
				(arc
					(start 189.484 -91.821)
					(mid 187.706 -91.821)
					(end 189.484 -91.821)
				)
			)
		)
	)
	(zone
		(layers "In4.Cu" "In5.Cu")
		(hatch none 0.5)
		(connect_pads
			(clearance 0)
		)
		(min_thickness 0.25)
		(keepout
			(tracks not_allowed)
			(vias allowed)
			(pads allowed)
			(copperpour not_allowed)
			(footprints allowed)
		)
		(placement
			(enabled no)
			(sheetname "")
		)
		(fill yes
			(thermal_gap 0.5)
			(thermal_bridge_width 0.5)
			(island_removal_mode 0)
		)
		(polygon
			(pts
				(arc
					(start 233.172 -74.168)
					(mid 231.394 -74.168)
					(end 233.172 -74.168)
				)
			)
		)
	)
	(zone
		(layers "In4.Cu" "In5.Cu")
		(hatch none 0.5)
		(connect_pads
			(clearance 0)
		)
		(min_thickness 0.25)
		(keepout
			(tracks not_allowed)
			(vias allowed)
			(pads allowed)
			(copperpour not_allowed)
			(footprints allowed)
		)
		(placement
			(enabled no)
			(sheetname "")
		)
		(fill yes
			(thermal_gap 0.5)
			(thermal_bridge_width 0.5)
			(island_removal_mode 0)
		)
		(polygon
			(pts
				(arc
					(start 81.788 -51.689)
					(mid 80.01 -51.689)
					(end 81.788 -51.689)
				)
			)
		)
	)
	(zone
		(layers "In4.Cu" "In5.Cu")
		(hatch none 0.5)
		(connect_pads
			(clearance 0)
		)
		(min_thickness 0.25)
		(keepout
			(tracks not_allowed)
			(vias allowed)
			(pads allowed)
			(copperpour not_allowed)
			(footprints allowed)
		)
		(placement
			(enabled no)
			(sheetname "")
		)
		(fill yes
			(thermal_gap 0.5)
			(thermal_bridge_width 0.5)
			(island_removal_mode 0)
		)
		(polygon
			(pts
				(arc
					(start 178.938174 -126.492)
					(mid 177.160174 -126.492)
					(end 178.938174 -126.492)
				)
			)
		)
	)
	(zone
		(layers "In4.Cu" "In5.Cu")
		(hatch none 0.5)
		(connect_pads
			(clearance 0)
		)
		(min_thickness 0.25)
		(keepout
			(tracks not_allowed)
			(vias allowed)
			(pads allowed)
			(copperpour not_allowed)
			(footprints allowed)
		)
		(placement
			(enabled no)
			(sheetname "")
		)
		(fill yes
			(thermal_gap 0.5)
			(thermal_bridge_width 0.5)
			(island_removal_mode 0)
		)
		(polygon
			(pts
				(arc
					(start 223.774 -72.00265)
					(mid 221.996 -72.00265)
					(end 223.774 -72.00265)
				)
			)
		)
	)
	(zone
		(layers "In4.Cu" "In5.Cu")
		(hatch none 0.5)
		(connect_pads
			(clearance 0)
		)
		(min_thickness 0.25)
		(keepout
			(tracks not_allowed)
			(vias allowed)
			(pads allowed)
			(copperpour not_allowed)
			(footprints allowed)
		)
		(placement
			(enabled no)
			(sheetname "")
		)
		(fill yes
			(thermal_gap 0.5)
			(thermal_bridge_width 0.5)
			(island_removal_mode 0)
		)
		(polygon
			(pts
				(arc
					(start 243.078 -92.964)
					(mid 241.3 -92.964)
					(end 243.078 -92.964)
				)
			)
		)
	)
	(zone
		(layers "In4.Cu" "In5.Cu")
		(hatch none 0.5)
		(connect_pads
			(clearance 0)
		)
		(min_thickness 0.25)
		(keepout
			(tracks not_allowed)
			(vias allowed)
			(pads allowed)
			(copperpour not_allowed)
			(footprints allowed)
		)
		(placement
			(enabled no)
			(sheetname "")
		)
		(fill yes
			(thermal_gap 0.5)
			(thermal_bridge_width 0.5)
			(island_removal_mode 0)
		)
		(polygon
			(pts
				(arc
					(start 159.893 -49.657)
					(mid 158.115 -49.657)
					(end 159.893 -49.657)
				)
			)
		)
	)
	(zone
		(layers "In4.Cu" "In5.Cu")
		(hatch none 0.5)
		(connect_pads
			(clearance 0)
		)
		(min_thickness 0.25)
		(keepout
			(tracks not_allowed)
			(vias allowed)
			(pads allowed)
			(copperpour not_allowed)
			(footprints allowed)
		)
		(placement
			(enabled no)
			(sheetname "")
		)
		(fill yes
			(thermal_gap 0.5)
			(thermal_bridge_width 0.5)
			(island_removal_mode 0)
		)
		(polygon
			(pts
				(arc
					(start 63.373 -59.817)
					(mid 61.595 -59.817)
					(end 63.373 -59.817)
				)
			)
		)
	)
	(zone
		(layers "In4.Cu" "In5.Cu")
		(hatch none 0.5)
		(connect_pads
			(clearance 0)
		)
		(min_thickness 0.25)
		(keepout
			(tracks not_allowed)
			(vias allowed)
			(pads allowed)
			(copperpour not_allowed)
			(footprints allowed)
		)
		(placement
			(enabled no)
			(sheetname "")
		)
		(fill yes
			(thermal_gap 0.5)
			(thermal_bridge_width 0.5)
			(island_removal_mode 0)
		)
		(polygon
			(pts
				(arc
					(start 232.280968 -91.71305)
					(mid 230.502968 -91.71305)
					(end 232.280968 -91.71305)
				)
			)
		)
	)
	(zone
		(layers "In4.Cu" "In5.Cu")
		(hatch none 0.5)
		(connect_pads
			(clearance 0)
		)
		(min_thickness 0.25)
		(keepout
			(tracks not_allowed)
			(vias allowed)
			(pads allowed)
			(copperpour not_allowed)
			(footprints allowed)
		)
		(placement
			(enabled no)
			(sheetname "")
		)
		(fill yes
			(thermal_gap 0.5)
			(thermal_bridge_width 0.5)
			(island_removal_mode 0)
		)
		(polygon
			(pts
				(arc
					(start 154.432 -51.562)
					(mid 152.654 -51.562)
					(end 154.432 -51.562)
				)
			)
		)
	)
	(zone
		(layers "In4.Cu" "In5.Cu")
		(hatch none 0.5)
		(connect_pads
			(clearance 0)
		)
		(min_thickness 0.25)
		(keepout
			(tracks not_allowed)
			(vias allowed)
			(pads allowed)
			(copperpour not_allowed)
			(footprints allowed)
		)
		(placement
			(enabled no)
			(sheetname "")
		)
		(fill yes
			(thermal_gap 0.5)
			(thermal_bridge_width 0.5)
			(island_removal_mode 0)
		)
		(polygon
			(pts
				(arc
					(start 235.839 -92.964)
					(mid 234.061 -92.964)
					(end 235.839 -92.964)
				)
			)
		)
	)
	(zone
		(layers "In4.Cu" "In5.Cu")
		(hatch none 0.5)
		(connect_pads
			(clearance 0)
		)
		(min_thickness 0.25)
		(keepout
			(tracks not_allowed)
			(vias allowed)
			(pads allowed)
			(copperpour not_allowed)
			(footprints allowed)
		)
		(placement
			(enabled no)
			(sheetname "")
		)
		(fill yes
			(thermal_gap 0.5)
			(thermal_bridge_width 0.5)
			(island_removal_mode 0)
		)
		(polygon
			(pts
				(arc
					(start 213.233 -66.167)
					(mid 211.455 -66.167)
					(end 213.233 -66.167)
				)
			)
		)
	)
	(zone
		(layers "In4.Cu" "In5.Cu")
		(hatch none 0.5)
		(connect_pads
			(clearance 0)
		)
		(min_thickness 0.25)
		(keepout
			(tracks not_allowed)
			(vias allowed)
			(pads allowed)
			(copperpour not_allowed)
			(footprints allowed)
		)
		(placement
			(enabled no)
			(sheetname "")
		)
		(fill yes
			(thermal_gap 0.5)
			(thermal_bridge_width 0.5)
			(island_removal_mode 0)
		)
		(polygon
			(pts
				(arc
					(start 58.937906 -126.492)
					(mid 57.159906 -126.492)
					(end 58.937906 -126.492)
				)
			)
		)
	)
	(zone
		(layers "In4.Cu" "In5.Cu")
		(hatch none 0.5)
		(connect_pads
			(clearance 0)
		)
		(min_thickness 0.25)
		(keepout
			(tracks not_allowed)
			(vias allowed)
			(pads allowed)
			(copperpour not_allowed)
			(footprints allowed)
		)
		(placement
			(enabled no)
			(sheetname "")
		)
		(fill yes
			(thermal_gap 0.5)
			(thermal_bridge_width 0.5)
			(island_removal_mode 0)
		)
		(polygon
			(pts
				(arc
					(start 181.986174 -59.944)
					(mid 180.208174 -59.944)
					(end 181.986174 -59.944)
				)
			)
		)
	)
	(zone
		(layers "In4.Cu" "In5.Cu")
		(hatch none 0.5)
		(connect_pads
			(clearance 0)
		)
		(min_thickness 0.25)
		(keepout
			(tracks not_allowed)
			(vias allowed)
			(pads allowed)
			(copperpour not_allowed)
			(footprints allowed)
		)
		(placement
			(enabled no)
			(sheetname "")
		)
		(fill yes
			(thermal_gap 0.5)
			(thermal_bridge_width 0.5)
			(island_removal_mode 0)
		)
		(polygon
			(pts
				(arc
					(start 87.014304 -34.26206)
					(mid 84.220304 -34.26206)
					(end 87.014304 -34.26206)
				)
			)
		)
	)
	(zone
		(layers "In4.Cu" "In5.Cu")
		(hatch none 0.5)
		(connect_pads
			(clearance 0)
		)
		(min_thickness 0.25)
		(keepout
			(tracks not_allowed)
			(vias allowed)
			(pads allowed)
			(copperpour not_allowed)
			(footprints allowed)
		)
		(placement
			(enabled no)
			(sheetname "")
		)
		(fill yes
			(thermal_gap 0.5)
			(thermal_bridge_width 0.5)
			(island_removal_mode 0)
		)
		(polygon
			(pts
				(arc
					(start 232.664 -92.964)
					(mid 230.886 -92.964)
					(end 232.664 -92.964)
				)
			)
		)
	)
	(zone
		(layers "In4.Cu" "In5.Cu" "In6.Cu" "In8.Cu")
		(hatch none 0.5)
		(connect_pads
			(clearance 0)
		)
		(min_thickness 0.25)
		(keepout
			(tracks not_allowed)
			(vias allowed)
			(pads allowed)
			(copperpour not_allowed)
			(footprints allowed)
		)
		(placement
			(enabled no)
			(sheetname "")
		)
		(fill yes
			(thermal_gap 0.5)
			(thermal_bridge_width 0.5)
			(island_removal_mode 0)
		)
		(polygon
			(pts
				(arc
					(start 286.872172 -49.636172)
					(mid 285.094172 -49.636172)
					(end 286.872172 -49.636172)
				)
			)
		)
	)
	(zone
		(layers "In4.Cu" "In5.Cu" "In6.Cu" "In8.Cu")
		(hatch none 0.5)
		(connect_pads
			(clearance 0)
		)
		(min_thickness 0.25)
		(keepout
			(tracks not_allowed)
			(vias allowed)
			(pads allowed)
			(copperpour not_allowed)
			(footprints allowed)
		)
		(placement
			(enabled no)
			(sheetname "")
		)
		(fill yes
			(thermal_gap 0.5)
			(thermal_bridge_width 0.5)
			(island_removal_mode 0)
		)
		(polygon
			(pts
				(arc
					(start 287.672272 -49.657)
					(mid 285.894272 -49.657)
					(end 287.672272 -49.657)
				)
			)
		)
	)
	(zone
		(layers "In4.Cu" "In5.Cu" "In6.Cu" "In8.Cu")
		(hatch none 0.5)
		(connect_pads
			(clearance 0)
		)
		(min_thickness 0.25)
		(keepout
			(tracks not_allowed)
			(vias allowed)
			(pads allowed)
			(copperpour not_allowed)
			(footprints allowed)
		)
		(placement
			(enabled no)
			(sheetname "")
		)
		(fill yes
			(thermal_gap 0.5)
			(thermal_bridge_width 0.5)
			(island_removal_mode 0)
		)
		(polygon
			(pts
				(arc
					(start 288.671 -50.292)
					(mid 286.893 -50.292)
					(end 288.671 -50.292)
				)
			)
		)
	)
	(zone
		(layer "In5.Cu")
		(hatch none 0.5)
		(connect_pads
			(clearance 0)
		)
		(min_thickness 0.25)
		(keepout
			(tracks not_allowed)
			(vias allowed)
			(pads allowed)
			(copperpour not_allowed)
			(footprints allowed)
		)
		(placement
			(enabled no)
			(sheetname "")
		)
		(fill
			(thermal_gap 0.5)
			(thermal_bridge_width 0.5)
			(island_removal_mode 0)
		)
		(polygon
			(pts
				(arc
					(start 94.145354 -67.869816)
					(mid 91.554554 -67.869816)
					(end 94.145354 -67.869816)
				)
			)
		)
	)
	(zone
		(layer "In5.Cu")
		(hatch none 0.5)
		(connect_pads
			(clearance 0)
		)
		(min_thickness 0.25)
		(keepout
			(tracks not_allowed)
			(vias allowed)
			(pads allowed)
			(copperpour not_allowed)
			(footprints allowed)
		)
		(placement
			(enabled no)
			(sheetname "")
		)
		(fill
			(thermal_gap 0.5)
			(thermal_bridge_width 0.5)
			(island_removal_mode 0)
		)
		(polygon
			(pts
				(arc
					(start 220.091 -92.456)
					(mid 218.313 -92.456)
					(end 220.091 -92.456)
				)
			)
		)
	)
	(zone
		(layer "In5.Cu")
		(hatch none 0.5)
		(connect_pads
			(clearance 0)
		)
		(min_thickness 0.25)
		(keepout
			(tracks not_allowed)
			(vias allowed)
			(pads allowed)
			(copperpour not_allowed)
			(footprints allowed)
		)
		(placement
			(enabled no)
			(sheetname "")
		)
		(fill
			(thermal_gap 0.5)
			(thermal_bridge_width 0.5)
			(island_removal_mode 0)
		)
		(polygon
			(pts
				(arc
					(start 138.14552 -67.869816)
					(mid 135.55472 -67.869816)
					(end 138.14552 -67.869816)
				)
			)
		)
	)
	(zone
		(layer "In5.Cu")
		(hatch none 0.5)
		(connect_pads
			(clearance 0)
		)
		(min_thickness 0.25)
		(keepout
			(tracks not_allowed)
			(vias allowed)
			(pads allowed)
			(copperpour not_allowed)
			(footprints allowed)
		)
		(placement
			(enabled no)
			(sheetname "")
		)
		(fill
			(thermal_gap 0.5)
			(thermal_bridge_width 0.5)
			(island_removal_mode 0)
		)
		(polygon
			(pts
				(arc
					(start 132.145532 -67.869816)
					(mid 129.554732 -67.869816)
					(end 132.145532 -67.869816)
				)
			)
		)
	)
	(zone
		(layer "In5.Cu")
		(hatch none 0.5)
		(connect_pads
			(clearance 0)
		)
		(min_thickness 0.25)
		(keepout
			(tracks not_allowed)
			(vias allowed)
			(pads allowed)
			(copperpour not_allowed)
			(footprints allowed)
		)
		(placement
			(enabled no)
			(sheetname "")
		)
		(fill
			(thermal_gap 0.5)
			(thermal_bridge_width 0.5)
			(island_removal_mode 0)
		)
		(polygon
			(pts
				(arc
					(start 273.558 -48.641)
					(mid 271.78 -48.641)
					(end 273.558 -48.641)
				)
			)
		)
	)
	(zone
		(layer "In5.Cu")
		(hatch none 0.5)
		(connect_pads
			(clearance 0)
		)
		(min_thickness 0.25)
		(keepout
			(tracks not_allowed)
			(vias allowed)
			(pads allowed)
			(copperpour not_allowed)
			(footprints allowed)
		)
		(placement
			(enabled no)
			(sheetname "")
		)
		(fill
			(thermal_gap 0.5)
			(thermal_bridge_width 0.5)
			(island_removal_mode 0)
		)
		(polygon
			(pts
				(arc
					(start 218.059 -92.583)
					(mid 216.281 -92.583)
					(end 218.059 -92.583)
				)
			)
		)
	)
	(zone
		(layer "In5.Cu")
		(hatch none 0.5)
		(connect_pads
			(clearance 0)
		)
		(min_thickness 0.25)
		(keepout
			(tracks not_allowed)
			(vias allowed)
			(pads allowed)
			(copperpour not_allowed)
			(footprints allowed)
		)
		(placement
			(enabled no)
			(sheetname "")
		)
		(fill
			(thermal_gap 0.5)
			(thermal_bridge_width 0.5)
			(island_removal_mode 0)
		)
		(polygon
			(pts
				(arc
					(start 134.145528 -67.869816)
					(mid 131.554728 -67.869816)
					(end 134.145528 -67.869816)
				)
			)
		)
	)
	(zone
		(layer "In5.Cu")
		(hatch none 0.5)
		(connect_pads
			(clearance 0)
		)
		(min_thickness 0.25)
		(keepout
			(tracks not_allowed)
			(vias allowed)
			(pads allowed)
			(copperpour not_allowed)
			(footprints allowed)
		)
		(placement
			(enabled no)
			(sheetname "")
		)
		(fill
			(thermal_gap 0.5)
			(thermal_bridge_width 0.5)
			(island_removal_mode 0)
		)
		(polygon
			(pts
				(arc
					(start 92.145358 -67.869816)
					(mid 89.554558 -67.869816)
					(end 92.145358 -67.869816)
				)
			)
		)
	)
	(zone
		(layer "In5.Cu")
		(hatch none 0.5)
		(connect_pads
			(clearance 0)
		)
		(min_thickness 0.25)
		(keepout
			(tracks not_allowed)
			(vias allowed)
			(pads allowed)
			(copperpour not_allowed)
			(footprints allowed)
		)
		(placement
			(enabled no)
			(sheetname "")
		)
		(fill
			(thermal_gap 0.5)
			(thermal_bridge_width 0.5)
			(island_removal_mode 0)
		)
		(polygon
			(pts
				(arc
					(start 102.145338 -67.869816)
					(mid 99.554538 -67.869816)
					(end 102.145338 -67.869816)
				)
			)
		)
	)
	(zone
		(layer "In5.Cu")
		(hatch none 0.5)
		(connect_pads
			(clearance 0)
		)
		(min_thickness 0.25)
		(keepout
			(tracks not_allowed)
			(vias allowed)
			(pads allowed)
			(copperpour not_allowed)
			(footprints allowed)
		)
		(placement
			(enabled no)
			(sheetname "")
		)
		(fill
			(thermal_gap 0.5)
			(thermal_bridge_width 0.5)
			(island_removal_mode 0)
		)
		(polygon
			(pts
				(arc
					(start 178.145694 -67.869816)
					(mid 175.554894 -67.869816)
					(end 178.145694 -67.869816)
				)
			)
		)
	)
	(zone
		(layer "In5.Cu")
		(hatch none 0.5)
		(connect_pads
			(clearance 0)
		)
		(min_thickness 0.25)
		(keepout
			(tracks not_allowed)
			(vias allowed)
			(pads allowed)
			(copperpour not_allowed)
			(footprints allowed)
		)
		(placement
			(enabled no)
			(sheetname "")
		)
		(fill
			(thermal_gap 0.5)
			(thermal_bridge_width 0.5)
			(island_removal_mode 0)
		)
		(polygon
			(pts
				(arc
					(start 136.145524 -67.869816)
					(mid 133.554724 -67.869816)
					(end 136.145524 -67.869816)
				)
			)
		)
	)
	(zone
		(layer "In5.Cu")
		(hatch none 0.5)
		(connect_pads
			(clearance 0)
		)
		(min_thickness 0.25)
		(keepout
			(tracks not_allowed)
			(vias allowed)
			(pads allowed)
			(copperpour not_allowed)
			(footprints allowed)
		)
		(placement
			(enabled no)
			(sheetname "")
		)
		(fill
			(thermal_gap 0.5)
			(thermal_bridge_width 0.5)
			(island_removal_mode 0)
		)
		(polygon
			(pts
				(arc
					(start 96.14535 -67.869816)
					(mid 93.55455 -67.869816)
					(end 96.14535 -67.869816)
				)
			)
		)
	)
	(zone
		(layer "In5.Cu")
		(hatch none 0.5)
		(connect_pads
			(clearance 0)
		)
		(min_thickness 0.25)
		(keepout
			(tracks not_allowed)
			(vias allowed)
			(pads allowed)
			(copperpour not_allowed)
			(footprints allowed)
		)
		(placement
			(enabled no)
			(sheetname "")
		)
		(fill
			(thermal_gap 0.5)
			(thermal_bridge_width 0.5)
			(island_removal_mode 0)
		)
		(polygon
			(pts
				(arc
					(start 176.145698 -67.869816)
					(mid 173.554898 -67.869816)
					(end 176.145698 -67.869816)
				)
			)
		)
	)
	(zone
		(layer "In5.Cu")
		(hatch none 0.5)
		(connect_pads
			(clearance 0)
		)
		(min_thickness 0.25)
		(keepout
			(tracks not_allowed)
			(vias allowed)
			(pads allowed)
			(copperpour not_allowed)
			(footprints allowed)
		)
		(placement
			(enabled no)
			(sheetname "")
		)
		(fill
			(thermal_gap 0.5)
			(thermal_bridge_width 0.5)
			(island_removal_mode 0)
		)
		(polygon
			(pts
				(arc
					(start 172.145706 -67.869816)
					(mid 169.554906 -67.869816)
					(end 172.145706 -67.869816)
				)
			)
		)
	)
	(zone
		(layer "In5.Cu")
		(hatch none 0.5)
		(connect_pads
			(clearance 0)
		)
		(min_thickness 0.25)
		(keepout
			(tracks not_allowed)
			(vias allowed)
			(pads allowed)
			(copperpour not_allowed)
			(footprints allowed)
		)
		(placement
			(enabled no)
			(sheetname "")
		)
		(fill
			(thermal_gap 0.5)
			(thermal_bridge_width 0.5)
			(island_removal_mode 0)
		)
		(polygon
			(pts
				(arc
					(start 182.145686 -67.869816)
					(mid 179.554886 -67.869816)
					(end 182.145686 -67.869816)
				)
			)
		)
	)
	(zone
		(layer "In5.Cu")
		(hatch none 0.5)
		(connect_pads
			(clearance 0)
		)
		(min_thickness 0.25)
		(keepout
			(tracks not_allowed)
			(vias allowed)
			(pads allowed)
			(copperpour not_allowed)
			(footprints allowed)
		)
		(placement
			(enabled no)
			(sheetname "")
		)
		(fill
			(thermal_gap 0.5)
			(thermal_bridge_width 0.5)
			(island_removal_mode 0)
		)
		(polygon
			(pts
				(arc
					(start 272.85061 -45.36059)
					(mid 271.07261 -45.36059)
					(end 272.85061 -45.36059)
				)
			)
		)
	)
	(zone
		(layer "In5.Cu")
		(hatch none 0.5)
		(connect_pads
			(clearance 0)
		)
		(min_thickness 0.25)
		(keepout
			(tracks not_allowed)
			(vias allowed)
			(pads allowed)
			(copperpour not_allowed)
			(footprints allowed)
		)
		(placement
			(enabled no)
			(sheetname "")
		)
		(fill
			(thermal_gap 0.5)
			(thermal_bridge_width 0.5)
			(island_removal_mode 0)
		)
		(polygon
			(pts
				(arc
					(start 206.248 -69.32295)
					(mid 204.47 -69.32295)
					(end 206.248 -69.32295)
				)
			)
		)
	)
	(zone
		(layer "In5.Cu")
		(hatch none 0.5)
		(connect_pads
			(clearance 0)
		)
		(min_thickness 0.25)
		(keepout
			(tracks not_allowed)
			(vias allowed)
			(pads allowed)
			(copperpour not_allowed)
			(footprints allowed)
		)
		(placement
			(enabled no)
			(sheetname "")
		)
		(fill
			(thermal_gap 0.5)
			(thermal_bridge_width 0.5)
			(island_removal_mode 0)
		)
		(polygon
			(pts
				(arc
					(start 140.145516 -67.869816)
					(mid 137.554716 -67.869816)
					(end 140.145516 -67.869816)
				)
			)
		)
	)
	(zone
		(layer "In5.Cu")
		(hatch none 0.5)
		(connect_pads
			(clearance 0)
		)
		(min_thickness 0.25)
		(keepout
			(tracks not_allowed)
			(vias allowed)
			(pads allowed)
			(copperpour not_allowed)
			(footprints allowed)
		)
		(placement
			(enabled no)
			(sheetname "")
		)
		(fill
			(thermal_gap 0.5)
			(thermal_bridge_width 0.5)
			(island_removal_mode 0)
		)
		(polygon
			(pts
				(arc
					(start 142.145512 -67.869816)
					(mid 139.554712 -67.869816)
					(end 142.145512 -67.869816)
				)
			)
		)
	)
	(zone
		(layer "In5.Cu")
		(hatch none 0.5)
		(connect_pads
			(clearance 0)
		)
		(min_thickness 0.25)
		(keepout
			(tracks not_allowed)
			(vias allowed)
			(pads allowed)
			(copperpour not_allowed)
			(footprints allowed)
		)
		(placement
			(enabled no)
			(sheetname "")
		)
		(fill
			(thermal_gap 0.5)
			(thermal_bridge_width 0.5)
			(island_removal_mode 0)
		)
		(polygon
			(pts
				(arc
					(start 219.202 -92.456)
					(mid 217.424 -92.456)
					(end 219.202 -92.456)
				)
			)
		)
	)
	(zone
		(layer "In5.Cu")
		(hatch none 0.5)
		(connect_pads
			(clearance 0)
		)
		(min_thickness 0.25)
		(keepout
			(tracks not_allowed)
			(vias allowed)
			(pads allowed)
			(copperpour not_allowed)
			(footprints allowed)
		)
		(placement
			(enabled no)
			(sheetname "")
		)
		(fill
			(thermal_gap 0.5)
			(thermal_bridge_width 0.5)
			(island_removal_mode 0)
		)
		(polygon
			(pts
				(arc
					(start 174.145702 -67.869816)
					(mid 171.554902 -67.869816)
					(end 174.145702 -67.869816)
				)
			)
		)
	)
	(zone
		(layer "In5.Cu")
		(hatch none 0.5)
		(connect_pads
			(clearance 0)
		)
		(min_thickness 0.25)
		(keepout
			(tracks not_allowed)
			(vias allowed)
			(pads allowed)
			(copperpour not_allowed)
			(footprints allowed)
		)
		(placement
			(enabled no)
			(sheetname "")
		)
		(fill
			(thermal_gap 0.5)
			(thermal_bridge_width 0.5)
			(island_removal_mode 0)
		)
		(polygon
			(pts
				(arc
					(start 100.145342 -67.869816)
					(mid 97.554542 -67.869816)
					(end 100.145342 -67.869816)
				)
			)
		)
	)
	(zone
		(layer "In5.Cu")
		(hatch none 0.5)
		(connect_pads
			(clearance 0)
		)
		(min_thickness 0.25)
		(keepout
			(tracks not_allowed)
			(vias allowed)
			(pads allowed)
			(copperpour not_allowed)
			(footprints allowed)
		)
		(placement
			(enabled no)
			(sheetname "")
		)
		(fill
			(thermal_gap 0.5)
			(thermal_bridge_width 0.5)
			(island_removal_mode 0)
		)
		(polygon
			(pts
				(arc
					(start 98.145346 -67.869816)
					(mid 95.554546 -67.869816)
					(end 98.145346 -67.869816)
				)
			)
		)
	)
	(zone
		(layer "In5.Cu")
		(hatch none 0.5)
		(connect_pads
			(clearance 0)
		)
		(min_thickness 0.25)
		(keepout
			(tracks not_allowed)
			(vias allowed)
			(pads allowed)
			(copperpour not_allowed)
			(footprints allowed)
		)
		(placement
			(enabled no)
			(sheetname "")
		)
		(fill
			(thermal_gap 0.5)
			(thermal_bridge_width 0.5)
			(island_removal_mode 0)
		)
		(polygon
			(pts
				(arc
					(start 180.14569 -67.869816)
					(mid 177.55489 -67.869816)
					(end 180.14569 -67.869816)
				)
			)
		)
	)
	(zone
		(layer "In7.Cu")
		(hatch none 0.5)
		(connect_pads
			(clearance 0)
		)
		(min_thickness 0.25)
		(keepout
			(tracks not_allowed)
			(vias allowed)
			(pads allowed)
			(copperpour not_allowed)
			(footprints allowed)
		)
		(placement
			(enabled no)
			(sheetname "")
		)
		(fill
			(thermal_gap 0.5)
			(thermal_bridge_width 0.5)
			(island_removal_mode 0)
		)
		(polygon
			(pts
				(arc
					(start 7.999984 -6.364986)
					(mid 2.364994 -11.999976)
					(end 7.999984 -17.634966)
				)
				(arc
					(start 29.99994 -17.634966)
					(mid 35.63493 -11.999976)
					(end 29.99994 -6.364986)
				)
			)
		)
	)
)
